G04 ================== begin FILE IDENTIFICATION RECORD ==================*
G04 Layout Name:  D:/<user>/Wistron_project/16315-1/gbr/16315-1.brd*
G04 Film Name:    TSILK*
G04 File Format:  Gerber RS274X*
G04 File Origin:  Cadence Allegro 16.5-S056*
G04 Origin Date:  Fri Jun 09 15:30:40 2017*
G04 *
G04 Layer:  VIA CLASS/FILMMASKTOP*
G04 Layer:  REF DES/ASSEMBLY_TOP*
G04 Layer:  PACKAGE GEOMETRY/SILKSCREEN_TOP*
G04 Layer:  DRAWING FORMAT/LAYER_PCB_STORY*
G04 Layer:  DRAWING FORMAT/LAYER_SILK_T*
G04 Layer:  BOARD GEOMETRY/SILKSCREEN_TOP*
G04 *
G04 Offset:    (0.00 0.00)*
G04 Mirror:    No*
G04 Mode:      Positive*
G04 Rotation:  0*
G04 FullContactRelief:  No*
G04 UndefLineWidth:     6.00*
G04 ================== end FILE IDENTIFICATION RECORD ====================*
%FSLAX35Y35*MOIN*%
%IR0*IPPOS*OFA0.00000B0.00000*MIA0B0*SFA1.00000B1.00000*%
%ADD10C,.026*%
%ADD11C,.01*%
%ADD12C,.02*%
%ADD13C,.03*%
%ADD14C,.013*%
%ADD15C,.015*%
%ADD16C,.016*%
%ADD17C,.025*%
%ADD18C,.018*%
%ADD19C,.027*%
%ADD20C,.019*%
%ADD21C,.002*%
%ADD22C,.006*%
%ADD23C,.008*%
G75*
%LPD*%
G75*
G36*
G01X49737Y241261D02*
Y230061D01*
X67137D01*
Y241261D01*
X49737D01*
G37*
G36*
G01Y694017D02*
Y682817D01*
X67137D01*
Y694017D01*
X49737D01*
G37*
G36*
G01Y1146773D02*
Y1135573D01*
X67137D01*
Y1146773D01*
X49737D01*
G37*
G36*
G01X90137Y212061D02*
Y223261D01*
X72737D01*
Y212061D01*
X90137D01*
G37*
G36*
G01Y664817D02*
Y676017D01*
X72737D01*
Y664817D01*
X90137D01*
G37*
G36*
G01Y1117573D02*
Y1128773D01*
X72737D01*
Y1117573D01*
X90137D01*
G37*
G36*
G01X123742Y165516D02*
X126242Y163016D01*
Y168016D01*
X123742Y165516D01*
G37*
G36*
G01Y618272D02*
X126242Y615772D01*
Y620772D01*
X123742Y618272D01*
G37*
G36*
G01Y1071028D02*
X126242Y1068528D01*
Y1073528D01*
X123742Y1071028D01*
G37*
G36*
G01X214349Y212061D02*
Y223261D01*
X196949D01*
Y212061D01*
X214349D01*
G37*
G36*
G01X173949Y241261D02*
Y230061D01*
X191349D01*
Y241261D01*
X173949D01*
G37*
G36*
G01Y694017D02*
Y682817D01*
X191349D01*
Y694017D01*
X173949D01*
G37*
G36*
G01X214349Y664817D02*
Y676017D01*
X196949D01*
Y664817D01*
X214349D01*
G37*
G36*
G01Y1117573D02*
Y1128773D01*
X196949D01*
Y1117573D01*
X214349D01*
G37*
G36*
G01X173949Y1146773D02*
Y1135573D01*
X191349D01*
Y1146773D01*
X173949D01*
G37*
G36*
G01X247954Y165516D02*
X250454Y163016D01*
Y168016D01*
X247954Y165516D01*
G37*
G36*
G01X244220Y395240D02*
Y397040D01*
X249620D01*
Y395240D01*
X244220D01*
G37*
G36*
G01X255920D02*
Y397040D01*
X261320D01*
Y395240D01*
X255920D01*
G37*
G36*
G01Y403340D02*
Y405140D01*
X263120D01*
Y403340D01*
X255920D01*
G37*
G36*
G01X254120Y387140D02*
Y405140D01*
X255920D01*
Y387140D01*
X254120D01*
G37*
G36*
G01X249620D02*
Y405140D01*
X251420D01*
Y387140D01*
X249620D01*
G37*
G36*
G01X242420D02*
Y405140D01*
X244220D01*
Y387140D01*
X242420D01*
G37*
G36*
G01X247954Y618272D02*
X250454Y615772D01*
Y620772D01*
X247954Y618272D01*
G37*
G36*
G01Y1071028D02*
X250454Y1068528D01*
Y1073528D01*
X247954Y1071028D01*
G37*
G36*
G01X298162Y241261D02*
Y230061D01*
X315562D01*
Y241261D01*
X298162D01*
G37*
G36*
G01Y694017D02*
Y682817D01*
X315562D01*
Y694017D01*
X298162D01*
G37*
G36*
G01Y1146773D02*
Y1135573D01*
X315562D01*
Y1146773D01*
X298162D01*
G37*
G36*
G01X323541Y105915D02*
X354301D01*
Y91315D01*
X323541D01*
Y105915D01*
G37*
G36*
G01X338562Y212061D02*
Y223261D01*
X321162D01*
Y212061D01*
X338562D01*
G37*
G36*
G01X373835Y512445D02*
G02I-11811J0D01*
G37*
G36*
G01X357327Y559714D02*
X357388Y559227D01*
X357448Y559167D01*
X357509Y558437D01*
X357570Y558376D01*
X357631Y557585D01*
X357692Y557524D01*
X357753Y556794D01*
X357813Y556734D01*
X357874Y556004D01*
X357935Y555943D01*
X357996Y555213D01*
X358057Y555152D01*
X358117Y554422D01*
X358178Y554362D01*
X358239Y553571D01*
X358300Y553510D01*
X358361Y552780D01*
X358422Y552720D01*
X358482Y551990D01*
X358543Y551929D01*
X358604Y551199D01*
X358665Y551138D01*
X358726Y550409D01*
X358787Y550348D01*
X358847Y549618D01*
X358908Y549557D01*
X358969Y548767D01*
X359030Y548706D01*
X359091Y547976D01*
X359152Y547915D01*
X359212Y547489D01*
X363652D01*
X363835Y547732D01*
X363956Y548037D01*
X364139Y548280D01*
X364260Y548584D01*
X364443Y548827D01*
X364504Y549009D01*
X364686Y549253D01*
X364807Y549557D01*
X364990Y549800D01*
X365112Y550104D01*
X365294Y550348D01*
X365416Y550652D01*
X365598Y550895D01*
X365659Y551078D01*
X365841Y551321D01*
X365963Y551625D01*
X366146Y551868D01*
X366267Y552172D01*
X366450Y552415D01*
X366571Y552720D01*
X366754Y552963D01*
X366876Y553267D01*
X367058Y553510D01*
X367119Y553693D01*
X367301Y553936D01*
X367423Y554240D01*
X367605Y554483D01*
X367727Y554787D01*
X367909Y555031D01*
Y555092D01*
X368031Y555213D01*
X368092Y555152D01*
X368153Y554057D01*
X368213Y553997D01*
X368274Y552902D01*
X368335Y552841D01*
X368396Y551746D01*
X368457Y551686D01*
X368518Y550530D01*
X368578Y550469D01*
X368639Y549374D01*
X368700Y549314D01*
X368761Y548219D01*
X368822Y548158D01*
X368882Y547489D01*
X373322D01*
X373444Y547793D01*
X373626Y548037D01*
X373687Y548219D01*
X373870Y548462D01*
X373930Y548645D01*
X374113Y548888D01*
X374174Y549070D01*
X374356Y549314D01*
X374478Y549618D01*
X374660Y549861D01*
X374721Y550044D01*
X374904Y550287D01*
X374965Y550469D01*
X375147Y550713D01*
X375207Y550895D01*
X375390Y551138D01*
X375451Y551321D01*
X375633Y551564D01*
X375694Y551746D01*
X375877Y551990D01*
X375937Y552172D01*
X376120Y552415D01*
X376181Y552598D01*
X376363Y552841D01*
X376424Y553024D01*
X376607Y553267D01*
X376728Y553571D01*
X376911Y553814D01*
X376971Y553997D01*
X377154Y554240D01*
X377215Y554422D01*
X377397Y554666D01*
X377458Y554848D01*
X377641Y555092D01*
X377701Y555274D01*
X377884Y555517D01*
X377944Y555700D01*
X378127Y555943D01*
X378188Y556126D01*
X378370Y556369D01*
X378431Y556551D01*
X378613Y556794D01*
X378674Y556977D01*
X378857Y557220D01*
X378978Y557524D01*
X379161Y557768D01*
X379222Y557950D01*
X379404Y558193D01*
X379465Y558376D01*
X379648Y558619D01*
X379708Y558802D01*
X379891Y559045D01*
X379952Y559227D01*
X380134Y559470D01*
X380195Y559653D01*
X380377Y559896D01*
X380438Y560079D01*
X380620Y560322D01*
Y560383D01*
X380681Y560444D01*
X375572D01*
X375512Y560200D01*
X375269Y559775D01*
X375207Y559531D01*
X375025Y559227D01*
X374965Y558984D01*
X374843Y558802D01*
X374782Y558558D01*
X374600Y558254D01*
X374539Y558011D01*
X374356Y557707D01*
X374295Y557463D01*
X374174Y557281D01*
X374113Y557038D01*
X373930Y556734D01*
X373870Y556491D01*
X373687Y556186D01*
X373626Y555943D01*
X373505Y555761D01*
X373444Y555517D01*
X373261Y555213D01*
X373201Y554970D01*
X373018Y554666D01*
X372957Y554422D01*
X372836Y554240D01*
X372775Y553997D01*
X372593Y553693D01*
X372531Y553450D01*
X372349Y553145D01*
X372288Y552902D01*
X372167Y552720D01*
X372106Y552476D01*
X371984Y552355D01*
X371924Y552415D01*
X371863Y553632D01*
X371802Y553693D01*
X371741Y554970D01*
X371680Y555031D01*
X371619Y556308D01*
X371559Y556369D01*
X371498Y557707D01*
X371437Y557768D01*
X371376Y559045D01*
X371315Y559106D01*
X371254Y560383D01*
X371194Y560444D01*
X366693D01*
X366511Y560018D01*
X366328Y559775D01*
X366146Y559349D01*
X365963Y559106D01*
X365781Y558680D01*
X365598Y558437D01*
X365416Y558011D01*
X365233Y557768D01*
X365112Y557463D01*
X364929Y557220D01*
X364747Y556794D01*
X364564Y556551D01*
X364382Y556126D01*
X364199Y555882D01*
X364078Y555578D01*
X363895Y555335D01*
X363713Y554909D01*
X363530Y554666D01*
X363348Y554240D01*
X363165Y553997D01*
X362983Y553571D01*
X362800Y553328D01*
X362679Y553024D01*
X362496Y552780D01*
X362314Y552355D01*
X362193Y552233D01*
X362131Y552294D01*
X362071Y554240D01*
X362010Y554301D01*
X361949Y556308D01*
X361888Y556369D01*
X361828Y558376D01*
X361767Y558437D01*
X361706Y560444D01*
X357205D01*
X357327Y559714D01*
G37*
G36*
G01X325886Y562473D02*
Y564273D01*
X330386D01*
Y562473D01*
X325886D01*
G37*
G36*
G01X316886Y557973D02*
Y559773D01*
X320486D01*
Y557973D01*
X316886D01*
G37*
G36*
G01X325886D02*
Y559773D01*
X328586D01*
Y557973D01*
X325886D01*
G37*
G36*
G01X320486Y553473D02*
Y564273D01*
X322286D01*
Y553473D01*
X320486D01*
G37*
G36*
G01X324086D02*
Y564273D01*
X325886D01*
Y553473D01*
X324086D01*
G37*
G36*
G01X315086D02*
Y564273D01*
X316886D01*
Y553473D01*
X315086D01*
G37*
G36*
G01X338562Y664817D02*
Y676017D01*
X321162D01*
Y664817D01*
X338562D01*
G37*
G36*
G01Y1117573D02*
Y1128773D01*
X321162D01*
Y1117573D01*
X338562D01*
G37*
G36*
G01X372167Y165516D02*
X374667Y163016D01*
Y168016D01*
X372167Y165516D01*
G37*
G36*
G01X388041Y559896D02*
X388101Y559835D01*
X388162Y559045D01*
X388223Y558984D01*
X388284Y558254D01*
X388344Y558193D01*
X388406Y557463D01*
X388466Y557403D01*
X388527Y556673D01*
X388588Y556612D01*
X388649Y555882D01*
X388709Y555821D01*
X388770Y555092D01*
X388831Y555031D01*
X388892Y554240D01*
X388953Y554179D01*
X389014Y553450D01*
X389074Y553389D01*
X389135Y552659D01*
X389196Y552598D01*
X389257Y551868D01*
X389318Y551807D01*
X389378Y551078D01*
X389439Y551017D01*
X389500Y550287D01*
X389561Y550226D01*
X389622Y549435D01*
X389683Y549374D01*
X389743Y548645D01*
X389804Y548584D01*
X389865Y547854D01*
X389926Y547793D01*
Y547489D01*
X394426D01*
X394548Y547732D01*
X394731Y547976D01*
X394852Y548280D01*
X395035Y548523D01*
X395156Y548827D01*
X395339Y549070D01*
X395461Y549374D01*
X395643Y549618D01*
X395765Y549922D01*
X395947Y550165D01*
X396069Y550469D01*
X396251Y550713D01*
X396312Y550895D01*
X396494Y551138D01*
X396616Y551443D01*
X396798Y551686D01*
X396920Y551990D01*
X397103Y552233D01*
X397224Y552537D01*
X397407Y552780D01*
X397528Y553085D01*
X397711Y553328D01*
X397832Y553632D01*
X398015Y553875D01*
X398076Y554057D01*
X398258Y554301D01*
X398380Y554605D01*
X398562Y554848D01*
X398745Y555213D01*
X398806Y555152D01*
X398866Y554666D01*
X398927Y553936D01*
X398988Y553571D01*
X399049Y552720D01*
X399109Y552659D01*
X399170Y551564D01*
X399231Y551503D01*
X399292Y550409D01*
X399353Y550348D01*
X399414Y549192D01*
X399474Y549131D01*
X399535Y548037D01*
X399596Y547976D01*
Y547489D01*
X404036D01*
X404157Y547732D01*
X404340Y547976D01*
X404401Y548158D01*
X404583Y548402D01*
X404644Y548584D01*
X404827Y548827D01*
X404887Y549009D01*
X405070Y549253D01*
X405131Y549435D01*
X405313Y549679D01*
X405374Y549861D01*
X405556Y550104D01*
X405617Y550287D01*
X405800Y550530D01*
X405861Y550713D01*
X406043Y550956D01*
X406104Y551138D01*
X406286Y551381D01*
X406408Y551686D01*
X406591Y551929D01*
X406651Y552111D01*
X406833Y552355D01*
X406894Y552537D01*
X407077Y552780D01*
X407138Y552963D01*
X407320Y553206D01*
X407381Y553389D01*
X407563Y553632D01*
X407624Y553814D01*
X407807Y554057D01*
X407868Y554240D01*
X408050Y554483D01*
X408111Y554666D01*
X408293Y554909D01*
X408354Y555092D01*
X408537Y555335D01*
X408597Y555517D01*
X408780Y555761D01*
X408902Y556065D01*
X409084Y556308D01*
X409145Y556491D01*
X409327Y556734D01*
X409388Y556916D01*
X409570Y557159D01*
X409631Y557342D01*
X409814Y557585D01*
X409874Y557768D01*
X410057Y558011D01*
X410118Y558193D01*
X410300Y558437D01*
X410361Y558619D01*
X410544Y558862D01*
X410604Y559045D01*
X410787Y559288D01*
X410848Y559470D01*
X411030Y559714D01*
X411152Y560018D01*
X411334Y560261D01*
X411395Y560383D01*
Y560444D01*
X406347D01*
X406104Y559957D01*
X406043Y559714D01*
X405861Y559410D01*
X405800Y559167D01*
X405678Y558984D01*
X405617Y558741D01*
X405435Y558437D01*
X405374Y558193D01*
X405191Y557889D01*
X405131Y557646D01*
X405009Y557463D01*
X404948Y557220D01*
X404766Y556916D01*
X404705Y556673D01*
X404522Y556369D01*
X404462Y556126D01*
X404340Y555943D01*
X404279Y555700D01*
X404097Y555396D01*
X404036Y555152D01*
X403854Y554848D01*
X403793Y554605D01*
X403671Y554422D01*
X403610Y554179D01*
X403428Y553875D01*
X403367Y553632D01*
X403185Y553328D01*
X403124Y553085D01*
X403002Y552902D01*
X402941Y552659D01*
X402759Y552355D01*
X402698Y552415D01*
X402637Y553389D01*
X402576Y553754D01*
X402515Y554727D01*
X402455Y555092D01*
X402394Y556065D01*
X402333Y556430D01*
X402272Y557403D01*
X402211Y557768D01*
X402150Y558741D01*
X402090Y559106D01*
X402029Y560079D01*
X401968Y560444D01*
X397467D01*
Y560383D01*
X397285Y560139D01*
X397103Y559714D01*
X396920Y559470D01*
X396738Y559045D01*
X396555Y558802D01*
X396373Y558376D01*
X396190Y558133D01*
X396069Y557828D01*
X395886Y557585D01*
X395704Y557159D01*
X395521Y556916D01*
X395339Y556491D01*
X395156Y556247D01*
X394974Y555821D01*
X394791Y555578D01*
X394670Y555274D01*
X394487Y555031D01*
X394305Y554605D01*
X394122Y554362D01*
X393940Y553936D01*
X393757Y553693D01*
X393575Y553267D01*
X393393Y553024D01*
X393271Y552720D01*
X393089Y552476D01*
X392967Y552233D01*
X392906Y552294D01*
X392845Y553632D01*
X392784Y554362D01*
X392724Y555700D01*
X392663Y556430D01*
X392602Y557768D01*
X392541Y558619D01*
X392480Y559835D01*
X392420Y560444D01*
X387980D01*
X388041Y559896D01*
G37*
G36*
G01X381594Y560079D02*
X381533Y560018D01*
X381472Y559531D01*
X381411Y559470D01*
X381350Y558984D01*
X381290Y558923D01*
X381229Y558376D01*
X381168Y558315D01*
X381107Y557828D01*
X381046Y557768D01*
X380985Y557281D01*
X380925Y557220D01*
X380864Y556673D01*
X380803Y556612D01*
X380742Y556126D01*
X380681Y556065D01*
X380620Y555578D01*
X380560Y555517D01*
X380499Y554970D01*
X380438Y554909D01*
X380377Y554422D01*
X380317Y554362D01*
X380256Y553875D01*
X380195Y553814D01*
X380134Y553267D01*
X380073Y553206D01*
X380012Y552720D01*
X379952Y552659D01*
X379891Y552172D01*
X379830Y552111D01*
X379769Y551564D01*
X379708Y551503D01*
X379648Y551017D01*
X379587Y550956D01*
X379526Y550469D01*
X379465Y550409D01*
X379404Y549861D01*
X379343Y549800D01*
X379283Y549314D01*
X379222Y549253D01*
X379161Y548767D01*
X379100Y548706D01*
X379039Y548158D01*
X378978Y548097D01*
X378918Y547611D01*
X378857Y547550D01*
Y547489D01*
X384209D01*
X384270Y547854D01*
X384331Y547915D01*
X384391Y548402D01*
X384452Y548462D01*
X384513Y549009D01*
X384574Y549070D01*
X384635Y549557D01*
X384695Y549618D01*
X384756Y550104D01*
X384817Y550165D01*
X384878Y550713D01*
X384939Y550773D01*
X385000Y551260D01*
X385060Y551321D01*
X385121Y551807D01*
X385182Y551868D01*
X385243Y552415D01*
X385304Y552476D01*
X385365Y552963D01*
X385425Y553024D01*
X385486Y553510D01*
X385547Y553571D01*
X385608Y554119D01*
X385669Y554179D01*
X385730Y554666D01*
X385790Y554727D01*
X385851Y555213D01*
X385912Y555274D01*
X385973Y555761D01*
X386033Y555821D01*
X386094Y556369D01*
X386155Y556430D01*
X386216Y556916D01*
X386277Y556977D01*
X386337Y557463D01*
X386398Y557524D01*
X386459Y558072D01*
X386520Y558133D01*
X386581Y558619D01*
X386642Y558680D01*
X386702Y559167D01*
X386763Y559227D01*
X386824Y559775D01*
X386885Y559835D01*
X386946Y560322D01*
X387007Y560383D01*
Y560444D01*
X381654D01*
X381594Y560079D01*
G37*
G36*
G01X385121Y566891D02*
X384635Y566830D01*
X384452Y566708D01*
X384209Y566647D01*
X383966Y566526D01*
X383661Y566282D01*
X383601D01*
X382932Y565552D01*
Y565492D01*
X382749Y565248D01*
X382628Y565005D01*
X382567Y564701D01*
X382506Y564640D01*
X382445Y564032D01*
X382506Y563241D01*
X382567Y563180D01*
X382628Y562937D01*
X382810Y562694D01*
Y562633D01*
X383357Y562146D01*
X383418D01*
X383540Y562025D01*
X383783Y561964D01*
X383844Y561903D01*
X384331Y561843D01*
X384391Y561781D01*
X385365Y561843D01*
X385425Y561903D01*
X385730Y561964D01*
X385790Y562025D01*
X386033Y562086D01*
X386277Y562207D01*
X386642Y562511D01*
X386702D01*
X387372Y563241D01*
X387432Y563424D01*
X387615Y563667D01*
X387676Y563910D01*
X387737Y563971D01*
X387797Y564458D01*
X387858Y564519D01*
X387797Y565431D01*
X387737Y565492D01*
X387676Y565735D01*
X387554Y565978D01*
X387128Y566465D01*
X386885Y566647D01*
X386520Y566830D01*
X386094Y566891D01*
X386033Y566951D01*
X385182D01*
X385121Y566891D01*
G37*
G36*
G01X372167Y618272D02*
X374667Y615772D01*
Y620772D01*
X372167Y618272D01*
G37*
G36*
G01Y1071028D02*
X374667Y1068528D01*
Y1073528D01*
X372167Y1071028D01*
G37*
G36*
G01X462774Y212061D02*
Y223261D01*
X445374D01*
Y212061D01*
X462774D01*
G37*
G36*
G01X422374Y241261D02*
Y230061D01*
X439774D01*
Y241261D01*
X422374D01*
G37*
G36*
G01X452387Y560687D02*
X451657Y560626D01*
X451596Y560565D01*
X451171Y560504D01*
X451110Y560444D01*
X450806Y560383D01*
X450624Y560261D01*
X450380Y560200D01*
X449772Y559896D01*
X449468Y559653D01*
X449407D01*
X449042Y559349D01*
X448981D01*
X448069Y558437D01*
X448008Y558497D01*
X448069Y558923D01*
X448130Y558984D01*
X448191Y559470D01*
X448252Y559531D01*
X448312Y560018D01*
X448373Y560079D01*
X448434Y560383D01*
Y560444D01*
X443812D01*
X443751Y560383D01*
X443690Y559896D01*
X443629Y559835D01*
X443569Y559288D01*
X443507Y559227D01*
X443447Y558741D01*
X443386Y558680D01*
X443325Y558193D01*
X443264Y558133D01*
X443204Y557585D01*
X443143Y557524D01*
X443082Y557038D01*
X443021Y556977D01*
X442960Y556491D01*
X442899Y556430D01*
X442839Y555943D01*
X442778Y555882D01*
X442717Y555335D01*
X442656Y555274D01*
X442595Y554787D01*
X442535Y554727D01*
X442474Y554240D01*
X442413Y554179D01*
X442352Y553632D01*
X442291Y553571D01*
X442230Y553085D01*
X442170Y553024D01*
X442109Y552537D01*
X442048Y552476D01*
X441987Y551929D01*
X441926Y551868D01*
X441865Y551381D01*
X441805Y551321D01*
X441744Y550834D01*
X441683Y550773D01*
X441622Y550287D01*
X441561Y550226D01*
X441500Y549679D01*
X441440Y549618D01*
X441379Y549131D01*
X441318Y549070D01*
X441257Y548584D01*
X441196Y548523D01*
X441136Y547976D01*
X441075Y547915D01*
X441014Y547489D01*
X446001D01*
X446062Y547854D01*
X446123Y547915D01*
X446183Y548462D01*
X446244Y548523D01*
X446305Y549009D01*
X446366Y549070D01*
X446427Y549557D01*
X446488Y549618D01*
X446548Y550104D01*
X446609Y550165D01*
X446670Y550652D01*
X446731Y550713D01*
X446792Y551260D01*
X446853Y551321D01*
X446913Y551807D01*
X446974Y551868D01*
X447035Y552355D01*
X447096Y552415D01*
X447157Y552902D01*
X447218Y552963D01*
X447278Y553450D01*
X447339Y553510D01*
X447400Y553936D01*
X447461Y553997D01*
X447522Y554301D01*
X447583Y554362D01*
X447643Y554605D01*
X447704Y554666D01*
X447765Y554909D01*
X447826Y554970D01*
X447887Y555213D01*
X448069Y555456D01*
X448130Y555639D01*
X448373Y555943D01*
Y556004D01*
X448799Y556491D01*
X448860D01*
X449285Y556855D01*
X449650Y557038D01*
X450137Y557098D01*
X450198Y557159D01*
X450806Y557098D01*
X451049Y556916D01*
X451171D01*
Y556794D01*
X451293Y556673D01*
X451353Y556308D01*
X451414Y556247D01*
X451353Y555517D01*
X451293Y555456D01*
X451231Y554848D01*
X451171Y554787D01*
X451110Y554240D01*
X451049Y554179D01*
X450988Y553693D01*
X450928Y553632D01*
X450867Y553085D01*
X450806Y553024D01*
X450745Y552537D01*
X450684Y552476D01*
X450624Y551990D01*
X450563Y551929D01*
X450502Y551381D01*
X450441Y551321D01*
X450380Y550834D01*
X450319Y550773D01*
X450259Y550226D01*
X450198Y550165D01*
X450137Y549679D01*
X450076Y549618D01*
X450015Y549131D01*
X449954Y549070D01*
X449894Y548523D01*
X449833Y548462D01*
X449772Y547976D01*
X449711Y547915D01*
X449650Y547489D01*
X454637D01*
X454698Y547976D01*
X454759Y548037D01*
X454820Y548523D01*
X454881Y548584D01*
X454942Y549131D01*
X455002Y549192D01*
X455063Y549679D01*
X455124Y549739D01*
X455185Y550287D01*
X455246Y550348D01*
X455307Y550834D01*
X455367Y550895D01*
X455428Y551381D01*
X455489Y551443D01*
X455550Y551990D01*
X455611Y552050D01*
X455671Y552537D01*
X455732Y552598D01*
X455793Y553145D01*
X455854Y553206D01*
X455915Y553693D01*
X455976Y553754D01*
X456036Y554301D01*
X456097Y554362D01*
X456158Y554848D01*
X456219Y554909D01*
X456280Y555456D01*
X456341Y555517D01*
X456401Y556126D01*
X456462Y556186D01*
X456523Y556916D01*
X456584Y556977D01*
X456523Y558558D01*
X456462Y558619D01*
X456401Y558862D01*
X456341Y558923D01*
Y559045D01*
X456158Y559288D01*
Y559349D01*
X455732Y559835D01*
X455246Y560261D01*
X454759Y560504D01*
X454455Y560565D01*
X454394Y560626D01*
X453786Y560687D01*
X453725Y560748D01*
X452448D01*
X452387Y560687D01*
G37*
G36*
G01X436939D02*
X436209Y560626D01*
X436148Y560565D01*
X435783Y560504D01*
X435723Y560444D01*
X435419Y560383D01*
X435358Y560322D01*
X435115Y560261D01*
X435054Y560200D01*
X434811Y560139D01*
X434567Y560018D01*
X434324Y559835D01*
X434263D01*
X433959Y559592D01*
X433898D01*
X433412Y559167D01*
X433351D01*
X432682Y558497D01*
X432621Y558558D01*
X432682Y559045D01*
X432743Y559106D01*
X432804Y559592D01*
X432864Y559653D01*
X432925Y560139D01*
X432986Y560200D01*
Y560444D01*
X428364D01*
X428303Y560018D01*
X428242Y559957D01*
X428181Y559410D01*
X428120Y559349D01*
X428059Y558862D01*
X427999Y558802D01*
X427938Y558315D01*
X427877Y558254D01*
X427816Y557707D01*
X427756Y557646D01*
X427694Y557159D01*
X427634Y557098D01*
X427573Y556612D01*
X427512Y556551D01*
X427451Y556065D01*
X427391Y556004D01*
X427330Y555456D01*
X427269Y555396D01*
X427208Y554909D01*
X427147Y554848D01*
X427087Y554362D01*
X427026Y554301D01*
X426965Y553754D01*
X426904Y553693D01*
X426843Y553206D01*
X426782Y553145D01*
X426722Y552659D01*
X426661Y552598D01*
X426600Y552050D01*
X426539Y551990D01*
X426478Y551503D01*
X426417Y551443D01*
X426357Y550956D01*
X426296Y550895D01*
X426235Y550409D01*
X426174Y550348D01*
X426113Y549800D01*
X426052Y549739D01*
X425992Y549253D01*
X425931Y549192D01*
X425870Y548706D01*
X425809Y548645D01*
X425748Y548097D01*
X425687Y548037D01*
X425627Y547550D01*
X425566Y547489D01*
X430614D01*
X430675Y548037D01*
X430735Y548097D01*
X430796Y548584D01*
X430857Y548645D01*
X430918Y549131D01*
X430979Y549192D01*
X431040Y549679D01*
X431100Y549739D01*
X431161Y550226D01*
X431222Y550287D01*
X431283Y550834D01*
X431344Y550895D01*
X431405Y551381D01*
X431465Y551443D01*
X431526Y551929D01*
X431587Y551990D01*
X431648Y552476D01*
X431709Y552537D01*
X431770Y553024D01*
X431830Y553085D01*
X431891Y553571D01*
X431952Y553632D01*
X432013Y553997D01*
X432074Y554057D01*
X432134Y554362D01*
X432195Y554422D01*
X432256Y554727D01*
X432682Y555578D01*
X432925Y555882D01*
Y555943D01*
X433472Y556551D01*
X433776Y556794D01*
X434263Y557038D01*
X434750Y557098D01*
X434811Y557159D01*
X435419Y557098D01*
X435783Y556794D01*
X435905Y556612D01*
X435966Y556126D01*
X435905Y555335D01*
X435844Y555274D01*
X435783Y554727D01*
X435723Y554666D01*
X435662Y554119D01*
X435601Y554057D01*
X435540Y553510D01*
X435480Y553450D01*
X435419Y552963D01*
X435358Y552902D01*
X435297Y552355D01*
X435236Y552294D01*
X435175Y551807D01*
X435115Y551746D01*
X435054Y551260D01*
X434993Y551199D01*
X434932Y550652D01*
X434871Y550591D01*
X434811Y550104D01*
X434750Y550044D01*
X434689Y549496D01*
X434628Y549435D01*
X434567Y548949D01*
X434506Y548888D01*
X434446Y548402D01*
X434385Y548341D01*
X434324Y547793D01*
X434263Y547732D01*
Y547489D01*
X439189D01*
X439250Y547793D01*
X439311Y547854D01*
X439372Y548402D01*
X439433Y548462D01*
X439494Y548949D01*
X439554Y549009D01*
X439615Y549557D01*
X439676Y549618D01*
X439737Y550104D01*
X439798Y550165D01*
X439858Y550652D01*
X439919Y550713D01*
X439980Y551260D01*
X440041Y551321D01*
X440102Y551807D01*
X440163Y551868D01*
X440223Y552415D01*
X440284Y552476D01*
X440345Y552963D01*
X440406Y553024D01*
X440467Y553510D01*
X440528Y553571D01*
X440588Y554119D01*
X440649Y554179D01*
X440710Y554666D01*
X440771Y554727D01*
X440831Y555274D01*
X440893Y555335D01*
X440953Y555943D01*
X441014Y556004D01*
X441075Y556673D01*
X441136Y556734D01*
X441196Y557707D01*
X441136Y558437D01*
X441075Y558497D01*
X441014Y558802D01*
X440953Y558862D01*
X440893Y559106D01*
X440710Y559349D01*
Y559410D01*
X440284Y559896D01*
X439858Y560261D01*
X439494Y560444D01*
X439250Y560504D01*
X439189Y560565D01*
X438764Y560626D01*
X438703Y560687D01*
X437730Y560748D01*
X437000D01*
X436939Y560687D01*
G37*
G36*
G01X422221Y560200D02*
X422039Y559957D01*
X421978Y559775D01*
X421795Y559531D01*
X421734Y559349D01*
X421552Y559106D01*
X421491Y558923D01*
X421309Y558680D01*
X421187Y558376D01*
X421004Y558133D01*
X420944Y557950D01*
X420761Y557707D01*
X420700Y557524D01*
X420518Y557281D01*
X420457Y557098D01*
X420275Y556855D01*
X420153Y556551D01*
X419970Y556308D01*
X419910Y556126D01*
X419727Y555882D01*
X419667Y555700D01*
X419484Y555456D01*
X419423Y555274D01*
X419241Y555031D01*
X419180Y554848D01*
X418998Y554605D01*
X418876Y554301D01*
X418693Y554057D01*
X418633Y553875D01*
X418450Y553632D01*
X418389Y553450D01*
X418207Y553206D01*
Y553145D01*
X418085Y553024D01*
X418024Y553085D01*
X417963Y554057D01*
X417903Y554119D01*
X417842Y555274D01*
X417781Y555335D01*
X417720Y556551D01*
X417659Y556612D01*
X417599Y557768D01*
X417538Y557828D01*
X417477Y559045D01*
X417416Y559106D01*
X417356Y560261D01*
X417294Y560322D01*
Y560444D01*
X412429D01*
X412490Y560383D01*
X412551Y559775D01*
X412611Y559714D01*
X412672Y559106D01*
X412733Y559045D01*
X412794Y558497D01*
X412855Y558437D01*
X412916Y557828D01*
X412976Y557768D01*
X413037Y557159D01*
X413098Y557098D01*
X413159Y556551D01*
X413220Y556491D01*
X413280Y555882D01*
X413341Y555821D01*
X413402Y555213D01*
X413463Y555152D01*
X413524Y554605D01*
X413585Y554544D01*
X413645Y553936D01*
X413706Y553875D01*
X413767Y553267D01*
X413828Y553206D01*
X413889Y552659D01*
X413950Y552598D01*
X414010Y551990D01*
X414071Y551929D01*
X414132Y551321D01*
X414193Y551260D01*
X414254Y550713D01*
X414315Y550652D01*
X414375Y550044D01*
X414436Y549983D01*
X414497Y549374D01*
X414557Y549314D01*
X414619Y548767D01*
X414679Y548706D01*
X414740Y548097D01*
X414801Y548037D01*
X414862Y547428D01*
X414922Y547367D01*
X414801Y547124D01*
X414619Y546881D01*
X414497Y546577D01*
X414315Y546333D01*
X414254Y546151D01*
X414071Y545908D01*
X414010Y545726D01*
X413828Y545482D01*
X413767Y545300D01*
X413585Y545056D01*
X413463Y544752D01*
X413280Y544509D01*
X413220Y544326D01*
X413037Y544083D01*
X412976Y543901D01*
X412794Y543657D01*
X412733Y543475D01*
X412551Y543232D01*
X412429Y542928D01*
X412246Y542684D01*
X412186Y542502D01*
X412003Y542259D01*
X411943Y542076D01*
X411760Y541833D01*
X411699Y541650D01*
X411517Y541407D01*
X411395Y541103D01*
X411274Y540981D01*
X416382D01*
X416443Y541164D01*
X416626Y541407D01*
X416686Y541590D01*
X416869Y541833D01*
X416930Y542015D01*
X417112Y542259D01*
X417234Y542563D01*
X417416Y542806D01*
X417477Y542989D01*
X417659Y543232D01*
X417720Y543414D01*
X417903Y543657D01*
X417963Y543840D01*
X418146Y544083D01*
X418268Y544387D01*
X418450Y544631D01*
X418511Y544813D01*
X418693Y545056D01*
X418754Y545239D01*
X418937Y545482D01*
X418998Y545665D01*
X419180Y545908D01*
X419241Y546090D01*
X419423Y546333D01*
X419545Y546638D01*
X419727Y546881D01*
X419788Y547063D01*
X419970Y547307D01*
X420031Y547489D01*
X420214Y547732D01*
X420275Y547915D01*
X420457Y548158D01*
X420579Y548462D01*
X420761Y548706D01*
X420822Y548888D01*
X421004Y549131D01*
X421065Y549314D01*
X421248Y549557D01*
X421309Y549739D01*
X421491Y549983D01*
X421613Y550287D01*
X421795Y550530D01*
X421856Y550713D01*
X422039Y550956D01*
X422099Y551138D01*
X422282Y551381D01*
X422343Y551564D01*
X422525Y551807D01*
X422586Y551990D01*
X422768Y552233D01*
X422890Y552537D01*
X423072Y552780D01*
X423133Y552963D01*
X423316Y553206D01*
X423376Y553389D01*
X423559Y553632D01*
X423620Y553814D01*
X423802Y554057D01*
X423924Y554362D01*
X424106Y554605D01*
X424167Y554787D01*
X424350Y555031D01*
X424410Y555213D01*
X424593Y555456D01*
X424654Y555639D01*
X424836Y555882D01*
X424958Y556186D01*
X425140Y556430D01*
X425201Y556612D01*
X425383Y556855D01*
X425444Y557038D01*
X425627Y557281D01*
X425687Y557463D01*
X425870Y557707D01*
X425992Y558011D01*
X426174Y558254D01*
X426235Y558437D01*
X426417Y558680D01*
X426478Y558862D01*
X426661Y559106D01*
X426722Y559288D01*
X426904Y559531D01*
X426965Y559714D01*
X427147Y559957D01*
X427269Y560261D01*
X427391Y560383D01*
Y560504D01*
X422343D01*
X422221Y560200D01*
G37*
G36*
G01X459685Y562937D02*
X459807Y562694D01*
X459260D01*
X459199Y562755D01*
X459017Y563180D01*
X458834Y563424D01*
Y563545D01*
X458652Y563606D01*
X458226Y563667D01*
Y562694D01*
X457800D01*
Y564490D01*
X458226D01*
Y564032D01*
X458530D01*
X459138Y564093D01*
X459199Y564275D01*
X459138Y564640D01*
X458956D01*
X458895Y564701D01*
X458226D01*
Y564491D01*
X457800D01*
Y565066D01*
X458956D01*
X459320Y565005D01*
X459564Y564822D01*
X459625Y564580D01*
X459685Y564519D01*
X459625Y564154D01*
X459381Y563850D01*
X459138Y563789D01*
X459077Y563728D01*
X459199Y563606D01*
X459260D01*
X459320Y563545D01*
X459442Y563363D01*
X459503Y563180D01*
X459685Y562937D01*
G37*
G36*
G01X460172Y562207D02*
X459868Y561964D01*
X459625Y561903D01*
X459442Y561781D01*
X458408Y561721D01*
X458348Y561781D01*
X457983Y561843D01*
X457618Y562025D01*
X457374Y562207D01*
X456949Y562694D01*
X456706Y563180D01*
X456644Y564093D01*
X456645Y564099D01*
X457030D01*
X457009Y563910D01*
X457070Y563302D01*
X457192Y563059D01*
X457435Y562755D01*
Y562694D01*
X457861Y562329D01*
X458104Y562207D01*
X458530Y562146D01*
X458591Y562086D01*
X459320Y562146D01*
X459381Y562207D01*
X459625Y562268D01*
X459990Y562572D01*
X460415Y563059D01*
X460476Y563302D01*
X460537Y563363D01*
X460598Y563789D01*
X460537Y564397D01*
X460476Y564458D01*
X460415Y564701D01*
X460111Y565066D01*
Y565187D01*
X459990D01*
X459625Y565492D01*
X459503D01*
X459442Y565552D01*
X459077Y565613D01*
X459017Y565674D01*
X458287Y565613D01*
X458226Y565552D01*
X457983Y565492D01*
X457739Y565309D01*
X457678D01*
X457253Y564822D01*
X457070Y564458D01*
X457030Y564100D01*
X456645D01*
X456706Y564580D01*
X456949Y565066D01*
X457131Y565309D01*
X457618Y565735D01*
X457983Y565917D01*
X458348Y565978D01*
X458408Y566039D01*
X459199D01*
X459260Y565978D01*
X459625Y565917D01*
X459868Y565796D01*
X460172Y565552D01*
X460233D01*
X460659Y565066D01*
X460780Y564822D01*
X460841Y564580D01*
X460902Y564519D01*
X460963Y563424D01*
X460902Y563363D01*
X460841Y563059D01*
X460659Y562694D01*
X460233Y562207D01*
X460172D01*
G37*
G36*
G01X422374Y694017D02*
Y682817D01*
X439774D01*
Y694017D01*
X422374D01*
G37*
G36*
G01X462774Y664817D02*
Y676017D01*
X445374D01*
Y664817D01*
X462774D01*
G37*
G36*
G01X445900Y1145800D02*
Y1134600D01*
X463300D01*
Y1145800D01*
X445900D01*
G37*
G36*
G01X496379Y165516D02*
X498879Y163016D01*
Y168016D01*
X496379Y165516D01*
G37*
G36*
G01X469452Y502177D02*
Y497177D01*
X489452D01*
Y502177D01*
X469452D01*
G37*
G36*
G01X496379Y618272D02*
X498879Y615772D01*
Y620772D01*
X496379Y618272D01*
G37*
G36*
G01Y1071028D02*
X498879Y1068528D01*
Y1073528D01*
X496379Y1071028D01*
G37*
G36*
G01X546587Y241261D02*
Y230061D01*
X563987D01*
Y241261D01*
X546587D01*
G37*
G36*
G01Y694017D02*
Y682817D01*
X563987D01*
Y694017D01*
X546587D01*
G37*
G36*
G01X530674Y1117473D02*
Y1128673D01*
X513274D01*
Y1117473D01*
X530674D01*
G37*
G36*
G01X546587Y1146773D02*
Y1135573D01*
X563987D01*
Y1146773D01*
X546587D01*
G37*
G36*
G01X586987Y212061D02*
Y223261D01*
X569587D01*
Y212061D01*
X586987D01*
G37*
G36*
G01X579629Y556681D02*
X584629Y551681D01*
Y556681D01*
X579629D01*
G37*
G36*
G01X586987Y664817D02*
Y676017D01*
X569587D01*
Y664817D01*
X586987D01*
G37*
G36*
G01Y1117573D02*
Y1128773D01*
X569587D01*
Y1117573D01*
X586987D01*
G37*
G36*
G01X620592Y165516D02*
X623092Y163016D01*
Y168016D01*
X620592Y165516D01*
G37*
G36*
G01Y618272D02*
X623092Y615772D01*
Y620772D01*
X620592Y618272D01*
G37*
G36*
G01X642392Y604986D02*
Y601586D01*
X644092Y603286D01*
X642392Y604986D01*
G37*
G36*
G01X620592Y1071028D02*
X623092Y1068528D01*
Y1073528D01*
X620592Y1071028D01*
G37*
G36*
G01X711200Y212061D02*
Y223261D01*
X693800D01*
Y212061D01*
X711200D01*
G37*
G36*
G01X670800Y241261D02*
Y230061D01*
X688200D01*
Y241261D01*
X670800D01*
G37*
G36*
G01X693343Y593787D02*
X695343Y591787D01*
Y595787D01*
X693343Y593787D01*
G37*
G36*
G01X670800Y694017D02*
Y682817D01*
X688200D01*
Y694017D01*
X670800D01*
G37*
G36*
G01X711200Y664817D02*
Y676017D01*
X693800D01*
Y664817D01*
X711200D01*
G37*
G36*
G01Y1117573D02*
Y1128773D01*
X693800D01*
Y1117573D01*
X711200D01*
G37*
G36*
G01X670800Y1146773D02*
Y1135573D01*
X688200D01*
Y1146773D01*
X670800D01*
G37*
G36*
G01X744805Y165516D02*
X747305Y163016D01*
Y168016D01*
X744805Y165516D01*
G37*
G36*
G01Y618272D02*
X747305Y615772D01*
Y620772D01*
X744805Y618272D01*
G37*
G36*
G01Y1071028D02*
X747305Y1068528D01*
Y1073528D01*
X744805Y1071028D01*
G37*
G36*
G01X801162Y9459D02*
X878366D01*
Y25975D01*
X801162D01*
Y9459D01*
G37*
G36*
G01X802362Y34017D02*
X804862Y36517D01*
X799862D01*
X802362Y34017D01*
G37*
G36*
G01X818072Y1581294D02*
Y1658268D01*
X824272D01*
Y1591595D01*
X845772D01*
Y1583394D01*
X887772D01*
Y1591595D01*
X914311D01*
Y1658268D01*
X921672D01*
Y1581294D01*
X818072D01*
G37*
G36*
G01X841946Y1655394D02*
G02X839946I-1000J0D01*
G01Y1656394D01*
G02X841946I1000J0D01*
G01Y1655394D01*
G37*
G36*
G01X834859D02*
G02X832859I-1000J0D01*
G01Y1656394D01*
G02X834859I1000J0D01*
G01Y1655394D01*
G37*
G36*
G01X827772D02*
G02X825772I-1000J0D01*
G01Y1656394D01*
G02X827772I1000J0D01*
G01Y1655394D01*
G37*
G36*
G01X875223Y841403D02*
X884223D01*
Y833403D01*
X875223D01*
Y841403D01*
G37*
G36*
G01X875481Y1468461D02*
X906241D01*
Y1453861D01*
X875481D01*
Y1468461D01*
G37*
G36*
G01X891555Y1655394D02*
G02X889555I-1000J0D01*
G01Y1656394D01*
G02X891555I1000J0D01*
G01Y1655394D01*
G37*
G36*
G01X877381D02*
G02X875381I-1000J0D01*
G01Y1656394D01*
G02X877381I1000J0D01*
G01Y1655394D01*
G37*
G36*
G01X870294D02*
G02X868294I-1000J0D01*
G01Y1656394D01*
G02X870294I1000J0D01*
G01Y1655394D01*
G37*
G36*
G01X863207D02*
G02X861207I-1000J0D01*
G01Y1656394D01*
G02X863207I1000J0D01*
G01Y1655394D01*
G37*
G36*
G01X856120D02*
G02X854120I-1000J0D01*
G01Y1656394D01*
G02X856120I1000J0D01*
G01Y1655394D01*
G37*
G36*
G01X849033D02*
G02X847033I-1000J0D01*
G01Y1656394D01*
G02X849033I1000J0D01*
G01Y1655394D01*
G37*
G36*
G01X930331Y6565D02*
G02X928331I-1000J0D01*
G01Y8565D01*
G02X930331I1000J0D01*
G01Y6565D01*
G37*
G36*
G01X938205D02*
G02X936205I-1000J0D01*
G01Y8565D01*
G02X938205I1000J0D01*
G01Y6565D01*
G37*
G36*
G01X963426Y-235D02*
X925726D01*
Y352165D01*
X926431D01*
Y5065D01*
X957821D01*
Y150765D01*
X963026D01*
Y191565D01*
X957821D01*
Y352165D01*
X963426D01*
Y-235D01*
G37*
G36*
G01X930331Y385698D02*
G02X928331I-1000J0D01*
G01Y387698D01*
G02X930331I1000J0D01*
G01Y385698D01*
G37*
G36*
G01X938205D02*
G02X936205I-1000J0D01*
G01Y387698D01*
G02X938205I1000J0D01*
G01Y385698D01*
G37*
G36*
G01X963426Y378898D02*
X925726D01*
Y731298D01*
X926431D01*
Y384198D01*
X957821D01*
Y529898D01*
X963026D01*
Y570698D01*
X957821D01*
Y731298D01*
X963426D01*
Y378898D01*
G37*
G36*
G01X925880Y925700D02*
X895120D01*
Y940300D01*
X925880D01*
Y925700D01*
G37*
G36*
G01X928380Y995200D02*
X897620D01*
Y1009800D01*
X928380D01*
Y995200D01*
G37*
G36*
G01X913776Y1375483D02*
X899776D01*
Y1356483D01*
X913776D01*
Y1375483D01*
G37*
G36*
G01X912816Y1655394D02*
G02X910816I-1000J0D01*
G01Y1656394D01*
G02X912816I1000J0D01*
G01Y1655394D01*
G37*
G36*
G01X905729D02*
G02X903729I-1000J0D01*
G01Y1656394D01*
G02X905729I1000J0D01*
G01Y1655394D01*
G37*
G36*
G01X898642D02*
G02X896642I-1000J0D01*
G01Y1656394D01*
G02X898642I1000J0D01*
G01Y1655394D01*
G37*
G36*
G01X961737Y-127875D02*
X959237Y-130375D01*
X964237D01*
X961737Y-127875D01*
G37*
G36*
G01X955921Y6565D02*
G02X953921I-1000J0D01*
G01Y8565D01*
G02X955921I1000J0D01*
G01Y6565D01*
G37*
G36*
G01X948047D02*
G02X946047I-1000J0D01*
G01Y8565D01*
G02X948047I1000J0D01*
G01Y6565D01*
G37*
G36*
G01X955921Y385698D02*
G02X953921I-1000J0D01*
G01Y387698D01*
G02X955921I1000J0D01*
G01Y385698D01*
G37*
G36*
G01X948047D02*
G02X946047I-1000J0D01*
G01Y387698D01*
G02X948047I1000J0D01*
G01Y385698D01*
G37*
G36*
G01X952120Y940300D02*
X982880D01*
Y925700D01*
X952120D01*
Y940300D01*
G37*
G36*
G01X947120Y1010800D02*
X977880D01*
Y996200D01*
X947120D01*
Y1010800D01*
G37*
G36*
G01X948850Y1543050D02*
X953850Y1538050D01*
Y1543050D01*
X948850D01*
G37*
G36*
G01X1052207Y1658268D02*
Y1581307D01*
X965307D01*
Y1658268D01*
X970666D01*
Y1587870D01*
X989407D01*
Y1582307D01*
X1030207D01*
Y1587870D01*
X1046657D01*
Y1658268D01*
X1052207D01*
G37*
G36*
G01X972422Y1656187D02*
G02X975422I1500J0D01*
G01Y1653687D01*
G02X972422I-1500J0D01*
G01Y1656187D01*
G37*
G36*
G01X985020D02*
G02X988020I1500J0D01*
G01Y1653687D01*
G02X985020I-1500J0D01*
G01Y1656187D01*
G37*
G36*
G01X1032020Y-66455D02*
X1030620Y-67855D01*
X1033420D01*
X1032020Y-66455D01*
G37*
G36*
G01X1036623Y857803D02*
X1045623D01*
Y849803D01*
X1036623D01*
Y857803D01*
G37*
G36*
G01X1019800Y939500D02*
Y925500D01*
X1038800D01*
Y939500D01*
X1019800D01*
G37*
G36*
G01X996314Y1011140D02*
X1027074D01*
Y996540D01*
X996314D01*
Y1011140D01*
G37*
G36*
G01X1024620Y1102300D02*
X1055380D01*
Y1087700D01*
X1024620D01*
Y1102300D01*
G37*
G36*
G01X998300Y1170100D02*
Y1158900D01*
X1015700D01*
Y1170100D01*
X998300D01*
G37*
G36*
G01X1028255Y1476511D02*
X1031655D01*
X1029955Y1478211D01*
X1028255Y1476511D01*
G37*
G36*
G01X1000455D02*
X1003855D01*
X1002155Y1478211D01*
X1000455Y1476511D01*
G37*
G36*
G01X1035528Y1519029D02*
X1037836Y1516721D01*
Y1521337D01*
X1035528Y1519029D01*
G37*
G36*
G01X1000768Y1656187D02*
G02X1003768I1500J0D01*
G01Y1653687D01*
G02X1000768I-1500J0D01*
G01Y1656187D01*
G37*
G36*
G01X1013366D02*
G02X1016366I1500J0D01*
G01Y1653687D01*
G02X1013366I-1500J0D01*
G01Y1656187D01*
G37*
G36*
G01X1029114D02*
G02X1032114I1500J0D01*
G01Y1653687D01*
G02X1029114I-1500J0D01*
G01Y1656187D01*
G37*
G36*
G01X1054533Y-71697D02*
X1053133Y-73097D01*
X1055933D01*
X1054533Y-71697D01*
G37*
G36*
G01X1082015Y1045698D02*
X1133245D01*
Y1040698D01*
X1082215D01*
Y986092D01*
X1141615D01*
Y1028398D01*
X1136109D01*
Y1040698D01*
X1133255D01*
Y1045698D01*
X1143515D01*
Y1037998D01*
X1141215D01*
Y1033798D01*
X1143515D01*
Y978798D01*
X1082015D01*
Y1045698D01*
G37*
G36*
G01X1084389Y987292D02*
G02Y989892I0J1300D01*
G01X1087389D01*
G02Y987292I0J-1300D01*
G01X1084389D01*
G37*
G36*
G01Y994379D02*
G02Y996979I0J1300D01*
G01X1087389D01*
G02Y994379I0J-1300D01*
G01X1084389D01*
G37*
G36*
G01Y1001465D02*
G02Y1004065I0J1300D01*
G01X1087389D01*
G02Y1001465I0J-1300D01*
G01X1084389D01*
G37*
G36*
G01Y1008552D02*
G02Y1011152I0J1300D01*
G01X1087389D01*
G02Y1008552I0J-1300D01*
G01X1084389D01*
G37*
G36*
G01Y1015638D02*
G02Y1018238I0J1300D01*
G01X1087389D01*
G02Y1015638I0J-1300D01*
G01X1084389D01*
G37*
G36*
G01Y1022725D02*
G02Y1025325I0J1300D01*
G01X1087389D01*
G02Y1022725I0J-1300D01*
G01X1084389D01*
G37*
G36*
G01Y1029811D02*
G02Y1032411I0J1300D01*
G01X1087389D01*
G02Y1029811I0J-1300D01*
G01X1084389D01*
G37*
G36*
G01Y1036898D02*
G02Y1039498I0J1300D01*
G01X1087389D01*
G02Y1036898I0J-1300D01*
G01X1084389D01*
G37*
G36*
G01X1072120Y1103300D02*
X1102880D01*
Y1088700D01*
X1072120D01*
Y1103300D01*
G37*
G36*
G01X1082015Y1415938D02*
X1143515D01*
Y1406788D01*
X1140715D01*
Y1402788D01*
X1143515D01*
Y1305788D01*
X1136109D01*
Y1410788D01*
X1088589D01*
Y1153288D01*
X1136109D01*
Y1262788D01*
X1143515D01*
Y1150838D01*
X1082015D01*
Y1415938D01*
G37*
G36*
G01X1056055Y1476511D02*
X1059455D01*
X1057755Y1478211D01*
X1056055Y1476511D01*
G37*
G36*
G01X1041712Y1656187D02*
G02X1044712I1500J0D01*
G01Y1653687D01*
G02X1041712I-1500J0D01*
G01Y1656187D01*
G37*
G36*
G01X1098441Y6565D02*
G02X1096441I-1000J0D01*
G01Y8565D01*
G02X1098441I1000J0D01*
G01Y6565D01*
G37*
G36*
G01X1124031D02*
G02X1122031I-1000J0D01*
G01Y8565D01*
G02X1124031I1000J0D01*
G01Y6565D01*
G37*
G36*
G01X1116157D02*
G02X1114157I-1000J0D01*
G01Y8565D01*
G02X1116157I1000J0D01*
G01Y6565D01*
G37*
G36*
G01X1106315D02*
G02X1104315I-1000J0D01*
G01Y8565D01*
G02X1106315I1000J0D01*
G01Y6565D01*
G37*
G36*
G01X1131536Y-235D02*
X1093836D01*
Y352165D01*
X1094541D01*
Y5065D01*
X1125931D01*
Y150765D01*
X1131136D01*
Y191565D01*
X1125931D01*
Y352165D01*
X1131536D01*
Y-235D01*
G37*
G36*
G01X1098441Y385698D02*
G02X1096441I-1000J0D01*
G01Y387698D01*
G02X1098441I1000J0D01*
G01Y385698D01*
G37*
G36*
G01X1124031D02*
G02X1122031I-1000J0D01*
G01Y387698D01*
G02X1124031I1000J0D01*
G01Y385698D01*
G37*
G36*
G01X1116157D02*
G02X1114157I-1000J0D01*
G01Y387698D01*
G02X1116157I1000J0D01*
G01Y385698D01*
G37*
G36*
G01X1106315D02*
G02X1104315I-1000J0D01*
G01Y387698D01*
G02X1106315I1000J0D01*
G01Y385698D01*
G37*
G36*
G01X1131536Y378898D02*
X1093836D01*
Y731298D01*
X1094541D01*
Y384198D01*
X1125931D01*
Y529898D01*
X1131136D01*
Y570698D01*
X1125931D01*
Y731298D01*
X1131536D01*
Y378898D01*
G37*
G36*
G01X1115120Y1103300D02*
X1145880D01*
Y1088700D01*
X1115120D01*
Y1103300D01*
G37*
G36*
G01X1092215Y1154288D02*
G02Y1156288I0J1000D01*
G01X1093215D01*
G02Y1154288I0J-1000D01*
G01X1092215D01*
G37*
G36*
G01X1097215D02*
G02Y1156288I0J1000D01*
G01X1098215D01*
G02Y1154288I0J-1000D01*
G01X1097215D01*
G37*
G36*
G01X1102215D02*
G02Y1156288I0J1000D01*
G01X1103215D01*
G02Y1154288I0J-1000D01*
G01X1102215D01*
G37*
G36*
G01X1107215D02*
G02Y1156288I0J1000D01*
G01X1108215D01*
G02Y1154288I0J-1000D01*
G01X1107215D01*
G37*
G36*
G01X1112215D02*
G02Y1156288I0J1000D01*
G01X1113215D01*
G02Y1154288I0J-1000D01*
G01X1112215D01*
G37*
G36*
G01X1117215D02*
G02Y1156288I0J1000D01*
G01X1118215D01*
G02Y1154288I0J-1000D01*
G01X1117215D01*
G37*
G36*
G01X1122215D02*
G02Y1156288I0J1000D01*
G01X1123215D01*
G02Y1154288I0J-1000D01*
G01X1122215D01*
G37*
G36*
G01X1127215D02*
G02Y1156288I0J1000D01*
G01X1128215D01*
G02Y1154288I0J-1000D01*
G01X1127215D01*
G37*
G36*
G01X1132215D02*
G02Y1156288I0J1000D01*
G01X1133215D01*
G02Y1154288I0J-1000D01*
G01X1132215D01*
G37*
G36*
G01X1095478Y1587783D02*
G02Y1589383I0J800D01*
G01X1096278D01*
G02Y1587783I0J-800D01*
G01X1095478D01*
G37*
G36*
G01Y1600381D02*
G02Y1601981I0J800D01*
G01X1096278D01*
G02Y1600381I0J-800D01*
G01X1095478D01*
G37*
G36*
G01X1093778Y1606881D02*
X1129782D01*
Y1604581D01*
X1094378D01*
Y1585183D01*
X1129782D01*
Y1582881D01*
X1093778D01*
Y1606881D01*
G37*
G36*
G01X1321741Y114535D02*
X1352501D01*
Y99935D01*
X1321741D01*
Y114535D01*
G37*
G36*
G01X1294411Y165516D02*
X1296911Y163016D01*
Y168016D01*
X1294411Y165516D01*
G37*
G36*
G01X1324100Y216861D02*
X1312900D01*
Y199461D01*
X1324100D01*
Y216861D01*
G37*
G36*
G01X1317300Y249761D02*
Y238561D01*
X1334700D01*
Y249761D01*
X1317300D01*
G37*
G36*
G01X1294411Y618272D02*
X1296911Y615772D01*
Y620772D01*
X1294411Y618272D01*
G37*
G36*
G01X1317300Y702517D02*
Y691317D01*
X1334700D01*
Y702517D01*
X1317300D01*
G37*
G36*
G01X1324100Y669617D02*
X1312900D01*
Y652217D01*
X1324100D01*
Y669617D01*
G37*
G36*
G01X1294411Y1071028D02*
X1296911Y1068528D01*
Y1073528D01*
X1294411Y1071028D01*
G37*
G36*
G01X1324100Y1122373D02*
X1312900D01*
Y1104973D01*
X1324100D01*
Y1122373D01*
G37*
G36*
G01X1317300Y1155273D02*
Y1144073D01*
X1334700D01*
Y1155273D01*
X1317300D01*
G37*
G36*
G01X1374400Y534900D02*
X1377800D01*
X1376100Y536600D01*
X1374400Y534900D01*
G37*
G36*
G01X1418624Y165516D02*
X1421124Y163016D01*
Y168016D01*
X1418624Y165516D01*
G37*
G36*
G01X1384989Y583399D02*
X1386989Y585399D01*
X1382989D01*
X1384989Y583399D01*
G37*
G36*
G01X1418624Y618272D02*
X1421124Y615772D01*
Y620772D01*
X1418624Y618272D01*
G37*
G36*
G01Y1071028D02*
X1421124Y1068528D01*
Y1073528D01*
X1418624Y1071028D01*
G37*
G36*
G01X1448313Y216861D02*
X1437113D01*
Y199461D01*
X1448313D01*
Y216861D01*
G37*
G36*
G01X1441513Y249761D02*
Y238561D01*
X1458913D01*
Y249761D01*
X1441513D01*
G37*
G36*
G01X1448350Y535750D02*
X1443350Y540750D01*
Y535750D01*
X1448350D01*
G37*
G36*
G01X1441513Y702517D02*
Y691317D01*
X1458913D01*
Y702517D01*
X1441513D01*
G37*
G36*
G01X1448313Y669617D02*
X1437113D01*
Y652217D01*
X1448313D01*
Y669617D01*
G37*
G36*
G01Y1122373D02*
X1437113D01*
Y1104973D01*
X1448313D01*
Y1122373D01*
G37*
G36*
G01X1441513Y1155273D02*
Y1144073D01*
X1458913D01*
Y1155273D01*
X1441513D01*
G37*
G36*
G01X1542836Y165516D02*
X1545336Y163016D01*
Y168016D01*
X1542836Y165516D01*
G37*
G36*
G01X1572525Y216861D02*
X1561325D01*
Y199461D01*
X1572525D01*
Y216861D01*
G37*
G36*
G01X1565725Y249761D02*
Y238561D01*
X1583125D01*
Y249761D01*
X1565725D01*
G37*
G36*
G01X1542836Y618272D02*
X1545336Y615772D01*
Y620772D01*
X1542836Y618272D01*
G37*
G36*
G01X1565725Y702517D02*
Y691317D01*
X1583125D01*
Y702517D01*
X1565725D01*
G37*
G36*
G01X1567525Y671617D02*
X1556325D01*
Y654217D01*
X1567525D01*
Y671617D01*
G37*
G36*
G01X1542836Y1071028D02*
X1545336Y1068528D01*
Y1073528D01*
X1542836Y1071028D01*
G37*
G36*
G01X1565273Y1109575D02*
Y1120775D01*
X1547873D01*
Y1109575D01*
X1565273D01*
G37*
G36*
G01X1608408Y40911D02*
Y17289D01*
X1734392D01*
Y40911D01*
X1608408D01*
G37*
G36*
G01X1576500Y1098500D02*
X1587700D01*
Y1115900D01*
X1576500D01*
Y1098500D01*
G37*
G36*
G01X1667049Y165516D02*
X1669549Y163016D01*
Y168016D01*
X1667049Y165516D01*
G37*
G36*
G01Y618272D02*
X1669549Y615772D01*
Y620772D01*
X1667049Y618272D01*
G37*
G36*
G01Y1071028D02*
X1669549Y1068528D01*
Y1073528D01*
X1667049Y1071028D01*
G37*
G36*
G01X1696738Y216861D02*
X1685538D01*
Y199461D01*
X1696738D01*
Y216861D01*
G37*
G36*
G01X1689938Y249761D02*
Y238561D01*
X1707338D01*
Y249761D01*
X1689938D01*
G37*
G36*
G01Y702517D02*
Y691317D01*
X1707338D01*
Y702517D01*
X1689938D01*
G37*
G36*
G01X1696738Y669617D02*
X1685538D01*
Y652217D01*
X1696738D01*
Y669617D01*
G37*
G36*
G01Y1122373D02*
X1685538D01*
Y1104973D01*
X1696738D01*
Y1122373D01*
G37*
G36*
G01X1689938Y1155273D02*
Y1144073D01*
X1707338D01*
Y1155273D01*
X1689938D01*
G37*
G36*
G01X1791261Y165516D02*
X1793761Y163016D01*
Y168016D01*
X1791261Y165516D01*
G37*
G36*
G01X1820950Y216861D02*
X1809750D01*
Y199461D01*
X1820950D01*
Y216861D01*
G37*
G36*
G01X1791261Y618272D02*
X1793761Y615772D01*
Y620772D01*
X1791261Y618272D01*
G37*
G36*
G01X1820950Y669617D02*
X1809750D01*
Y652217D01*
X1820950D01*
Y669617D01*
G37*
G36*
G01X1791261Y1071028D02*
X1793761Y1068528D01*
Y1073528D01*
X1791261Y1071028D01*
G37*
G36*
G01X1818950Y1122373D02*
X1807750D01*
Y1104973D01*
X1818950D01*
Y1122373D01*
G37*
G36*
G01X1841469Y241261D02*
Y230061D01*
X1858869D01*
Y241261D01*
X1841469D01*
G37*
G36*
G01X1814150Y249761D02*
Y238561D01*
X1831550D01*
Y249761D01*
X1814150D01*
G37*
G36*
G01X1841469Y694017D02*
Y682817D01*
X1858869D01*
Y694017D01*
X1841469D01*
G37*
G36*
G01X1814150Y702517D02*
Y691317D01*
X1831550D01*
Y702517D01*
X1814150D01*
G37*
G36*
G01X1842077Y1140864D02*
Y1129664D01*
X1859477D01*
Y1140864D01*
X1842077D01*
G37*
G36*
G01X1814150Y1155273D02*
Y1144073D01*
X1831550D01*
Y1155273D01*
X1814150D01*
G37*
G36*
G01X1881869Y212061D02*
Y223261D01*
X1864469D01*
Y212061D01*
X1881869D01*
G37*
G36*
G01Y664817D02*
Y676017D01*
X1864469D01*
Y664817D01*
X1881869D01*
G37*
G36*
G01X1881979Y1102163D02*
Y1113363D01*
X1864579D01*
Y1102163D01*
X1881979D01*
G37*
G36*
G01X1915474Y165516D02*
X1917974Y163016D01*
Y168016D01*
X1915474Y165516D01*
G37*
G36*
G01Y618272D02*
X1917974Y615772D01*
Y620772D01*
X1915474Y618272D01*
G37*
G36*
G01Y1071028D02*
X1917974Y1068528D01*
Y1073528D01*
X1915474Y1071028D01*
G37*
%LPC*%
G75*
G36*
G01X362024Y501815D02*
X364099Y502020D01*
X366094Y502625D01*
X367929Y503605D01*
X368998Y504485D01*
X366558Y506925D01*
X366128D01*
X366030Y506933D01*
X365329Y507145D01*
X365004Y507320D01*
Y506925D01*
X363404D01*
Y510080D01*
X360687Y512797D01*
X360279Y512465D01*
X359643Y512124D01*
X358987Y511925D01*
X356429D01*
Y506925D01*
X354859D01*
Y518625D01*
X354064Y519419D01*
X353184Y518350D01*
X352204Y516515D01*
X351599Y514520D01*
X351394Y512445D01*
X351599Y510370D01*
X352204Y508375D01*
X353184Y506540D01*
X354509Y504930D01*
X356119Y503605D01*
X357954Y502625D01*
X359949Y502020D01*
X362024Y501815D01*
G37*
G36*
G01X369983Y505470D02*
X370864Y506540D01*
X371844Y508375D01*
X372449Y510370D01*
X372654Y512445D01*
X372449Y514520D01*
X371844Y516515D01*
X370864Y518350D01*
X369539Y519960D01*
X367929Y521285D01*
X366094Y522265D01*
X364099Y522870D01*
X362024Y523075D01*
X359949Y522870D01*
X357954Y522265D01*
X356119Y521285D01*
X355048Y520403D01*
X356290Y519160D01*
X358679D01*
X358953Y519125D01*
X359644Y518915D01*
X360279Y518575D01*
X360839Y518120D01*
X361294Y517560D01*
X361634Y516925D01*
X361844Y516235D01*
X361914Y515520D01*
X361844Y514805D01*
X361634Y514115D01*
X361530Y513922D01*
X363404Y512048D01*
Y518965D01*
X365004D01*
Y514910D01*
X365329Y515085D01*
X366024Y515295D01*
X366749Y515365D01*
X367474Y515295D01*
X368169Y515085D01*
X368809Y514740D01*
X369369Y514280D01*
X369829Y513720D01*
X370174Y513080D01*
X370383Y512387D01*
X370454Y511660D01*
Y510570D01*
X370384Y509845D01*
X370174Y509150D01*
X369829Y508510D01*
X369369Y507950D01*
X368809Y507490D01*
X368259Y507194D01*
X369983Y505470D01*
G37*
G36*
G01X367059Y508394D02*
X367179Y508405D01*
X367595Y508535D01*
X367977Y508737D01*
X368313Y509014D01*
X368586Y509348D01*
X368787Y509729D01*
X368915Y510143D01*
X368954Y510570D01*
Y511660D01*
X368916Y512090D01*
X368784Y512505D01*
X368584Y512885D01*
X368309Y513220D01*
X367974Y513496D01*
X367592Y513696D01*
X367177Y513825D01*
X366750Y513865D01*
X366320Y513825D01*
X365904Y513695D01*
X365524Y513495D01*
X365189Y513220D01*
X365004Y512995D01*
Y510448D01*
X367059Y508394D01*
G37*
G36*
G01X356429Y513500D02*
X359039D01*
X359069Y513510D01*
X359449Y513710D01*
X359631Y513853D01*
X356429Y517055D01*
Y513500D01*
G37*
G36*
G01X360370Y515081D02*
X360374Y515095D01*
X360414Y515520D01*
X360374Y515945D01*
X360249Y516350D01*
X360049Y516730D01*
X359779Y517060D01*
X359449Y517330D01*
X359069Y517530D01*
X358984Y517560D01*
X357890D01*
X360370Y515081D01*
G37*
%LPD*%
G75*
G54D10*
X111800Y987200D03*
Y983200D03*
X115800Y979200D03*
X119800Y971200D03*
Y975200D03*
Y979200D03*
X115800Y975200D03*
X119800Y987200D03*
Y983200D03*
X115800Y971200D03*
Y983200D03*
Y987200D03*
X182500Y559200D03*
Y571200D03*
Y575200D03*
X178500D03*
Y571200D03*
X182500Y567200D03*
X186500Y559200D03*
Y563200D03*
Y567200D03*
X182500Y563200D03*
X186500Y575200D03*
Y571200D03*
X730882Y888502D03*
X1757600Y987200D03*
X1761600D03*
Y983200D03*
X1757600D03*
X1761600Y991200D03*
Y999200D03*
Y995200D03*
X1757600Y991200D03*
X1753600Y995200D03*
Y999200D03*
X1757600D03*
Y995200D03*
X1860276Y916059D03*
Y912059D03*
X1872276Y916059D03*
X1876276D03*
Y920059D03*
X1872276D03*
X1868276Y916059D03*
X1864276Y912059D03*
X1868276D03*
X1864276Y916059D03*
X1876276Y912059D03*
X1872276D03*
G54D20*
G01X85437Y197161D02*
Y193761D01*
G01Y649917D02*
Y646517D01*
G01Y1102673D02*
Y1099273D01*
G01X209649Y197161D02*
Y193761D01*
G01X209849Y640917D02*
Y637517D01*
G01X209649Y1102673D02*
Y1099273D01*
G01X333862Y197161D02*
Y193761D01*
G01Y649917D02*
Y646517D01*
G01Y1102673D02*
Y1099273D01*
G01X458074Y197161D02*
Y193761D01*
G01Y649917D02*
Y646517D01*
G01X463173Y1078826D02*
X459773D01*
G01X582287Y197161D02*
Y193761D01*
G01Y649917D02*
Y646517D01*
G01Y1102673D02*
Y1099273D01*
G01X706500Y197161D02*
Y193761D01*
G01X706700Y651417D02*
Y648017D01*
G01X706500Y1102673D02*
Y1099273D01*
G01X1014100Y-59032D02*
Y-55632D01*
G01X999100Y-62268D02*
Y-58868D01*
G01X1084300Y-79732D02*
Y-76332D01*
G01X1069400Y-66132D02*
Y-62732D01*
G01X1102362Y-74821D02*
Y-71421D01*
G01X1301500Y183161D02*
X1304900D01*
G01X1301500Y635917D02*
X1304900D01*
G01X1301500Y1088673D02*
X1304900D01*
G01X1425713Y183161D02*
X1429113D01*
G01X1425713Y635917D02*
X1429113D01*
G01X1425713Y1088673D02*
X1429113D01*
G01X1549925Y183161D02*
X1553325D01*
G01X1549925Y635917D02*
X1553325D01*
G01X1549925Y1088673D02*
X1553325D01*
G01X1674138Y183161D02*
X1677538D01*
G01X1674138Y635917D02*
X1677538D01*
G01X1674138Y1088673D02*
X1677538D01*
G01X1798350Y183161D02*
X1801750D01*
G01X1798350Y635917D02*
X1801750D01*
G01X1798350Y1088673D02*
X1801750D01*
G01X1861417Y168575D02*
X1858017D01*
G01X1861417Y621331D02*
X1858017D01*
G01X1873330Y1074500D02*
X1869930D01*
G54D11*
G01X1472579Y1658268D02*
G03X1483052I5236J0D01*
G01X1504074D02*
G03X1514547I5236J0D01*
G01X1567065D02*
G03X1577537I5236J0D01*
G01X1535569D02*
G03X1546042I5236J0D01*
G01X1598560D02*
G03X1609032I5236J0D01*
G01X1630055D02*
G03X1640527I5236J0D01*
G54D21*
G01X472622Y507267D02*
X471962D01*
G01X472062Y507357D02*
X472722D01*
G01X472812Y507467D02*
X472162D01*
G01X472262Y507557D02*
X472912D01*
G01X473012Y507667D02*
X472352D01*
G01X472452Y507767D02*
X473102D01*
G01X473202Y507857D02*
X472552D01*
G01X472642Y507967D02*
X473302D01*
G01X473392Y508057D02*
X472742D01*
G01X472832Y508167D02*
X473492D01*
G01X473592Y508267D02*
X472932D01*
G01X473032Y508357D02*
X473682D01*
G01X473782Y508467D02*
X473137D01*
G01X473132D02*
X473182D01*
G01X473222Y508557D02*
X473262D01*
G01X473222D02*
X473872D01*
G01X473972Y508667D02*
X473322D01*
G01X473422Y508767D02*
X474072D01*
G01X474172Y508857D02*
X473512D01*
G01X473612Y508967D02*
X474262D01*
G01X474362Y509057D02*
X473702D01*
G01X473802Y509167D02*
X474462D01*
G01X474552Y509267D02*
X473902D01*
G01X474002Y509357D02*
X474652D01*
G01X474742Y509467D02*
X474092D01*
G01X474192Y509557D02*
X474842D01*
G01X474942Y509667D02*
X474282D01*
G01X474382Y509767D02*
X475042D01*
G01X475132Y509857D02*
X474482D01*
G01X474572Y509967D02*
X475232D01*
G01X475422Y510167D02*
X474772D01*
G01X474962Y510357D02*
X475612D01*
G01X470322Y524777D02*
X470352Y524797D01*
G01X470322Y524237D02*
Y524777D01*
G01X470332Y524217D02*
X470322Y524237D01*
G01X470382Y524107D02*
X470332Y524217D01*
G01X470392Y524097D02*
X470382Y524107D01*
G01X475572Y518507D02*
X470392Y524097D01*
G01X470322Y524767D02*
X470382D01*
G01X470322Y524667D02*
X470472D01*
G01X470562Y524557D02*
X470322D01*
G01Y524467D02*
X470662D01*
G01X470752Y524357D02*
X470322D01*
G01Y524267D02*
X470842D01*
G01X470942Y524167D02*
X470352D01*
G01X470422Y524057D02*
X471032D01*
G01X471122Y523967D02*
X470512D01*
G01X470602Y523857D02*
X471212D01*
G01X471312Y523767D02*
X470702D01*
G01X470792Y523667D02*
X471402D01*
G01X471492Y523557D02*
X470882D01*
G01X470972Y523467D02*
X471592D01*
G01X471682Y523357D02*
X471072D01*
G01X471162Y523267D02*
X471772D01*
G01X471872Y523167D02*
X471252D01*
G01X471352Y523057D02*
X471962D01*
G01X472052Y522967D02*
X471442D01*
G01X471532Y522857D02*
X472152D01*
G01X472242Y522767D02*
X471632D01*
G01X471722Y522667D02*
X472332D01*
G01X472432Y522557D02*
X471812D01*
G01X471902Y522467D02*
X472522D01*
G01X472612Y522357D02*
X472002D01*
G01X472092Y522267D02*
X472702D01*
G01X472802Y522167D02*
X472182D01*
G01X472282Y522057D02*
X472892D01*
G01X472982Y521967D02*
X472372D01*
G01X472462Y521857D02*
X473072D01*
G01X473172Y521767D02*
X472562D01*
G01X472652Y521667D02*
X473262D01*
G01X473352Y521557D02*
X472742D01*
G01X472832Y521467D02*
X473452D01*
G01X473542Y521357D02*
X472932D01*
G01X473022Y521267D02*
X473632D01*
G01X473732Y521167D02*
X473112D01*
G01X473202Y521057D02*
X473822D01*
G01X473912Y520967D02*
X473302D01*
G01X473392Y520857D02*
X474012D01*
G01X474102Y520767D02*
X473482D01*
G01X473572Y520667D02*
X474192D01*
G01X474292Y520557D02*
X473672D01*
G01X473762Y520467D02*
X474382D01*
G01X474472Y520357D02*
X473852D01*
G01X473942Y520267D02*
X474572D01*
G01X474662Y520167D02*
X474042D01*
G01X474132Y520057D02*
X474752D01*
G01X474842Y519967D02*
X474222D01*
G01X474322Y519857D02*
X474942D01*
G01X475032Y519767D02*
X474412D01*
G01X474502Y519667D02*
X475122D01*
G01X475222Y519557D02*
X474602D01*
G01X474782Y519357D02*
X476022D01*
G01X476032Y519167D02*
X474972D01*
G01X474722Y521457D02*
X475232D01*
G01X474682Y521417D02*
X474722Y521457D01*
G01X474682Y520957D02*
Y521417D01*
G01X474722Y520917D02*
X474682Y520957D01*
G01Y521357D02*
X484932D01*
G01X484862Y521167D02*
X474682D01*
G01Y520967D02*
X484702D01*
G01X477332Y522267D02*
X475902D01*
G01X475322Y521527D02*
X475232Y521457D01*
G01X475342Y521577D02*
X475322Y521527D01*
G01X475342Y521587D02*
Y521577D01*
G01X475462Y521837D02*
X475342Y521587D01*
G01X475482Y521847D02*
X475462Y521837D01*
G01X475912Y522267D02*
X475482Y521847D01*
G01X475242Y521467D02*
X475972D01*
G01X476082Y521797D02*
X476192Y521867D01*
G01X475912Y521627D02*
X476082Y521797D01*
G01X475892Y521517D02*
X475912Y521627D01*
G01X475982Y521457D02*
X475892Y521517D01*
G01X476052Y521767D02*
X475432D01*
G01X475382Y521667D02*
X475952D01*
G01X475902Y521557D02*
X475332D01*
G01X475592Y521967D02*
X477272D01*
G01Y522167D02*
X475802D01*
G01X476152Y518567D02*
X479382Y515087D01*
G01X476142Y518567D02*
X476152D01*
G01X476102Y518617D02*
X476142Y518567D01*
G01X476072Y518677D02*
X476102Y518617D01*
G01X475892Y520807D02*
X476072Y518677D01*
G01X475992Y520917D02*
X475892Y520807D01*
G01X476412Y514767D02*
X475942D01*
G01X475932Y514967D02*
X476392D01*
G01X476372Y515167D02*
X475912D01*
G01X475892Y515357D02*
X476362D01*
G01X476342Y515557D02*
X475872D01*
G01X475852Y515767D02*
X476322D01*
G01X476312Y515967D02*
X475842D01*
G01X475822Y516167D02*
X476292D01*
G01X476272Y516357D02*
X475802D01*
G01X475792Y516557D02*
X476262D01*
G01X476242Y516767D02*
X475772D01*
G01X475752Y516967D02*
X476222D01*
G01X476202Y517167D02*
X475742D01*
G01X475722Y517357D02*
X476192D01*
G01X476172Y517557D02*
X475702D01*
G01X475692Y517667D02*
X476202D01*
G01X476702Y517967D02*
X475672D01*
G01X475652Y518167D02*
X476522D01*
G01X475592Y518477D02*
X475572Y518507D01*
G01X475632Y518377D02*
X475592Y518477D01*
G01X475632Y518367D02*
Y518377D01*
G01Y518357D02*
Y518367D01*
G01X476332Y518357D02*
X475632D01*
G01X475532Y518557D02*
X476152D01*
G01X476082Y518667D02*
X475432D01*
G01X475342Y518767D02*
X476072D01*
G01X476062Y518857D02*
X475252D01*
G01X475152Y518967D02*
X476052D01*
G01X476042Y519057D02*
X475062D01*
G01X474872Y519267D02*
X476022D01*
G01X476012Y519467D02*
X475532D01*
G01X475322Y520917D02*
X474722D01*
G01X475422Y520827D02*
X475322Y520917D01*
G01X475542Y519477D02*
X475422Y520827D01*
G01X475382Y520857D02*
X475942D01*
G01X475892Y520767D02*
X475432D01*
G01X475442Y520667D02*
X475912D01*
G01Y520557D02*
X475442D01*
G01X475452Y520467D02*
X475922D01*
G01X475932Y520357D02*
X475462D01*
G01X475472Y520267D02*
X475942D01*
G01X475952Y520167D02*
X475482D01*
G01X475492Y520057D02*
X475962D01*
G01Y519967D02*
X475502D01*
G01Y519857D02*
X475972D01*
G01X475982Y519767D02*
X475522D01*
G01Y519667D02*
X475992D01*
G01X476002Y519557D02*
X475532D01*
G01X475372Y519407D02*
X470352Y524797D01*
G01X475482Y519377D02*
X475372Y519407D01*
G01X475542Y519477D02*
X475482Y519377D01*
G01X474692Y519467D02*
X475312D01*
G01X475632Y518357D02*
X476072Y513207D01*
G01X476082Y513167D02*
X476552D01*
G01X476562Y512967D02*
X476092D01*
G01X476112Y512767D02*
X476582D01*
G01X476602Y512557D02*
X476132D01*
G01X476152Y512357D02*
X476622D01*
G01X476662Y512267D02*
X476162D01*
G01X476172Y511617D02*
X476072Y511507D01*
G01X476202Y511687D02*
X476172Y511617D01*
G01X476022Y511467D02*
X476712D01*
G01Y511267D02*
X475832D01*
G01X475642Y511057D02*
X476732D01*
G01X476092Y510857D02*
X475442D01*
G01X475352Y510767D02*
X476002D01*
G01X475902Y510667D02*
X475252D01*
G01X475152Y510557D02*
X475812D01*
G01X475712Y510467D02*
X475062D01*
G01X474872Y510267D02*
X475522D01*
G01X475322Y510057D02*
X474672D01*
G01X476052Y513467D02*
X476522D01*
G01X476502Y513667D02*
X476042D01*
G01X476022Y513857D02*
X476492D01*
G01X476472Y514057D02*
X476002D01*
G01X475982Y514267D02*
X476452D01*
G01X476442Y514467D02*
X475972D01*
G01X475962Y514557D02*
X476432D01*
G01X476422Y514667D02*
X475952D01*
G01X475932Y514857D02*
X476402D01*
G01X476392Y515057D02*
X475922D01*
G01X475902Y515267D02*
X476372D01*
G01X476352Y515467D02*
X475882D01*
G01X475872Y515667D02*
X476332D01*
G01X476312Y515857D02*
X475852D01*
G01X475832Y516057D02*
X476302D01*
G01X476282Y516267D02*
X475812D01*
G01X475802Y516467D02*
X476262D01*
G01X476252Y516667D02*
X475782D01*
G01X475762Y516857D02*
X476232D01*
G01X476212Y517057D02*
X475742D01*
G01X475732Y517267D02*
X476192D01*
G01X476182Y517467D02*
X475712D01*
G01X476342Y517687D02*
X479072Y514747D01*
G01X476222Y517707D02*
X476342Y517687D01*
G01X476172Y517607D02*
X476222Y517707D01*
G01X476442Y514357D02*
X475982D01*
G01X475992Y514167D02*
X476462D01*
G01X476482Y513967D02*
X476012D01*
G01X476032Y513767D02*
X476502D01*
G01X476512Y513557D02*
X476042D01*
G01X476062Y513357D02*
X476532D01*
G01X476542Y513267D02*
X476072D01*
G01X476202Y511747D02*
Y511687D01*
G01X476072Y513207D02*
X476202Y511747D01*
G01X476192Y511667D02*
X476872D01*
G01X476722Y511487D02*
X476702Y511417D01*
G01X476772Y511567D02*
X476722Y511487D01*
G01X476702Y511357D02*
X475932D01*
G01X475742Y511167D02*
X476722D01*
G01X476742Y510857D02*
X476242D01*
G01X476212Y510897D02*
X476112Y510877D01*
G01X476482Y508457D02*
X476592D01*
G01X476482Y508467D02*
Y508457D01*
G01X476282Y510817D02*
X476482Y508467D01*
G01X476212Y510897D02*
X476282Y510817D01*
G01X476582Y508557D02*
X476472D01*
G01X476477D02*
X482072D01*
G01X482137Y508467D02*
X476482D01*
G01X476722Y507417D02*
X477612D01*
G01X476682Y507457D02*
X476722Y507417D01*
G01X476682Y508137D02*
Y507457D01*
G01X476652Y508207D02*
X476682Y508137D01*
G01X476502Y508367D02*
X476652Y508207D01*
G01X476492Y508387D02*
X476502Y508367D01*
G01X476482Y508447D02*
X476492Y508387D01*
G01X477652Y507467D02*
X476682D01*
G01Y507667D02*
X477652D01*
G01Y507857D02*
X476682D01*
G01Y508057D02*
X477652D01*
G01X476932Y508767D02*
X476462D01*
G01X476442Y508857D02*
X476912D01*
G01X476902Y509057D02*
X476432D01*
G01X476412Y509267D02*
X476882D01*
G01X476862Y509467D02*
X476392D01*
G01X476382Y509667D02*
X476852D01*
G01X476832Y509857D02*
X476362D01*
G01X476342Y510057D02*
X476812D01*
G01X476802Y510267D02*
X476332D01*
G01X476312Y510467D02*
X476782D01*
G01X476762Y510667D02*
X476302D01*
G01X476192Y511857D02*
X477062D01*
G01X477252Y512057D02*
X476172D01*
G01X476142Y512467D02*
X476612D01*
G01X476622Y512317D02*
X476172Y517607D01*
G01X476362Y517667D02*
X476982D01*
G01X477172Y517467D02*
X476552D01*
G01X476732Y517267D02*
X477352D01*
G01X476612Y518057D02*
X475662D01*
G01X475642Y518267D02*
X476432D01*
G01X476242Y518467D02*
X475602D01*
G01X476302Y521877D02*
X476192Y521867D01*
G01X476352Y521787D02*
X476302Y521877D01*
G01X476352Y521557D02*
Y521787D01*
G01X476252Y521457D02*
X476352Y521557D01*
G01X475982Y521457D02*
X476252D01*
G01X476182Y521857D02*
X475492D01*
G01X476362Y522847D02*
X476392Y522867D01*
G01X476352Y522817D02*
X476362Y522847D01*
G01X476352Y522617D02*
Y522817D01*
G01X476342Y522577D02*
X476352Y522617D01*
G01X476322Y522527D02*
X476342Y522577D01*
G01X476272Y522467D02*
X476322Y522527D01*
G01X476182Y522427D02*
X476272Y522467D01*
G01X475912Y522267D02*
X476182Y522427D01*
G01X476392Y522857D02*
X477222D01*
G01X476352Y522667D02*
X479242D01*
G01X479232Y522467D02*
X476252D01*
G01X476302Y521857D02*
X477272D01*
G01Y521667D02*
X476352D01*
G01X476262Y521467D02*
X477372D01*
G01X476562Y513057D02*
X476092D01*
G01X476102Y512857D02*
X476572D01*
G01X476592Y512667D02*
X476122D01*
G01X476692Y512227D02*
X476792Y512257D01*
G01X476622Y512317D02*
X476692Y512227D01*
G01X476602Y508267D02*
X482382D01*
G01X476922Y508837D02*
X476702Y511417D01*
G01X476922Y508767D02*
Y508837D01*
G01X477022Y508677D02*
X476922Y508767D01*
G01X481122Y508677D02*
X477022D01*
G01X476772Y511557D02*
X476122D01*
G01X476202Y511767D02*
X476962D01*
G01X476782Y511567D02*
X476772D01*
G01X476782Y511577D02*
Y511567D01*
G01Y511577D02*
X479372Y514267D01*
G01X479182Y514057D02*
X478542D01*
G01X478342Y513857D02*
X478992D01*
G01X478802Y513667D02*
X478152D01*
G01X477962Y513467D02*
X478602D01*
G01X478512Y513357D02*
X477862D01*
G01X477912Y513417D02*
X476792Y512257D01*
G01X476802Y512267D02*
X477442D01*
G01X477352Y512167D02*
X476172D01*
G01X476182Y511967D02*
X477162D01*
G01X476902Y512357D02*
X477542D01*
G01X477642Y512467D02*
X477002D01*
G01X477092Y512557D02*
X477742D01*
G01X477832Y512667D02*
X477192D01*
G01X477282Y512767D02*
X477932D01*
G01X478022Y512857D02*
X477382D01*
G01X477482Y512967D02*
X478122D01*
G01X478222Y513057D02*
X477572D01*
G01X477672Y513167D02*
X478312D01*
G01X478412Y513267D02*
X477762D01*
G01X478592Y515267D02*
X479222D01*
G01X479032Y515467D02*
X478412D01*
G01X478222Y515667D02*
X478842D01*
G01X478662Y515857D02*
X478032D01*
G01X477942Y515967D02*
X478562D01*
G01X478472Y516057D02*
X477852D01*
G01X477762Y516167D02*
X478382D01*
G01X478282Y516267D02*
X477662D01*
G01X477572Y516357D02*
X478192D01*
G01X478102Y516467D02*
X477482D01*
G01X477382Y516557D02*
X478012D01*
G01X477912Y516667D02*
X477292D01*
G01X477202Y516767D02*
X477822D01*
G01X477732Y516857D02*
X477102D01*
G01X477012Y516967D02*
X477632D01*
G01X477542Y517057D02*
X476922D01*
G01X476832Y517167D02*
X477452D01*
G01X477262Y517357D02*
X476642D01*
G01X476452Y517557D02*
X477072D01*
G01X476892Y517767D02*
X475692D01*
G01X475682Y517857D02*
X476802D01*
G01X478652Y517137D02*
X478692Y517097D01*
G01X477272Y521557D02*
X476352D01*
G01X477372Y521457D02*
X477272Y521557D01*
G01X476352Y521767D02*
X477272D01*
G01X478602Y522467D02*
X478712Y522357D01*
G01X478332Y522437D02*
X478602Y522467D01*
G01X478052Y522407D02*
X478332Y522437D01*
G01X477932Y522397D02*
X478052Y522407D01*
G01X477832Y522377D02*
X477932Y522397D01*
G01X477582Y522337D02*
X477832Y522377D01*
G01X477572Y522337D02*
X477582D01*
G01X477482Y522317D02*
X477572Y522337D01*
G01X477472Y522317D02*
X477482D01*
G01X477352Y522297D02*
X477472Y522317D01*
G01X477272Y522197D02*
X477352Y522297D01*
G01X477272Y521557D02*
Y522197D01*
G01X477212Y522867D02*
X476392D01*
G01X477232Y522857D02*
X477212Y522867D01*
G01X477262Y522847D02*
X477232Y522857D01*
G01X477292Y522827D02*
X477262Y522847D01*
G01X477372Y522807D02*
X477292Y522827D01*
G01X477392Y522817D02*
X477372Y522807D01*
G01X477632Y522857D02*
X477392Y522817D01*
G01X478132Y522927D02*
X477632Y522857D01*
G01X478252Y522937D02*
X478132Y522927D01*
G01X478312Y522937D02*
X478252D01*
G01X478472Y522957D02*
X478312Y522937D01*
G01X478612Y522967D02*
X478472Y522957D01*
G01X476072Y522357D02*
X477722D01*
G01X477272Y522057D02*
X475702D01*
G01X477372Y521457D02*
X483212D01*
G01X481282Y522967D02*
X478592D01*
G01X478612D02*
X478712Y523067D01*
G01X476742Y510967D02*
X475542D01*
G01X476282Y510767D02*
X476752D01*
G01X476772Y510557D02*
X476302D01*
G01X476322Y510357D02*
X476792D01*
G01X476802Y510167D02*
X476332D01*
G01X476352Y509967D02*
X476822D01*
G01X476842Y509767D02*
X476372D01*
G01X476392Y509557D02*
X476852D01*
G01X476872Y509357D02*
X476412D01*
G01X476422Y509167D02*
X476892D01*
G01X476912Y508967D02*
X476442D01*
G01X476672Y508167D02*
X477722D01*
G01X477652Y507457D02*
X477612Y507417D01*
G01X477652Y508097D02*
Y507457D01*
G01X477752Y508197D02*
X477652Y508097D01*
G01Y507557D02*
X476682D01*
G01Y507767D02*
X477652D01*
G01Y507967D02*
X476682D01*
G01X481222Y509147D02*
Y509157D01*
G01X481212Y509077D02*
X481222Y509147D01*
G01X481212Y508817D02*
Y509077D01*
G01X481222Y508797D02*
X481212Y508817D01*
G01X481122Y508677D02*
X481222Y508797D01*
G01Y509167D02*
X481992D01*
G01X481952Y508967D02*
X481212D01*
G01X481192Y508767D02*
X481992D01*
G01X479832Y514597D02*
Y514737D01*
G01X482532Y511697D02*
X479832Y514597D01*
G01X479852Y514767D02*
X479062D01*
G01X479072Y514607D02*
X477912Y513417D01*
G01X479072Y514747D02*
Y514607D01*
G01X478062Y513557D02*
X478702D01*
G01X478892Y513767D02*
X478252D01*
G01X478442Y513967D02*
X479092D01*
G01X479282Y514167D02*
X478632D01*
G01X479522Y514267D02*
X481202Y512447D01*
G01X479372Y514267D02*
X479522D01*
G01X478732D02*
X479372D01*
G01X481192Y512467D02*
X481822D01*
G01X481632Y512667D02*
X481002D01*
G01X480822Y512857D02*
X481452D01*
G01X481262Y513057D02*
X480632D01*
G01X480542Y513167D02*
X481172D01*
G01X481072Y513267D02*
X480442D01*
G01X480352Y513357D02*
X480982D01*
G01X480892Y513467D02*
X480262D01*
G01X480172Y513557D02*
X480802D01*
G01X480702Y513667D02*
X480072D01*
G01X479982Y513767D02*
X480612D01*
G01X480522Y513857D02*
X479892D01*
G01X479802Y513967D02*
X480432D01*
G01X480332Y514057D02*
X479702D01*
G01X479612Y514167D02*
X480242D01*
G01X480152Y514267D02*
X479502D01*
G01X479872Y514557D02*
X479022D01*
G01X479072Y514667D02*
X479832D01*
G01X479952Y514857D02*
X478962D01*
G01X478872Y514967D02*
X480052D01*
G01X480152Y515057D02*
X478782D01*
G01X478692Y515167D02*
X479312D01*
G01X479522Y515087D02*
X480952Y516557D01*
G01X479382Y515087D02*
X479522D01*
G01X480852Y516467D02*
X481492D01*
G01X481302Y516267D02*
X480662D01*
G01X480572Y516167D02*
X481202D01*
G01X481112Y516057D02*
X480472D01*
G01X480372Y515967D02*
X481012D01*
G01X480922Y515857D02*
X480282D01*
G01X480182Y515767D02*
X480822D01*
G01X480722Y515667D02*
X480082D01*
G01X479992Y515557D02*
X480632D01*
G01X480532Y515467D02*
X479892D01*
G01X479802Y515357D02*
X480432D01*
G01X480342Y515267D02*
X479702D01*
G01X479602Y515167D02*
X480242D01*
G01X479962Y514467D02*
X478932D01*
G01X478832Y514357D02*
X480052D01*
G01X479122Y515357D02*
X478502D01*
G01X478312Y515557D02*
X478942D01*
G01X478752Y515767D02*
X478132D01*
G01X478742Y517097D02*
X481232D01*
G01X478692D02*
X478742D01*
G01X481242Y516857D02*
X481882D01*
G01X481692Y516667D02*
X481052D01*
G01X482172Y517167D02*
X478652D01*
G01X478692Y518127D02*
X478742D01*
G01X478652Y518087D02*
X478692Y518127D01*
G01X478652Y517137D02*
Y518087D01*
G01Y517967D02*
X481912D01*
G01X481942Y517767D02*
X478652D01*
G01Y517557D02*
X482562D01*
G01X482362Y517357D02*
X478652D01*
G01X478712Y522017D02*
Y522357D01*
G01X478752Y521967D02*
X478712Y522017D01*
G01X478702Y522357D02*
X481332D01*
G01X481202Y521967D02*
X478752D01*
G01X481252Y522017D02*
X481202Y521967D01*
G01X481252Y522297D02*
Y522017D01*
G01X478712Y522057D02*
X481252D01*
G01Y522167D02*
X478712D01*
G01Y522267D02*
X481252D01*
G01X480802Y522577D02*
Y522537D01*
G01X480702Y522677D02*
X480802Y522577D01*
G01X479262Y522677D02*
X480702D01*
G01X479162Y522577D02*
X479262Y522677D01*
G01X479162Y522537D02*
Y522577D01*
G01X479262Y522427D02*
X479162Y522537D01*
G01X480702Y522427D02*
X479262D01*
G01X480802Y522537D02*
X480702Y522427D01*
G01X480802Y522557D02*
X482772D01*
G01X482482Y522667D02*
X480712D01*
G01X478712Y523097D02*
Y523067D01*
G01X478752Y523137D02*
X478712Y523097D01*
G01X481202Y523137D02*
X478752D01*
G01X481252Y523097D02*
X481202Y523137D01*
G01X481252Y522997D02*
Y523097D01*
G01X478702Y523057D02*
X481252D01*
G01X479162Y522557D02*
X476332D01*
G01X476352Y522767D02*
X482112D01*
G01X481332Y522897D02*
X481252Y522997D01*
G01X481382Y522897D02*
X481332D01*
G01X481942Y522807D02*
X481382Y522897D01*
G01X482122Y522767D02*
X481942Y522807D01*
G01X481562Y522857D02*
X477692D01*
G01X481762Y522327D02*
X482172Y522237D01*
G01X481472Y522377D02*
X481762Y522327D01*
G01X481442Y522377D02*
X481472D01*
G01X481362Y522397D02*
X481442Y522377D01*
G01X481252Y522297D02*
X481362Y522397D01*
G01X481552Y522357D02*
X483142D01*
G01X481862Y518127D02*
X478742D01*
G01X478652Y518057D02*
X481912D01*
G01X481902Y518087D02*
X481862Y518127D01*
G01X482082Y517737D02*
X482282Y517937D01*
G01X481972Y517707D02*
X482082Y517737D01*
G01X481912Y517807D02*
X481972Y517707D01*
G01X481912Y517987D02*
Y517807D01*
G01Y517997D02*
Y517987D01*
G01X481902Y518087D02*
X481912Y517997D01*
G01X482112Y517767D02*
X482752D01*
G01X481912Y517857D02*
X478652D01*
G01X480762Y516357D02*
X481402D01*
G01X481322Y517037D02*
X481232Y517097D01*
G01X481302Y516927D02*
X481322Y517037D01*
G01X480952Y516557D02*
X481302Y516927D01*
G01X481592Y516557D02*
X480952D01*
G01X481282Y517057D02*
X482072D01*
G01X481982Y516967D02*
X481312D01*
G01X481152Y516767D02*
X481782D01*
G01X481352Y512967D02*
X480722D01*
G01X480912Y512767D02*
X481542D01*
G01X481722Y512557D02*
X481092D01*
G01X481282Y512357D02*
X481912D01*
G01X482002Y512267D02*
X481372D01*
G01X481462Y512167D02*
X482102D01*
G01X482192Y512057D02*
X481562D01*
G01X481652Y511967D02*
X482282D01*
G01X482472Y511767D02*
X481842D01*
G01X482022Y511557D02*
X483162D01*
G01X483152Y511467D02*
X482122D01*
G01X481262Y509337D02*
X481222Y509157D01*
G01X481262Y509347D02*
Y509337D01*
G01X481372Y509657D02*
X481262Y509347D01*
G01X481382Y509667D02*
X481372Y509657D01*
G01X481592Y509977D02*
X481382Y509667D01*
G01X481602Y509987D02*
X481592Y509977D01*
G01X481842Y510207D02*
X481602Y509987D01*
G01X481852Y510207D02*
X481842D01*
G01X481972Y510287D02*
X481852Y510207D01*
G01X481982Y510297D02*
X481972Y510287D01*
G01X482042Y510327D02*
X481982Y510297D01*
G01X482202Y510397D02*
X482042Y510327D01*
G01X481212Y509057D02*
X481972D01*
G01X482012Y508667D02*
X476462D01*
G01X482002Y508687D02*
X482012Y508667D01*
G01X481952Y508947D02*
X482002Y508687D01*
G01X481952Y508957D02*
Y508947D01*
G01Y508977D02*
Y508957D01*
G01X476502Y508357D02*
X482242D01*
G01X482162Y508427D02*
X482102Y508517D01*
G01X482172Y508417D02*
X482162Y508427D01*
G01X482182Y508407D02*
X482172Y508417D01*
G01X482022Y508657D02*
X482012Y508667D01*
G01X482102Y508527D02*
X482022Y508657D01*
G01X481972Y508857D02*
X481212D01*
G01X481242Y509267D02*
X482012D01*
G01X482002Y509237D02*
X481952Y508977D01*
G01X482012Y509257D02*
X482002Y509237D01*
G01X482232Y508987D02*
X482242Y509007D01*
G01X482182Y509517D02*
X482402Y509677D01*
G01X482172Y509507D02*
X482182Y509517D01*
G01X482162Y509487D02*
X482172Y509507D01*
G01X482022Y509277D02*
X482162Y509487D01*
G01X482012Y509257D02*
X482022Y509277D01*
G01X482242Y509557D02*
X481342D01*
G01X481302Y509467D02*
X482142D01*
G01X482072Y509357D02*
X481262D01*
G01X481442Y509767D02*
X482702D01*
G01X482112Y510357D02*
X483782D01*
G01X483872Y510267D02*
X481932D01*
G01X481692Y510057D02*
X484062D01*
G01X484242Y509857D02*
X481522D01*
G01X482102Y508467D02*
X482142D01*
G01X482182Y508407D02*
X482402Y508247D01*
G01X481972Y507667D02*
X483522D01*
G01X483682Y507767D02*
X481792D01*
G01X481352Y508197D02*
X477752D01*
G01X481432Y508167D02*
X481352Y508197D01*
G01X481442Y508157D02*
X481432Y508167D01*
G01X481442Y508147D02*
Y508157D01*
G01X481482Y508077D02*
X481442Y508147D01*
G01X481492Y508077D02*
X481482D01*
G01X481502Y508067D02*
X481492Y508077D01*
G01X481572Y507967D02*
X481502Y508067D01*
G01X481582Y507957D02*
X481572Y507967D01*
G01X481812Y507737D02*
X481582Y507957D01*
G01Y507967D02*
X483922D01*
G01X481832Y507727D02*
X481812Y507737D01*
G01X482632Y507427D02*
X482972Y507437D01*
G01X482622Y507427D02*
X482632D01*
G01X482612D02*
X482622D01*
G01X482452Y507447D02*
X482612Y507427D01*
G01X482432Y507447D02*
X482452D01*
G01X481832Y507727D02*
X482432Y507447D01*
G01X483082Y507467D02*
X482412D01*
G01Y508237D02*
X482402Y508247D01*
G01X482432Y508237D02*
X482412D01*
G01X482602Y508177D02*
X482432Y508237D01*
G01X482822Y508167D02*
X482842D01*
G01X482692D02*
X482822D01*
G01X482622Y508177D02*
X482692Y508167D01*
G01X482602Y508177D02*
X482622D01*
G01X482262Y508797D02*
X482232Y508987D01*
G01X482272Y508767D02*
X482262Y508797D01*
G01X482442Y508547D02*
X482272Y508767D01*
G01X482462Y508537D02*
X482442Y508547D01*
G01X482632Y508457D02*
X482462Y508537D01*
G01X482642Y508457D02*
X482632D01*
G01X482682Y508447D02*
X482642Y508457D01*
G01X482742Y508447D02*
X482682D01*
G01X482762D02*
X482742D01*
G01X482792Y509477D02*
X482802D01*
G01X482702D02*
X482792D01*
G01X482682Y509467D02*
X482702Y509477D01*
G01X482372Y509307D02*
X482682Y509467D01*
G01X482352Y509287D02*
X482372Y509307D01*
G01X482242Y509007D02*
X482352Y509287D01*
G01X482412Y509687D02*
X482402Y509677D01*
G01X482432Y509687D02*
X482412D01*
G01X482602Y509747D02*
X482432Y509687D01*
G01X482622Y509747D02*
X482602D01*
G01X482692Y509757D02*
X482622Y509747D01*
G01X482712Y509767D02*
X482692Y509757D01*
G01X482772Y509767D02*
X482712D01*
G01X482802Y509757D02*
X482772Y509767D01*
G01X482382Y509667D02*
X481382D01*
G01X482292Y509147D02*
X483232D01*
G01X483252Y508947D02*
X482242D01*
G01X482292Y508747D02*
X483202D01*
G01X483022Y508547D02*
X482452D01*
G01X482762Y508447D02*
X482892Y508467D01*
G01X483092Y509337D02*
X482442D01*
G01X482842Y509757D02*
X483042Y509707D01*
G01X482802Y509757D02*
X482842D01*
G01X482292Y510427D02*
X482202Y510397D01*
G01X482302Y510437D02*
X482292Y510427D01*
G01X482442Y510467D02*
X482302Y510437D01*
G01X482522Y510487D02*
X482442Y510467D01*
G01X482302Y511267D02*
X481202Y512447D01*
G01X482562Y510987D02*
X482302Y511267D01*
G01X482592Y510937D02*
X482562Y510987D01*
G01X482622Y510787D02*
X482592Y510937D01*
G01X482632Y510767D02*
X482622Y510787D01*
G01X482632Y510747D02*
Y510767D01*
G01X482612Y510577D02*
X482632Y510747D01*
G01X482612Y510567D02*
Y510577D01*
G01X482522Y510487D02*
X482612Y510567D01*
G01X481742Y511857D02*
X482382D01*
G01X482702Y511757D02*
X483212Y517987D01*
G01X482642Y511677D02*
X482702Y511757D01*
G01X482532Y511697D02*
X482642Y511677D01*
G01X482302Y517967D02*
X482282Y517937D01*
G01X482942Y517967D02*
X482302D01*
G01D02*
X483112Y518807D01*
G01X482692Y518357D02*
X484952D01*
G01Y518167D02*
X482502D01*
G01X482202Y517857D02*
X482842D01*
G01X482652Y517667D02*
X478652D01*
G01Y517467D02*
X482462D01*
G01X482262Y517267D02*
X478652D01*
G01X482872Y513767D02*
X483332D01*
G01X483322Y513557D02*
X482852D01*
G01X482832Y513357D02*
X483302D01*
G01X483292Y513167D02*
X482822D01*
G01X482802Y512967D02*
X483272D01*
G01X483262Y512767D02*
X482792D01*
G01X482772Y512557D02*
X483242D01*
G01X483222Y512357D02*
X482762D01*
G01X482742Y512167D02*
X483202D01*
G01X483192Y511967D02*
X482722D01*
G01X482702Y511767D02*
X483172D01*
G01X483132Y511267D02*
X482302D01*
G01X482492Y511057D02*
X483132D01*
G01X483312Y510857D02*
X482612D01*
G01X482622Y510667D02*
X483502D01*
G01X482452Y522157D02*
X482172Y522237D01*
G01X482462Y522147D02*
X482452Y522157D01*
G01X482572Y522117D02*
X482462Y522147D01*
G01X482572Y522107D02*
Y522117D01*
G01X482682Y522067D02*
X482572Y522107D01*
G01X482692Y522057D02*
X482682Y522067D01*
G01X483552Y522057D02*
X482692D01*
G01X482412Y522167D02*
X483442D01*
G01X482242Y522727D02*
X482122Y522767D01*
G01X482352Y522707D02*
X482242Y522727D01*
G01X482592Y522627D02*
X482352Y522707D01*
G01X482702Y522587D02*
X482592Y522627D01*
G01X482762Y522567D02*
X482702Y522587D01*
G01X482052Y522267D02*
X483302D01*
G01X482982Y522467D02*
X480732D01*
G01X483302Y521507D02*
X483212Y521457D01*
G01X483292Y521607D02*
X483302Y521507D01*
G01X483222Y521717D02*
X483292Y521607D01*
G01X483202Y521737D02*
X483222Y521717D01*
G01X482902Y521957D02*
X483202Y521737D01*
G01X482892Y521967D02*
X482902Y521957D01*
G01X482882Y521967D02*
X482892D01*
G01X482692Y522057D02*
X482882Y521967D01*
G01X483222Y521467D02*
X484942D01*
G01X484922Y521667D02*
X483262D01*
G01X483032Y521857D02*
X484842D01*
G01X484952Y519857D02*
X483172D01*
G01X483142Y518837D02*
X483112Y518807D01*
G01X483172Y518897D02*
X483142Y518837D01*
G01X483172Y519917D02*
Y518897D01*
G01X483072Y518767D02*
X483742D01*
G01X483912Y518967D02*
X483172D01*
G01Y519167D02*
X484102D01*
G01X484292Y519357D02*
X483172D01*
G01Y519467D02*
X484952D01*
G01Y519667D02*
X483172D01*
G01X483282Y519997D02*
X483382Y520097D01*
G01X483212Y519997D02*
X483282D01*
G01X483172Y519957D02*
X483212Y519997D01*
G01X483172Y519917D02*
Y519957D01*
G01X482882Y518557D02*
X484952D01*
G01X483672Y517857D02*
X483202D01*
G01X483042Y518067D02*
X479832Y514737D01*
G01X483152Y518087D02*
X483042Y518067D01*
G01X483212Y517987D02*
X483152Y518087D01*
G01X482932Y514557D02*
X483402D01*
G01X483412Y514667D02*
X482942D01*
G01X482962Y514857D02*
X483432D01*
G01X483442Y515057D02*
X482982D01*
G01X482992Y515267D02*
X483462D01*
G01X483472Y515467D02*
X483012D01*
G01X483022Y515667D02*
X483492D01*
G01X483512Y515857D02*
X483042D01*
G01X483062Y516057D02*
X483522D01*
G01X483542Y516267D02*
X483072D01*
G01X483092Y516467D02*
X483562D01*
G01X483572Y516667D02*
X483112D01*
G01X483122Y516857D02*
X483592D01*
G01X483602Y517057D02*
X483142D01*
G01X483152Y517267D02*
X483622D01*
G01X483642Y517467D02*
X483172D01*
G01X483192Y517667D02*
X483652D01*
G01X483042Y518057D02*
X482402D01*
G01X482922Y514357D02*
X483392D01*
G01X483372Y514167D02*
X482902D01*
G01X482892Y513967D02*
X483352D01*
G01X483342Y513857D02*
X482882D01*
G01X482862Y513667D02*
X483332D01*
G01X483312Y513467D02*
X482842D01*
G01X482832Y513267D02*
X483302D01*
G01X483282Y513057D02*
X482812D01*
G01X482802Y512857D02*
X483262D01*
G01X483252Y512667D02*
X482782D01*
G01X482762Y512467D02*
X483232D01*
G01X483212Y512267D02*
X482752D01*
G01X482732Y512057D02*
X483202D01*
G01X483182Y511857D02*
X482712D01*
G01X483172Y511667D02*
X481932D01*
G01X482212Y511357D02*
X483142D01*
G01X483132Y511167D02*
X482402D01*
G01X482572Y510967D02*
X483212D01*
G01X483152Y511027D02*
X484112Y510007D01*
G01X484432Y509667D02*
X483102D01*
G01X483082Y509687D02*
X483042Y509707D01*
G01X483082Y509687D02*
X483392Y509427D01*
G01X483162Y509247D02*
X482332D01*
G01X482252Y509047D02*
X483242D01*
G01X483052Y509377D02*
X482802Y509477D01*
G01X483072Y509367D02*
X483052Y509377D01*
G01X483222Y509167D02*
X483072Y509367D01*
G01X483232Y509137D02*
X483222Y509167D01*
G01X482892Y509447D02*
X482622D01*
G01X482912Y508467D02*
X482892D01*
G01X483132Y508607D02*
X482912Y508467D01*
G01X483142Y508627D02*
X483132Y508607D01*
G01X483252Y508857D02*
X483142Y508627D01*
G01X483262Y508877D02*
X483252Y508857D01*
G01X483232Y509137D02*
X483262Y508877D01*
G01X483102Y508267D02*
X484122D01*
G01X482982Y507437D02*
X482972D01*
G01X483272Y507507D02*
X482982Y507437D01*
G01X483282Y507517D02*
X483272Y507507D01*
G01X483792Y507827D02*
X483282Y507517D01*
G01X483042Y508217D02*
X483082Y508237D01*
G01X482842Y508167D02*
X483042Y508217D01*
G01X483152Y508647D02*
X482372D01*
G01X482252Y508837D02*
X483252D01*
G01X483142Y511047D02*
X483122Y511117D01*
G01X483152Y511037D02*
X483142Y511047D01*
G01X483152Y511027D02*
Y511037D01*
G01X482912Y522507D02*
X482762Y522567D01*
G01X482922Y522497D02*
X482912Y522507D01*
G01X484172Y522217D02*
X484232Y522227D01*
G01X484162Y522217D02*
X484172D01*
G01X484052Y522187D02*
X484162Y522217D01*
G01X484042Y522187D02*
X484052D01*
G01X483912Y522137D02*
X484042Y522187D01*
G01X483912Y522127D02*
Y522137D01*
G01X483852Y522097D02*
X483912Y522127D01*
G01X483832Y522077D02*
X483852Y522097D01*
G01X483772Y522027D02*
X483832Y522077D01*
G01X483752Y522007D02*
X483772Y522027D01*
G01X483612Y522007D02*
X483752D01*
G01X483432Y522177D02*
X483612Y522007D01*
G01X483422Y522187D02*
X483432Y522177D01*
G01X482922Y522497D02*
X483422Y522187D01*
G01X483982Y522167D02*
X484502D01*
G01X484552Y520857D02*
X483392D01*
G01X483442Y520807D02*
X483382Y520097D01*
G01X483352Y520057D02*
X483902D01*
G01X484192Y520787D02*
X484222Y520777D01*
G01X484112Y520797D02*
X484192Y520787D01*
G01X484042Y520817D02*
X484112Y520797D01*
G01X484032Y520817D02*
X484042D01*
G01X483902Y520727D02*
X484032Y520817D01*
G01X483852Y520117D02*
X483902Y520727D01*
G01X483952Y520007D02*
X483852Y520117D01*
G01X483952Y520767D02*
X483442D01*
G01X483342Y520917D02*
X475992D01*
G01X483442Y520807D02*
X483342Y520917D01*
G01X482982Y518667D02*
X483802D01*
G01X483772Y518817D02*
X484322Y519397D01*
G01X483742Y518767D02*
X483772Y518817D01*
G01X483742Y518727D02*
Y518767D01*
G01X483842Y518617D02*
X483742Y518727D01*
G01X484202Y519267D02*
X483172D01*
G01Y519057D02*
X484002D01*
G01X483812Y518857D02*
X483152D01*
G01X483172Y518057D02*
X483702D01*
G01X483692Y518047D02*
X483122Y511117D01*
G01X483402Y510767D02*
X482632D01*
G01X482602Y510557D02*
X483592D01*
G01X483682Y510467D02*
X482412D01*
G01X481802Y510167D02*
X483962D01*
G01X484152Y509967D02*
X481582D01*
G01X481432Y508167D02*
X484062D01*
G01X483882Y507917D02*
X483792Y507827D01*
G01X483942Y507987D02*
X483882Y507917D01*
G01X484072Y508177D02*
X483942Y507987D01*
G01X483832Y507857D02*
X481682D01*
G01X481502Y508057D02*
X483992D01*
G01X484192Y508427D02*
X484252Y508597D01*
G01X484152Y508327D02*
X484192Y508427D01*
G01X484152Y508317D02*
Y508327D01*
G01X484082Y508187D02*
X484152Y508317D01*
G01X484072Y508177D02*
X484082Y508187D01*
G01X484242Y508557D02*
X483427D01*
G01X483432D02*
X483492D01*
G01X483392Y508497D02*
X483082Y508237D01*
G01X483422Y508547D02*
X483392Y508497D01*
G01X483222Y508357D02*
X484172D01*
G01X484202Y508467D02*
X483412D01*
G01X484172D02*
X484202D01*
G01X483422Y509377D02*
X483392Y509427D01*
G01X483542Y508987D02*
X483422Y509377D01*
G01X483542Y508927D02*
Y508987D01*
G01X483422Y508547D02*
X483542Y508927D01*
G01X483352Y509467D02*
X484612D01*
G01X484802Y509267D02*
X483462D01*
G01X483522Y509057D02*
X484982D01*
G01X484282Y508857D02*
X483522D01*
G01X483462Y508667D02*
X484262D01*
G01X483352Y507557D02*
X482192D01*
G01X482892Y514057D02*
X483362D01*
G01X483382Y514267D02*
X482912D01*
G01X482932Y514467D02*
X483392D01*
G01X483422Y514767D02*
X482952D01*
G01X482962Y514967D02*
X483432D01*
G01X483452Y515167D02*
X482982D01*
G01X483002Y515357D02*
X483462D01*
G01X483482Y515557D02*
X483022D01*
G01X483032Y515767D02*
X483502D01*
G01X483522Y515967D02*
X483052D01*
G01X483062Y516167D02*
X483532D01*
G01X483552Y516357D02*
X483082D01*
G01X483102Y516557D02*
X483562D01*
G01X483582Y516767D02*
X483112D01*
G01X483132Y516967D02*
X483592D01*
G01X483612Y517167D02*
X483152D01*
G01X483162Y517357D02*
X483632D01*
G01X483652Y517557D02*
X483182D01*
G01X483192Y517767D02*
X483662D01*
G01X483682Y517967D02*
X483212D01*
G01X483692Y518047D02*
X483782Y518137D01*
G01X484112Y519997D02*
X484232D01*
G01X483952Y520007D02*
X484112Y519997D01*
G01X483862Y520167D02*
X483392D01*
G01X483402Y520267D02*
X483872D01*
G01Y520357D02*
X483412D01*
G01Y520467D02*
X483882D01*
G01X483892Y520557D02*
X483422D01*
G01X483432Y520667D02*
X483902D01*
G01X484302Y522227D02*
X484232D01*
G01X484312Y522217D02*
X484302Y522227D01*
G01X484572Y522147D02*
X484312Y522217D01*
G01X484582Y522137D02*
X484572Y522147D01*
G01X484782Y521967D02*
X484582Y522137D01*
G01X484792Y521957D02*
X484782Y521967D01*
G01X484912Y521727D02*
X484792Y521957D01*
G01X484922Y521707D02*
X484912Y521727D01*
G01X484942Y521427D02*
X484922Y521707D01*
G01X484942Y521417D02*
Y521427D01*
G01X484862Y521157D02*
X484942Y521417D01*
G01X484852Y521147D02*
X484862Y521157D01*
G01X484692Y520947D02*
X484852Y521147D01*
G01X484682Y520927D02*
X484692Y520947D01*
G01X484452Y520807D02*
X484682Y520927D01*
G01X484432Y520807D02*
X484452D01*
G01X484312Y520787D02*
X484432Y520807D01*
G01X484302Y520787D02*
X484312D01*
G01X484242Y520777D02*
X484302Y520787D01*
G01X484222Y520777D02*
X484242D01*
G01X483812Y522057D02*
X484672D01*
G01X484782Y521967D02*
X482892D01*
G01X483172Y521767D02*
X484892D01*
G01X484932Y521557D02*
X483302D01*
G01X484792Y521057D02*
X474682D01*
G01Y521267D02*
X484892D01*
G01X485202Y520967D02*
X485832D01*
G01X485932Y521057D02*
X485302D01*
G01X485392Y521167D02*
X486032D01*
G01X486122Y521267D02*
X485492D01*
G01X485592Y521357D02*
X486222D01*
G01X486312Y521467D02*
X485692D01*
G01X485782Y521557D02*
X486412D01*
G01X486512Y521667D02*
X485882D01*
G01X485982Y521767D02*
X486612D01*
G01X486802Y521967D02*
X486172D01*
G01X486362Y522167D02*
X486992D01*
G01X485742Y520857D02*
X485112D01*
G01X485012Y520767D02*
X485642D01*
G01X485542Y520667D02*
X484912D01*
G01X484812Y520557D02*
X485452D01*
G01X485352Y520467D02*
X484722D01*
G01X484622Y520357D02*
X485262D01*
G01X485162Y520267D02*
X484532D01*
G01X484432Y520167D02*
X485062D01*
G01X484912Y518137D02*
X483782D01*
G01X484952Y518157D02*
X484912Y518137D01*
G01X484952Y518167D02*
Y518157D01*
G01Y519987D02*
Y518167D01*
G01Y519997D02*
Y519987D01*
G01X484982Y520077D02*
X484952Y519997D01*
G01X484432Y519417D02*
X484322Y519397D01*
G01X484492Y519317D02*
X484432Y519417D01*
G01X484492Y518717D02*
Y519317D01*
G01X484392Y518617D02*
X484492Y518717D01*
G01X483842Y518617D02*
X484392D01*
G01X484462Y519357D02*
X484952D01*
G01Y519267D02*
X484492D01*
G01Y519167D02*
X484952D01*
G01Y519057D02*
X484492D01*
G01Y518967D02*
X484952D01*
G01Y518857D02*
X484492D01*
G01Y518767D02*
X484952D01*
G01Y518667D02*
X484442D01*
G01X484952Y518467D02*
X482782D01*
G01X482592Y518267D02*
X484952D01*
G01Y519557D02*
X483172D01*
G01Y519767D02*
X484952D01*
G01Y519967D02*
X483172D01*
G01X484232Y519997D02*
X484302Y520027D01*
G01X484332Y520057D02*
X484972D01*
G01X484332Y509767D02*
X482782D01*
G01X483222Y509557D02*
X484522D01*
G01X484702Y509357D02*
X483432D01*
G01X483482Y509167D02*
X484892D01*
G01X485082Y508967D02*
X484392D01*
G01X484252Y508617D02*
Y508597D01*
G01X484292Y508887D02*
X484252Y508617D01*
G01X484352Y508967D02*
X484292Y508887D01*
G01X484272Y508767D02*
X483492D01*
G01X484352Y508967D02*
X484462Y508947D01*
G01X483542Y508967D02*
X484352D01*
G01X484542Y508857D02*
X485172D01*
G01X485262Y508767D02*
X484632D01*
G01X484722Y508667D02*
X485362D01*
G01X485412Y508557D02*
X485452D01*
G01X485462D02*
X484822D01*
G01X484912Y508467D02*
X485547D01*
G01X485542D02*
X485492D01*
G01X485647Y508357D02*
X485002D01*
G01X485092Y508267D02*
X485732D01*
G01X485822Y508167D02*
X485187D01*
G01X485287Y508057D02*
X485922D01*
G01X486012Y507967D02*
X485372D01*
G01X485477Y507857D02*
X486102D01*
G01X486202Y507767D02*
X485562D01*
G01X485652Y507667D02*
X486292D01*
G01X486382Y507557D02*
X485742D01*
G01X485832Y507467D02*
X486482D01*
G01X486662Y507267D02*
X486022D01*
G01X485932Y507357D02*
X486572D01*
G01X486752Y507167D02*
X486112D01*
G01X486212Y507057D02*
X486852D01*
G01X486942Y506967D02*
X486302D01*
G01X486392Y506857D02*
X487032D01*
G01X487132Y506767D02*
X486482D01*
G01X486582Y506667D02*
X487222D01*
G01X487312Y506557D02*
X486672D01*
G01X486762Y506467D02*
X487412D01*
G01X487502Y506357D02*
X486862D01*
G01X486952Y506267D02*
X487592D01*
G01X487782Y506057D02*
X487142D01*
G01X487322Y505857D02*
X487932D01*
G01X487922Y505917D02*
X484112Y510007D01*
G01X487592Y505577D02*
X487612Y505557D01*
G01X484462Y508947D02*
X487592Y505577D01*
G01X487512Y505667D02*
X487732D01*
G01X470652Y505897D02*
X476072Y511507D01*
G01X470622Y505867D02*
X470652Y505897D01*
G01X470632Y505847D02*
X470622Y505867D01*
G01X470942Y505577D02*
X470632Y505847D01*
G01X470972Y505567D02*
X470942Y505577D01*
G01X470992D02*
X470972Y505567D01*
G01X476112Y510877D02*
X470992Y505577D01*
G01X471072Y505667D02*
X470842D01*
G01X470722Y505767D02*
X471172D01*
G01X471272Y505857D02*
X470622D01*
G01X470712Y505967D02*
X471372D01*
G01X471462Y506057D02*
X470812D01*
G01X470902Y506167D02*
X471562D01*
G01X471652Y506267D02*
X471002D01*
G01X471092Y506357D02*
X471752D01*
G01X471852Y506467D02*
X471192D01*
G01X471292Y506557D02*
X471942D01*
G01X472042Y506667D02*
X471392D01*
G01X471482Y506767D02*
X472142D01*
G01X472232Y506857D02*
X471582D01*
G01X471682Y506967D02*
X472332D01*
G01X472432Y507057D02*
X471772D01*
G01X471872Y507167D02*
X472522D01*
G01X484302Y520027D02*
X488882Y524767D01*
G01X488912Y524157D02*
X484982Y520077D01*
G01X486072Y521857D02*
X486702D01*
G01X486892Y522057D02*
X486262D01*
G01X486462Y522267D02*
X487092D01*
G01X487192Y522357D02*
X486562D01*
G01X486652Y522467D02*
X487282D01*
G01X487382Y522557D02*
X486752D01*
G01X486852Y522667D02*
X487472D01*
G01X487572Y522767D02*
X486942D01*
G01X487132Y522967D02*
X487762D01*
G01X487962Y523167D02*
X487332D01*
G01X487522Y523357D02*
X488152D01*
G01X488052Y523267D02*
X487432D01*
G01X487622Y523467D02*
X488242D01*
G01X488342Y523557D02*
X487712D01*
G01X487812Y523667D02*
X488442D01*
G01X488542Y523767D02*
X487912D01*
G01X488002Y523857D02*
X488632D01*
G01X488732Y523967D02*
X488102D01*
G01X488202Y524057D02*
X488822D01*
G01X488932Y524267D02*
X488392D01*
G01X488922Y524187D02*
X488932Y524267D01*
G01X488912Y524157D02*
X488922Y524187D01*
G01X488302Y524167D02*
X488912D01*
G01X488932Y524757D02*
X488882Y524767D01*
G01X488932Y524267D02*
Y524757D01*
G01X488872Y524767D02*
X488912D01*
G01X488932Y524667D02*
X488782D01*
G01X488682Y524557D02*
X488932D01*
G01Y524467D02*
X488582D01*
G01X488492Y524357D02*
X488932D01*
G01X487862Y523057D02*
X487232D01*
G01X487042Y522857D02*
X487672D01*
G01X487692Y506167D02*
X487042D01*
G01X487232Y505967D02*
X487872D01*
G01X487642Y505577D02*
X487612Y505557D01*
G01X487932Y505867D02*
X487642Y505577D01*
G01X487942Y505887D02*
X487932Y505867D01*
G01Y505897D02*
X487942Y505887D01*
G01X487922Y505917D02*
X487932Y505897D01*
G01X487412Y505767D02*
X487832D01*
G54D12*
G01X63437Y191761D02*
X69437D01*
G01X57937Y252161D02*
Y257161D01*
G01X64979Y370654D02*
Y365354D01*
X75179D01*
Y370654D01*
G01X63437Y644517D02*
X69437D01*
G01X57937Y704917D02*
Y709917D01*
G01X64979Y823409D02*
Y818109D01*
X75179D01*
Y823409D01*
G01X63437Y1097273D02*
X69437D01*
G01X57937Y1157673D02*
Y1162673D01*
G01X64979Y1276165D02*
Y1270865D01*
X75179D01*
Y1276165D01*
G01X96737Y280661D02*
X91737D01*
G01X96737Y733417D02*
X91737D01*
G01X107000Y978000D02*
Y973000D01*
G01Y970400D02*
Y965400D01*
G01X96737Y1186173D02*
X91737D01*
G01X333500Y488631D02*
X127500D01*
Y421631D01*
X333500D01*
Y488631D01*
G01X187649Y191761D02*
X193649D01*
G01X182149Y252161D02*
Y257161D01*
G01X220949Y280661D02*
X215949D01*
G01X189191Y370654D02*
Y365354D01*
X199391D01*
Y370654D01*
G01X173700Y566000D02*
Y561000D01*
G01Y558400D02*
Y553400D01*
G01X191749Y634017D02*
X197749D01*
G01X220949Y733417D02*
X215949D01*
G01X182149Y704917D02*
Y709917D01*
G01X189191Y823409D02*
Y818109D01*
X199391D01*
Y823409D01*
G01X187651Y1098635D02*
X193651D01*
G01X182149Y1157673D02*
Y1162673D01*
G01X220949Y1186173D02*
X215949D01*
G01X189191Y1276165D02*
Y1270865D01*
X199391D01*
Y1276165D01*
G01X311862Y191761D02*
X317862D01*
G01X306362Y252161D02*
Y257161D01*
G01X313404Y370654D02*
Y365354D01*
X323604D01*
Y370654D01*
G01X311862Y644517D02*
X317862D01*
G01X306362Y704917D02*
Y709917D01*
G01X313404Y823409D02*
Y818109D01*
X323604D01*
Y823409D01*
G01X311862Y1097273D02*
X317862D01*
G01X306362Y1157673D02*
Y1162673D01*
G01X313404Y1276165D02*
Y1270865D01*
X323604D01*
Y1276165D01*
G01X363248Y-425196D02*
Y-505196D01*
G01D02*
X1639148D01*
G01X359248Y-409196D02*
G02I-12000J0D01*
G01X354098D02*
G02I-6850J0D01*
G01X347248Y-425196D02*
Y-393196D01*
G01X363248Y-425196D02*
X1639148D01*
G01X363248Y-460696D02*
X1639148D01*
G01X363248Y-409196D02*
X331248D01*
G01X322281Y83615D02*
X322271Y93115D01*
G01X345162Y280661D02*
X340162D01*
G01X345162Y733417D02*
X340162D01*
G01X345162Y1186173D02*
X340162D01*
G01X436074Y191761D02*
X442074D01*
G01X430574Y252161D02*
Y257161D01*
G01X437617Y370654D02*
Y365354D01*
X447817D01*
Y370654D01*
G01X436074Y644517D02*
X442074D01*
G01X430574Y704917D02*
Y709917D01*
G01X437617Y823409D02*
Y818109D01*
X447817D01*
Y823409D01*
G01X457773Y1100726D02*
Y1094726D01*
G01X445538Y1158196D02*
Y1163196D01*
G01X437617Y1276165D02*
Y1270865D01*
X447817D01*
Y1276165D01*
G01X469374Y280661D02*
X464374D01*
G01X469374Y733417D02*
X464374D01*
G01X469374Y1186173D02*
X464374D01*
G01X554787Y252161D02*
Y257161D01*
G01X516517Y564331D02*
X510517D01*
G01X554787Y704917D02*
Y709917D01*
G01Y1157673D02*
Y1162673D01*
G01X560287Y191761D02*
X566287D01*
G01X593587Y280661D02*
X588587D01*
G01X561829Y370654D02*
Y365354D01*
X572029D01*
Y370654D01*
G01X565779Y515331D02*
X560779D01*
G01X560287Y644517D02*
X566287D01*
G01X593587Y733417D02*
X588587D01*
G01X561829Y823409D02*
Y818109D01*
X572029D01*
Y823409D01*
G01X560287Y1097273D02*
X566287D01*
G01X593587Y1186173D02*
X588587D01*
G01X561829Y1276165D02*
Y1270865D01*
X572029D01*
Y1276165D01*
G01X684500Y191761D02*
X690500D01*
G01X679000Y252161D02*
Y257161D01*
G01X686042Y370654D02*
Y365354D01*
X696242D01*
Y370654D01*
G01X688600Y644517D02*
X694600D01*
G01X679000Y704917D02*
Y709917D01*
G01X686042Y823409D02*
Y818109D01*
X696242D01*
Y823409D01*
G01X684500Y1097273D02*
X690500D01*
G01X679000Y1157673D02*
Y1162673D01*
G01X686042Y1276165D02*
Y1270865D01*
X696242D01*
Y1276165D01*
G01X720748Y-425196D02*
Y-505196D01*
G01X717800Y280661D02*
X712800D01*
G01X717800Y733417D02*
X712800D01*
G01X717800Y1186173D02*
X712800D01*
G01X830162Y46447D02*
Y41447D01*
G01X858248Y-425196D02*
Y-505196D01*
G01X884279Y51570D02*
Y68170D01*
G01X865730Y45876D02*
Y40876D01*
G01X865336Y73472D02*
Y78472D01*
G01X882700Y697000D02*
X877700D01*
G01X891776Y1377283D02*
X899776D01*
G01X874221Y1446161D02*
X874211Y1455661D01*
G01X879500Y1535468D02*
X885500D01*
G01X927140Y948000D02*
X927150Y938500D01*
G01X929640Y1017500D02*
X929650Y1008000D01*
G01X935000Y1501700D02*
X930000D01*
G01X973248Y-425196D02*
Y-505196D01*
G01X950860Y918000D02*
X950850Y927500D01*
G01X945860Y988500D02*
X945850Y998000D01*
G01X1018000Y917500D02*
Y925500D01*
G01X995054Y988840D02*
X995044Y998340D01*
G01X1023360Y1080000D02*
X1023350Y1089500D01*
G01X1090700Y-54800D02*
X1084700D01*
G01X1070860Y1081000D02*
X1070850Y1090500D01*
G01X1078000Y1198162D02*
X1082000D01*
G01X1078000Y1240682D02*
X1082000D01*
G01X1078000Y1297375D02*
X1082000D01*
G01X1078000Y1354068D02*
X1082000D01*
G01X1060008Y1533820D02*
Y1559020D01*
G01X1113860Y1081000D02*
X1113850Y1090500D01*
G01X1175468Y85468D02*
Y68868D01*
G01X1183868Y719200D02*
Y714200D01*
G01X1143500Y1198162D02*
X1147500D01*
G01X1143500Y1240682D02*
X1147500D01*
G01X1143500Y1297375D02*
X1147500D01*
G01X1143500Y1354068D02*
X1147500D01*
G01X1193268Y60668D02*
Y55668D01*
G01X1271648Y-425196D02*
Y-505196D01*
G01X1235648Y370654D02*
Y365354D01*
X1245848D01*
Y370654D01*
G01X1235648Y823409D02*
Y818109D01*
X1245848D01*
Y823409D01*
G01X1235648Y1276165D02*
Y1270865D01*
X1245848D01*
Y1276165D01*
G01X1320481Y92235D02*
X1320471Y101735D01*
G01X1310500Y291161D02*
X1315500D01*
G01X1302500D02*
X1307500D01*
G01X1310500Y743917D02*
X1315500D01*
G01X1302500D02*
X1307500D01*
G01X1310500Y1196673D02*
X1315500D01*
G01X1302500D02*
X1307500D01*
G01X1336100Y191161D02*
Y185161D01*
G01X1359861Y370654D02*
Y365354D01*
X1370061D01*
Y370654D01*
G01X1336100Y643917D02*
Y637917D01*
G01X1359861Y823409D02*
Y818109D01*
X1370061D01*
Y823409D01*
G01X1336100Y1096673D02*
Y1090673D01*
G01X1359861Y1276165D02*
Y1270865D01*
X1370061D01*
Y1276165D01*
G01X1426713Y291161D02*
X1431713D01*
G01X1426713Y743917D02*
X1431713D01*
G01X1426713Y1196673D02*
X1431713D01*
G01X1441648Y-425196D02*
Y-505196D01*
G01X1460313Y191161D02*
Y185161D01*
G01X1434713Y291161D02*
X1439713D01*
G01X1462200Y577100D02*
X1467200D01*
G01X1460313Y643917D02*
Y637917D01*
G01X1434713Y743917D02*
X1439713D01*
G01X1460313Y1096673D02*
Y1090673D01*
G01X1434713Y1196673D02*
X1439713D01*
G01X1484073Y370654D02*
Y365354D01*
X1494273D01*
Y370654D01*
G01X1517297Y540911D02*
X1511297D01*
G01X1484073Y823409D02*
Y818109D01*
X1494273D01*
Y823409D01*
G01X1484073Y1276165D02*
Y1270865D01*
X1494273D01*
Y1276165D01*
G01X1558925Y291161D02*
X1563925D01*
G01X1550925D02*
X1555925D01*
G01X1558925Y743917D02*
X1563925D01*
G01X1550925D02*
X1555925D01*
G01X1550925Y1196673D02*
X1555925D01*
G01X1558925D02*
X1563925D01*
G01X1584525Y191161D02*
Y185161D01*
G01X1608286Y370654D02*
Y365354D01*
X1618486D01*
Y370654D01*
G01X1579525Y645917D02*
Y639917D01*
G01X1608286Y823409D02*
Y818109D01*
X1618486D01*
Y823409D01*
G01X1593625Y1090373D02*
Y1084373D01*
G01X1608286Y1276165D02*
Y1270865D01*
X1618486D01*
Y1276165D01*
G01X1639148Y-425196D02*
Y-505196D01*
G01X1667148Y-409196D02*
G02I-12000J0D01*
G01X1661998D02*
G02I-6850J0D01*
G01X1655148Y-425196D02*
Y-393196D01*
G01X1671148Y-409196D02*
X1639148D01*
G01X1708738Y191161D02*
Y185161D01*
G01X1683138Y291161D02*
X1688138D01*
G01X1675138D02*
X1680138D01*
G01X1708738Y643917D02*
Y637917D01*
G01X1683138Y743917D02*
X1688138D01*
G01X1675138D02*
X1680138D01*
G01X1708738Y1096673D02*
Y1090673D01*
G01X1683138Y1196673D02*
X1688138D01*
G01X1675138D02*
X1680138D01*
G01X1732498Y370654D02*
Y365354D01*
X1742698D01*
Y370654D01*
G01X1732498Y823409D02*
Y818109D01*
X1742698D01*
Y823409D01*
G01X1748800Y990000D02*
Y985000D01*
G01Y982400D02*
Y977400D01*
G01X1732498Y1276165D02*
Y1270865D01*
X1742698D01*
Y1276165D01*
G01X1807350Y291161D02*
X1812350D01*
G01X1799350D02*
X1804350D01*
G01X1807468Y744094D02*
X1812468D01*
G01X1799468D02*
X1804468D01*
G01X1807350Y1196673D02*
X1812350D01*
G01X1799350D02*
X1804350D01*
G01X1856017Y190575D02*
Y184575D01*
G01X1832950Y191161D02*
Y185161D01*
G01X1849669Y252161D02*
Y257161D01*
G01X1856711Y370654D02*
Y365354D01*
X1866911D01*
Y370654D01*
G01X1856017Y643331D02*
Y637331D01*
G01X1832950Y643917D02*
Y637917D01*
G01X1846076Y704917D02*
Y709917D01*
G01X1856711Y823409D02*
Y818109D01*
X1866911D01*
Y823409D01*
G01X1856496Y1095413D02*
Y1089413D01*
G01X1832950Y1096673D02*
Y1090673D01*
G01X1856711Y1276165D02*
Y1270865D01*
X1866911D01*
Y1276165D01*
G01X1888469Y280661D02*
X1883469D01*
G01X1888469Y733417D02*
X1883469D01*
G01X1868492Y1142530D02*
X1863492D01*
G01X1888469Y1186173D02*
X1883469D01*
G54D22*
G01X394744Y-485863D02*
X395618Y-484988D01*
X396273Y-483530D01*
X396710Y-481487D01*
X396273Y-479738D01*
X395400Y-478571D01*
X393871Y-477696D01*
X387976D01*
Y-495196D01*
X395181D01*
X396710Y-494030D01*
X397583Y-492279D01*
X398020Y-490238D01*
X397583Y-488196D01*
X396273Y-486446D01*
X394744Y-485863D01*
X387976D01*
G01X407441Y-495196D02*
Y-483530D01*
G01Y-485863D02*
X408533Y-484696D01*
X409625Y-483821D01*
X411153Y-483530D01*
X412244Y-483821D01*
X413555Y-484696D01*
G01X423413Y-500446D02*
X424723Y-501029D01*
X426470Y-500446D01*
X427561Y-499280D01*
X428435Y-497821D01*
X429744Y-493155D01*
X432583Y-483530D01*
G01X425596D02*
X429744Y-493155D01*
G01X448991Y-484988D02*
X447463Y-483821D01*
X446153Y-483530D01*
X444406Y-484113D01*
X443096Y-485279D01*
X442223Y-487321D01*
X442004Y-489363D01*
X442223Y-491405D01*
X443096Y-493155D01*
X444406Y-494613D01*
X446153Y-495196D01*
X447681Y-494613D01*
X448991Y-493446D01*
G01X459723Y-487321D02*
X466710D01*
X466055Y-485279D01*
X464963Y-484113D01*
X463435Y-483530D01*
X461906Y-483821D01*
X460596Y-484696D01*
X459723Y-486738D01*
X459286Y-488488D01*
Y-490238D01*
X459723Y-491988D01*
X460815Y-493738D01*
X462125Y-494904D01*
X463653Y-495196D01*
X465181Y-494613D01*
X466710Y-492863D01*
G01X502801Y-479155D02*
X501491Y-478279D01*
X499963Y-477696D01*
X498216D01*
X496251Y-478571D01*
X494723Y-480029D01*
X493631Y-481780D01*
X492758Y-484696D01*
X492539Y-487321D01*
X492976Y-489946D01*
X493631Y-491696D01*
X494941Y-493446D01*
X496470Y-494613D01*
X497998Y-495196D01*
X499526D01*
X501055Y-494613D01*
X502365Y-493738D01*
X503457Y-492572D01*
G01X519428Y-495196D02*
Y-483530D01*
G01Y-485571D02*
X518555Y-484405D01*
X517244Y-483821D01*
X515716Y-483530D01*
X514188Y-484113D01*
X512878Y-485279D01*
X512004Y-487029D01*
X511568Y-489363D01*
X512004Y-491696D01*
X512878Y-493446D01*
X514188Y-494613D01*
X515716Y-495196D01*
X517244Y-494904D01*
X518555Y-494030D01*
X519428Y-492863D01*
G01X529286Y-495196D02*
Y-483530D01*
G01Y-486446D02*
X530160Y-484988D01*
X531470Y-483821D01*
X533216Y-483530D01*
X534744Y-483821D01*
X536055Y-484988D01*
X536710Y-487029D01*
Y-495196D01*
G01X545913Y-500446D02*
X547223Y-501029D01*
X548970Y-500446D01*
X550061Y-499280D01*
X550935Y-497821D01*
X552244Y-493155D01*
X555083Y-483530D01*
G01X548096D02*
X552244Y-493155D01*
G01X567998Y-495196D02*
X566688Y-494904D01*
X565378Y-493738D01*
X564504Y-491696D01*
X564068Y-489363D01*
X564504Y-487029D01*
X565378Y-484988D01*
X566688Y-483821D01*
X567998Y-483530D01*
X569308Y-483821D01*
X570618Y-484988D01*
X571491Y-487029D01*
X571710Y-489363D01*
X571491Y-491696D01*
X570618Y-493738D01*
X569308Y-494904D01*
X567998Y-495196D01*
G01X581786D02*
Y-483530D01*
G01Y-486446D02*
X582660Y-484988D01*
X583970Y-483821D01*
X585716Y-483530D01*
X587244Y-483821D01*
X588555Y-484988D01*
X589210Y-487029D01*
Y-495196D01*
G01X616350D02*
Y-477696D01*
X624646D01*
G01X621590Y-486154D02*
X616350D01*
G01X637998Y-495779D02*
X637561Y-495488D01*
Y-494904D01*
X637998Y-494613D01*
X638435Y-494904D01*
Y-495488D01*
X637998Y-495779D01*
G01X650695Y-495196D02*
Y-477696D01*
X655061D01*
X656808Y-478571D01*
X658118Y-479738D01*
X659210Y-481487D01*
X660083Y-483530D01*
X660301Y-486446D01*
X660083Y-489363D01*
X659210Y-491405D01*
X658118Y-493155D01*
X656808Y-494321D01*
X655061Y-495196D01*
X650695D01*
G01X668631D02*
Y-477696D01*
X673871D01*
X675618Y-478571D01*
X676928Y-480613D01*
X677365Y-482946D01*
X676928Y-485279D01*
X675836Y-487029D01*
X673871Y-487905D01*
X668631D01*
G01X692244Y-485863D02*
X693118Y-484988D01*
X693773Y-483530D01*
X694210Y-481487D01*
X693773Y-479738D01*
X692900Y-478571D01*
X691371Y-477696D01*
X685476D01*
Y-495196D01*
X692681D01*
X694210Y-494030D01*
X695083Y-492279D01*
X695520Y-490238D01*
X695083Y-488196D01*
X693773Y-486446D01*
X692244Y-485863D01*
X685476D01*
G01X501071Y-450196D02*
Y-432696D01*
X506748Y-447279D01*
X512425Y-432696D01*
Y-450196D01*
G01X524248D02*
X522938Y-449904D01*
X521628Y-448738D01*
X520754Y-446696D01*
X520318Y-444363D01*
X520754Y-442029D01*
X521628Y-439988D01*
X522938Y-438821D01*
X524248Y-438530D01*
X525558Y-438821D01*
X526868Y-439988D01*
X527741Y-442029D01*
X527960Y-444363D01*
X527741Y-446696D01*
X526868Y-448738D01*
X525558Y-449904D01*
X524248Y-450196D01*
G01X545678Y-432696D02*
Y-450196D01*
G01Y-447572D02*
X544805Y-449030D01*
X543494Y-449904D01*
X541966Y-450196D01*
X540220Y-449613D01*
X538910Y-448155D01*
X538036Y-446405D01*
X537818Y-444363D01*
X538036Y-442321D01*
X538910Y-440571D01*
X540220Y-439113D01*
X541966Y-438530D01*
X543494Y-438821D01*
X544586Y-439405D01*
X545678Y-440571D01*
G01X555973Y-442321D02*
X562960D01*
X562305Y-440279D01*
X561213Y-439113D01*
X559685Y-438530D01*
X558156Y-438821D01*
X556846Y-439696D01*
X555973Y-441738D01*
X555536Y-443488D01*
Y-445238D01*
X555973Y-446988D01*
X557065Y-448738D01*
X558375Y-449904D01*
X559903Y-450196D01*
X561431Y-449613D01*
X562960Y-447863D01*
G01X576748Y-450196D02*
Y-432696D01*
G01X754448Y-495196D02*
Y-477696D01*
X751828Y-481196D01*
G01Y-495196D02*
X757068D01*
G01X767800Y-487905D02*
X769328Y-485863D01*
X770638Y-484696D01*
X772385Y-484113D01*
X773913Y-484696D01*
X775005Y-485863D01*
X775878Y-487613D01*
X776096Y-489654D01*
X775878Y-491405D01*
X775005Y-493155D01*
X773694Y-494613D01*
X772166Y-495196D01*
X770420Y-494613D01*
X768891Y-492863D01*
X768018Y-490238D01*
X767800Y-487321D01*
X768236Y-483530D01*
X768891Y-481487D01*
X769983Y-479446D01*
X771511Y-477988D01*
X773040Y-477696D01*
X774568Y-478279D01*
X775660Y-479738D01*
G01X784645Y-491696D02*
X785954Y-493738D01*
X787701Y-494904D01*
X789666Y-495196D01*
X791413Y-494904D01*
X793160Y-493446D01*
X794251Y-491696D01*
X794470Y-489946D01*
X794033Y-487905D01*
X792505Y-486446D01*
X790976Y-485863D01*
X789011D01*
G01X790976D02*
X792286Y-484988D01*
X793378Y-483530D01*
X793815Y-481780D01*
X793378Y-480029D01*
X792286Y-478571D01*
X790321Y-477696D01*
X788356Y-477988D01*
X786391Y-479155D01*
G01X806948Y-495196D02*
Y-477696D01*
X804328Y-481196D01*
G01Y-495196D02*
X809568D01*
G01X819645Y-492572D02*
X820954Y-494030D01*
X822483Y-494904D01*
X824448Y-495196D01*
X826413Y-494613D01*
X827941Y-493446D01*
X829033Y-491405D01*
X829251Y-489071D01*
X828815Y-486738D01*
X827723Y-485279D01*
X826194Y-484113D01*
X824666Y-483821D01*
X823138Y-484113D01*
X821173Y-485279D01*
X821828Y-477696D01*
X827723D01*
G01X741331Y-450196D02*
Y-432696D01*
X746571D01*
X748318Y-433571D01*
X749628Y-435613D01*
X750065Y-437946D01*
X749628Y-440279D01*
X748536Y-442029D01*
X746571Y-442905D01*
X741331D01*
G01X768001Y-434155D02*
X766691Y-433279D01*
X765163Y-432696D01*
X763416D01*
X761451Y-433571D01*
X759923Y-435029D01*
X758831Y-436780D01*
X757958Y-439696D01*
X757739Y-442321D01*
X758176Y-444946D01*
X758831Y-446696D01*
X760141Y-448446D01*
X761670Y-449613D01*
X763198Y-450196D01*
X764726D01*
X766255Y-449613D01*
X767565Y-448738D01*
X768657Y-447572D01*
G01X782444Y-440863D02*
X783318Y-439988D01*
X783973Y-438530D01*
X784410Y-436487D01*
X783973Y-434738D01*
X783100Y-433571D01*
X781571Y-432696D01*
X775676D01*
Y-450196D01*
X782881D01*
X784410Y-449030D01*
X785283Y-447279D01*
X785720Y-445238D01*
X785283Y-443196D01*
X783973Y-441446D01*
X782444Y-440863D01*
X775676D01*
G01X791648Y-456029D02*
X804748D01*
G01X810676Y-450196D02*
Y-432696D01*
X820720Y-450196D01*
Y-432696D01*
G01X833198Y-450196D02*
X831451Y-449904D01*
X829923Y-448738D01*
X828613Y-446988D01*
X827739Y-444946D01*
X827303Y-442613D01*
Y-440279D01*
X827739Y-437946D01*
X828613Y-435904D01*
X829923Y-434155D01*
X831451Y-432988D01*
X833198Y-432696D01*
X834944Y-432988D01*
X836473Y-434155D01*
X837783Y-435904D01*
X838657Y-437946D01*
X839093Y-440279D01*
Y-442613D01*
X838657Y-444946D01*
X837783Y-446988D01*
X836473Y-448738D01*
X834944Y-449904D01*
X833198Y-450196D01*
G01X884039Y-432696D02*
X889498Y-450196D01*
X894957Y-432696D01*
G01X911365Y-450196D02*
X902631D01*
Y-432696D01*
X911365D01*
G01X907871Y-441154D02*
X902631D01*
G01X920131Y-450196D02*
Y-432696D01*
X925590D01*
X927336Y-433571D01*
X928428Y-434738D01*
X928865Y-437071D01*
X928428Y-439405D01*
X927118Y-440863D01*
X925590Y-441738D01*
X920131D01*
G01X925590D02*
X928865Y-450196D01*
G01X941998Y-450779D02*
X941561Y-450488D01*
Y-449904D01*
X941998Y-449613D01*
X942435Y-449904D01*
Y-450488D01*
X941998Y-450779D01*
G01X915748Y-495196D02*
Y-477696D01*
X913128Y-481196D01*
G01Y-495196D02*
X918368D01*
G01X1087348Y-477696D02*
Y-495196D01*
G01X1082326Y-477696D02*
X1092370D01*
G01X1100263Y-492863D02*
X1102010Y-494321D01*
X1103975Y-495196D01*
X1105721D01*
X1107468Y-494321D01*
X1108778Y-492863D01*
X1109433Y-490821D01*
X1108996Y-488780D01*
X1107905Y-487029D01*
X1105940Y-485863D01*
X1103320Y-485279D01*
X1101791Y-484113D01*
X1101136Y-482071D01*
X1101573Y-480029D01*
X1102665Y-478571D01*
X1104193Y-477696D01*
X1105721D01*
X1107250Y-478279D01*
X1108560Y-479738D01*
G01X1119728Y-477696D02*
X1124968D01*
G01X1122348D02*
Y-495196D01*
G01X1119728D02*
X1124968D01*
G01X1135481Y-477696D02*
Y-495196D01*
X1144215D01*
G01X1152545D02*
Y-477696D01*
G01X1160841D02*
X1152545Y-488488D01*
G01X1162151Y-495196D02*
X1156256Y-483530D01*
G01X1082981Y-432696D02*
Y-450196D01*
X1091715D01*
G01X1108778D02*
Y-438530D01*
G01Y-440571D02*
X1107905Y-439405D01*
X1106594Y-438821D01*
X1105066Y-438530D01*
X1103538Y-439113D01*
X1102228Y-440279D01*
X1101354Y-442029D01*
X1100918Y-444363D01*
X1101354Y-446696D01*
X1102228Y-448446D01*
X1103538Y-449613D01*
X1105066Y-450196D01*
X1106594Y-449904D01*
X1107905Y-449030D01*
X1108778Y-447863D01*
G01X1117763Y-455446D02*
X1119073Y-456029D01*
X1120820Y-455446D01*
X1121911Y-454280D01*
X1122785Y-452821D01*
X1124094Y-448155D01*
X1126933Y-438530D01*
G01X1119946D02*
X1124094Y-448155D01*
G01X1136573Y-442321D02*
X1143560D01*
X1142905Y-440279D01*
X1141813Y-439113D01*
X1140285Y-438530D01*
X1138756Y-438821D01*
X1137446Y-439696D01*
X1136573Y-441738D01*
X1136136Y-443488D01*
Y-445238D01*
X1136573Y-446988D01*
X1137665Y-448738D01*
X1138975Y-449904D01*
X1140503Y-450196D01*
X1142031Y-449613D01*
X1143560Y-447863D01*
G01X1154291Y-450196D02*
Y-438530D01*
G01Y-440863D02*
X1155383Y-439696D01*
X1156475Y-438821D01*
X1158003Y-438530D01*
X1159094Y-438821D01*
X1160405Y-439696D01*
G01X1312898Y-495196D02*
X1311151Y-494904D01*
X1309623Y-493738D01*
X1308313Y-491988D01*
X1307439Y-489946D01*
X1307003Y-487613D01*
Y-485279D01*
X1307439Y-482946D01*
X1308313Y-480904D01*
X1309623Y-479155D01*
X1311151Y-477988D01*
X1312898Y-477696D01*
X1314644Y-477988D01*
X1316173Y-479155D01*
X1317483Y-480904D01*
X1318357Y-482946D01*
X1318793Y-485279D01*
Y-487613D01*
X1318357Y-489946D01*
X1317483Y-491988D01*
X1316173Y-493738D01*
X1314644Y-494904D01*
X1312898Y-495196D01*
G01X1314644Y-490529D02*
X1317265Y-495196D01*
G01X1325595Y-477696D02*
Y-490238D01*
X1326468Y-492863D01*
X1328215Y-494613D01*
X1330398Y-495196D01*
X1332581Y-494613D01*
X1334328Y-492863D01*
X1335201Y-490238D01*
Y-477696D01*
G01X1345278D02*
X1350518D01*
G01X1347898D02*
Y-495196D01*
G01X1345278D02*
X1350518D01*
G01X1360376D02*
Y-477696D01*
X1370420Y-495196D01*
Y-477696D01*
G01X1387701Y-479155D02*
X1386391Y-478279D01*
X1384863Y-477696D01*
X1383116D01*
X1381151Y-478571D01*
X1379623Y-480029D01*
X1378531Y-481780D01*
X1377658Y-484696D01*
X1377439Y-487321D01*
X1377876Y-489946D01*
X1378531Y-491696D01*
X1379841Y-493446D01*
X1381370Y-494613D01*
X1382898Y-495196D01*
X1384426D01*
X1385955Y-494613D01*
X1387265Y-493738D01*
X1388357Y-492572D01*
G01X1400398Y-495196D02*
Y-487321D01*
X1396031Y-477696D01*
G01X1404765D02*
X1400398Y-487321D01*
G01X1290595Y-450196D02*
Y-432696D01*
X1294961D01*
X1296708Y-433571D01*
X1298018Y-434738D01*
X1299110Y-436487D01*
X1299983Y-438530D01*
X1300201Y-441446D01*
X1299983Y-444363D01*
X1299110Y-446405D01*
X1298018Y-448155D01*
X1296708Y-449321D01*
X1294961Y-450196D01*
X1290595D01*
G01X1309623Y-442321D02*
X1316610D01*
X1315955Y-440279D01*
X1314863Y-439113D01*
X1313335Y-438530D01*
X1311806Y-438821D01*
X1310496Y-439696D01*
X1309623Y-441738D01*
X1309186Y-443488D01*
Y-445238D01*
X1309623Y-446988D01*
X1310715Y-448738D01*
X1312025Y-449904D01*
X1313553Y-450196D01*
X1315081Y-449613D01*
X1316610Y-447863D01*
G01X1327123Y-448155D02*
X1328215Y-449321D01*
X1329743Y-450196D01*
X1331053D01*
X1332363Y-449613D01*
X1333236Y-448738D01*
X1333673Y-447572D01*
X1333455Y-445821D01*
X1332581Y-444946D01*
X1328651Y-443196D01*
X1327778Y-441154D01*
X1328215Y-439696D01*
X1329088Y-438821D01*
X1330398Y-438530D01*
X1331708Y-438821D01*
X1333018Y-439696D01*
G01X1347898Y-438530D02*
Y-450196D01*
G01Y-433863D02*
X1347461Y-433571D01*
Y-432988D01*
X1347898Y-432696D01*
X1348335Y-432988D01*
Y-433571D01*
X1347898Y-433863D01*
G01X1362341Y-454571D02*
X1363870Y-455738D01*
X1365616Y-456029D01*
X1367144Y-455738D01*
X1368455Y-454280D01*
X1369328Y-452238D01*
Y-438530D01*
G01Y-440863D02*
X1368455Y-439696D01*
X1367144Y-438821D01*
X1365616Y-438530D01*
X1363870Y-439113D01*
X1362778Y-440279D01*
X1361904Y-442321D01*
X1361468Y-444363D01*
X1361686Y-446113D01*
X1362560Y-448155D01*
X1363870Y-449613D01*
X1365616Y-450196D01*
X1366926Y-449904D01*
X1368455Y-448738D01*
X1369328Y-447572D01*
G01X1379186Y-450196D02*
Y-438530D01*
G01Y-441446D02*
X1380060Y-439988D01*
X1381370Y-438821D01*
X1383116Y-438530D01*
X1384644Y-438821D01*
X1385955Y-439988D01*
X1386610Y-442029D01*
Y-450196D01*
G01X1397123Y-442321D02*
X1404110D01*
X1403455Y-440279D01*
X1402363Y-439113D01*
X1400835Y-438530D01*
X1399306Y-438821D01*
X1397996Y-439696D01*
X1397123Y-441738D01*
X1396686Y-443488D01*
Y-445238D01*
X1397123Y-446988D01*
X1398215Y-448738D01*
X1399525Y-449904D01*
X1401053Y-450196D01*
X1402581Y-449613D01*
X1404110Y-447863D01*
G01X1414841Y-450196D02*
Y-438530D01*
G01Y-440863D02*
X1415933Y-439696D01*
X1417025Y-438821D01*
X1418553Y-438530D01*
X1419644Y-438821D01*
X1420955Y-439696D01*
G01X1461598Y-477696D02*
X1459851Y-478279D01*
X1458541Y-479738D01*
X1457668Y-481487D01*
X1457013Y-483821D01*
X1456795Y-486446D01*
X1457013Y-489071D01*
X1457668Y-491405D01*
X1458541Y-493155D01*
X1459851Y-494613D01*
X1461598Y-495196D01*
X1463344Y-494613D01*
X1464655Y-493155D01*
X1465528Y-491405D01*
X1466183Y-489071D01*
X1466401Y-486446D01*
X1466183Y-483821D01*
X1465528Y-481487D01*
X1464655Y-479738D01*
X1463344Y-478279D01*
X1461598Y-477696D01*
G01X1474950Y-487905D02*
X1476478Y-485863D01*
X1477788Y-484696D01*
X1479535Y-484113D01*
X1481063Y-484696D01*
X1482155Y-485863D01*
X1483028Y-487613D01*
X1483246Y-489654D01*
X1483028Y-491405D01*
X1482155Y-493155D01*
X1480844Y-494613D01*
X1479316Y-495196D01*
X1477570Y-494613D01*
X1476041Y-492863D01*
X1475168Y-490238D01*
X1474950Y-487321D01*
X1475386Y-483530D01*
X1476041Y-481487D01*
X1477133Y-479446D01*
X1478661Y-477988D01*
X1480190Y-477696D01*
X1481718Y-478279D01*
X1482810Y-479738D01*
G01X1492668Y-495779D02*
X1500528Y-477696D01*
G01X1514098D02*
X1512351Y-478279D01*
X1511041Y-479738D01*
X1510168Y-481487D01*
X1509513Y-483821D01*
X1509295Y-486446D01*
X1509513Y-489071D01*
X1510168Y-491405D01*
X1511041Y-493155D01*
X1512351Y-494613D01*
X1514098Y-495196D01*
X1515844Y-494613D01*
X1517155Y-493155D01*
X1518028Y-491405D01*
X1518683Y-489071D01*
X1518901Y-486446D01*
X1518683Y-483821D01*
X1518028Y-481487D01*
X1517155Y-479738D01*
X1515844Y-478279D01*
X1514098Y-477696D01*
G01X1527886Y-493155D02*
X1529415Y-494613D01*
X1531161Y-495196D01*
X1532908Y-494613D01*
X1534436Y-492863D01*
X1535528Y-490238D01*
X1535965Y-487613D01*
Y-484405D01*
X1535528Y-481780D01*
X1534436Y-479446D01*
X1533126Y-478279D01*
X1531598Y-477696D01*
X1529851Y-478279D01*
X1528541Y-479446D01*
X1527668Y-481196D01*
X1527231Y-483530D01*
X1527668Y-485571D01*
X1528760Y-487613D01*
X1530070Y-488780D01*
X1531598Y-489071D01*
X1533344Y-488488D01*
X1534655Y-487029D01*
X1535965Y-484405D01*
G01X1545168Y-495779D02*
X1553028Y-477696D01*
G01X1562450Y-480613D02*
X1563760Y-478863D01*
X1565288Y-477988D01*
X1567035Y-477696D01*
X1569218Y-478279D01*
X1570746Y-479738D01*
X1571183Y-481487D01*
X1570965Y-483238D01*
X1570091Y-484696D01*
X1565725Y-487613D01*
X1563760Y-489654D01*
X1562450Y-492572D01*
X1562013Y-495196D01*
X1571183D01*
G01X1584098Y-477696D02*
X1582351Y-478279D01*
X1581041Y-479738D01*
X1580168Y-481487D01*
X1579513Y-483821D01*
X1579295Y-486446D01*
X1579513Y-489071D01*
X1580168Y-491405D01*
X1581041Y-493155D01*
X1582351Y-494613D01*
X1584098Y-495196D01*
X1585844Y-494613D01*
X1587155Y-493155D01*
X1588028Y-491405D01*
X1588683Y-489071D01*
X1588901Y-486446D01*
X1588683Y-483821D01*
X1588028Y-481487D01*
X1587155Y-479738D01*
X1585844Y-478279D01*
X1584098Y-477696D01*
G01X1601598Y-495196D02*
Y-477696D01*
X1598978Y-481196D01*
G01Y-495196D02*
X1604218D01*
G01X1618661D02*
X1619098Y-491405D01*
X1619753Y-488196D01*
X1620626Y-485279D01*
X1621718Y-482071D01*
X1623465Y-477696D01*
X1614731D01*
G01X1509295Y-450196D02*
Y-432696D01*
X1513661D01*
X1515408Y-433571D01*
X1516718Y-434738D01*
X1517810Y-436487D01*
X1518683Y-438530D01*
X1518901Y-441446D01*
X1518683Y-444363D01*
X1517810Y-446405D01*
X1516718Y-448155D01*
X1515408Y-449321D01*
X1513661Y-450196D01*
X1509295D01*
G01X1535528D02*
Y-438530D01*
G01Y-440571D02*
X1534655Y-439405D01*
X1533344Y-438821D01*
X1531816Y-438530D01*
X1530288Y-439113D01*
X1528978Y-440279D01*
X1528104Y-442029D01*
X1527668Y-444363D01*
X1528104Y-446696D01*
X1528978Y-448446D01*
X1530288Y-449613D01*
X1531816Y-450196D01*
X1533344Y-449904D01*
X1534655Y-449030D01*
X1535528Y-447863D01*
G01X1549098Y-432696D02*
Y-450196D01*
G01X1546041Y-438530D02*
X1552155D01*
G01X1563323Y-442321D02*
X1570310D01*
X1569655Y-440279D01*
X1568563Y-439113D01*
X1567035Y-438530D01*
X1565506Y-438821D01*
X1564196Y-439696D01*
X1563323Y-441738D01*
X1562886Y-443488D01*
Y-445238D01*
X1563323Y-446988D01*
X1564415Y-448738D01*
X1565725Y-449904D01*
X1567253Y-450196D01*
X1568781Y-449613D01*
X1570310Y-447863D01*
G01X13517Y687500D02*
Y690000D01*
X14558D01*
X14892Y689875D01*
X15100Y689708D01*
X15183Y689375D01*
X15100Y689042D01*
X14850Y688833D01*
X14558Y688708D01*
X13517D01*
G01X14558D02*
X15183Y687500D01*
G01X17450D02*
Y690000D01*
X16950Y689500D01*
G01Y687500D02*
X17950D01*
G01X21050D02*
Y690000D01*
X19508Y688208D01*
X21592D01*
G01X22858Y688542D02*
X23150Y688833D01*
X23400Y689000D01*
X23733Y689083D01*
X24025Y689000D01*
X24233Y688833D01*
X24400Y688583D01*
X24442Y688292D01*
X24400Y688042D01*
X24233Y687792D01*
X23983Y687583D01*
X23692Y687500D01*
X23358Y687583D01*
X23067Y687833D01*
X22900Y688208D01*
X22858Y688625D01*
X22942Y689167D01*
X23067Y689458D01*
X23275Y689750D01*
X23567Y689958D01*
X23858Y690000D01*
X24150Y689917D01*
X24358Y689708D01*
G01X14517Y662000D02*
Y664500D01*
X15558D01*
X15892Y664375D01*
X16100Y664208D01*
X16183Y663875D01*
X16100Y663542D01*
X15850Y663333D01*
X15558Y663208D01*
X14517D01*
G01X15558D02*
X16183Y662000D01*
G01X18450D02*
Y664500D01*
X17950Y664000D01*
G01Y662000D02*
X18950D01*
G01X22050D02*
Y664500D01*
X20508Y662708D01*
X22592D01*
G01X23733Y662375D02*
X23983Y662167D01*
X24275Y662042D01*
X24650Y662000D01*
X25025Y662083D01*
X25317Y662250D01*
X25525Y662542D01*
X25567Y662875D01*
X25483Y663208D01*
X25275Y663417D01*
X24983Y663583D01*
X24692Y663625D01*
X24400Y663583D01*
X24025Y663417D01*
X24150Y664500D01*
X25275D01*
G01X18500Y674350D02*
X18458Y674017D01*
X18292Y673725D01*
X18042Y673475D01*
X17750Y673308D01*
X17417Y673225D01*
X17083D01*
X16750Y673308D01*
X16458Y673475D01*
X16208Y673725D01*
X16042Y674017D01*
X16000Y674350D01*
X16042Y674683D01*
X16208Y674975D01*
X16458Y675225D01*
X16750Y675392D01*
X17083Y675475D01*
X17417D01*
X17750Y675392D01*
X18042Y675225D01*
X18292Y674975D01*
X18458Y674683D01*
X18500Y674350D01*
G01X17833Y674683D02*
X18500Y675183D01*
G01X16417Y676658D02*
X16167Y676908D01*
X16042Y677200D01*
X16000Y677533D01*
X16083Y677950D01*
X16292Y678242D01*
X16542Y678325D01*
X16792Y678283D01*
X17000Y678117D01*
X17417Y677283D01*
X17708Y676908D01*
X18125Y676658D01*
X18500Y676575D01*
Y678325D01*
G01X17458Y679758D02*
X17167Y680050D01*
X17000Y680300D01*
X16917Y680633D01*
X17000Y680925D01*
X17167Y681133D01*
X17417Y681300D01*
X17708Y681342D01*
X17958Y681300D01*
X18208Y681133D01*
X18417Y680883D01*
X18500Y680592D01*
X18417Y680258D01*
X18167Y679967D01*
X17792Y679800D01*
X17375Y679758D01*
X16833Y679842D01*
X16542Y679967D01*
X16250Y680175D01*
X16042Y680467D01*
X16000Y680758D01*
X16083Y681050D01*
X16292Y681258D01*
G01X18000Y682733D02*
X18292Y682983D01*
X18458Y683317D01*
X18500Y683692D01*
X18458Y684025D01*
X18250Y684358D01*
X18000Y684567D01*
X17750Y684608D01*
X17458Y684525D01*
X17250Y684233D01*
X17167Y683942D01*
Y683567D01*
G01Y683942D02*
X17042Y684192D01*
X16833Y684400D01*
X16583Y684483D01*
X16333Y684400D01*
X16125Y684192D01*
X16000Y683817D01*
X16042Y683442D01*
X16208Y683067D01*
G01X20322Y685683D02*
Y671683D01*
G01X33322Y685683D02*
X20322D01*
G01Y671683D02*
X33322D01*
G01X19000Y699350D02*
X18958Y699017D01*
X18792Y698725D01*
X18542Y698475D01*
X18250Y698308D01*
X17917Y698225D01*
X17583D01*
X17250Y698308D01*
X16958Y698475D01*
X16708Y698725D01*
X16542Y699017D01*
X16500Y699350D01*
X16542Y699683D01*
X16708Y699975D01*
X16958Y700225D01*
X17250Y700392D01*
X17583Y700475D01*
X17917D01*
X18250Y700392D01*
X18542Y700225D01*
X18792Y699975D01*
X18958Y699683D01*
X19000Y699350D01*
G01X18333Y699683D02*
X19000Y700183D01*
G01X16917Y701658D02*
X16667Y701908D01*
X16542Y702200D01*
X16500Y702533D01*
X16583Y702950D01*
X16792Y703242D01*
X17042Y703325D01*
X17292Y703283D01*
X17500Y703117D01*
X17917Y702283D01*
X18208Y701908D01*
X18625Y701658D01*
X19000Y701575D01*
Y703325D01*
G01X16917Y704758D02*
X16667Y705008D01*
X16542Y705300D01*
X16500Y705633D01*
X16583Y706050D01*
X16792Y706342D01*
X17042Y706425D01*
X17292Y706383D01*
X17500Y706217D01*
X17917Y705383D01*
X18208Y705008D01*
X18625Y704758D01*
X19000Y704675D01*
Y706425D01*
G01X18500Y707733D02*
X18792Y707983D01*
X18958Y708317D01*
X19000Y708692D01*
X18958Y709025D01*
X18750Y709358D01*
X18500Y709567D01*
X18250Y709608D01*
X17958Y709525D01*
X17750Y709233D01*
X17667Y708942D01*
Y708567D01*
G01Y708942D02*
X17542Y709192D01*
X17333Y709400D01*
X17083Y709483D01*
X16833Y709400D01*
X16625Y709192D01*
X16500Y708817D01*
X16542Y708442D01*
X16708Y708067D01*
G01X20689Y711034D02*
Y697034D01*
G01X33689Y711034D02*
X20689D01*
G01Y697034D02*
X33689D01*
G01X20613Y1110045D02*
Y1112545D01*
X21654D01*
X21988Y1112420D01*
X22196Y1112253D01*
X22279Y1111920D01*
X22196Y1111587D01*
X21946Y1111378D01*
X21654Y1111253D01*
X20613D01*
G01X21654D02*
X22279Y1110045D01*
G01X23629Y1110420D02*
X23879Y1110212D01*
X24171Y1110087D01*
X24546Y1110045D01*
X24921Y1110128D01*
X25213Y1110295D01*
X25421Y1110587D01*
X25463Y1110920D01*
X25379Y1111253D01*
X25171Y1111462D01*
X24879Y1111628D01*
X24588Y1111670D01*
X24296Y1111628D01*
X23921Y1111462D01*
X24046Y1112545D01*
X25171D01*
G01X26729Y1110420D02*
X26979Y1110212D01*
X27271Y1110087D01*
X27646Y1110045D01*
X28021Y1110128D01*
X28313Y1110295D01*
X28521Y1110587D01*
X28563Y1110920D01*
X28479Y1111253D01*
X28271Y1111462D01*
X27979Y1111628D01*
X27688Y1111670D01*
X27396Y1111628D01*
X27021Y1111462D01*
X27146Y1112545D01*
X28271D01*
G01X30746D02*
X30413Y1112462D01*
X30163Y1112253D01*
X29996Y1112003D01*
X29871Y1111670D01*
X29829Y1111295D01*
X29871Y1110920D01*
X29996Y1110587D01*
X30163Y1110337D01*
X30413Y1110128D01*
X30746Y1110045D01*
X31079Y1110128D01*
X31329Y1110337D01*
X31496Y1110587D01*
X31621Y1110920D01*
X31663Y1111295D01*
X31621Y1111670D01*
X31496Y1112003D01*
X31329Y1112253D01*
X31079Y1112462D01*
X30746Y1112545D01*
G01X18000Y1126850D02*
X17958Y1126517D01*
X17792Y1126225D01*
X17542Y1125975D01*
X17250Y1125808D01*
X16917Y1125725D01*
X16583D01*
X16250Y1125808D01*
X15958Y1125975D01*
X15708Y1126225D01*
X15542Y1126517D01*
X15500Y1126850D01*
X15542Y1127183D01*
X15708Y1127475D01*
X15958Y1127725D01*
X16250Y1127892D01*
X16583Y1127975D01*
X16917D01*
X17250Y1127892D01*
X17542Y1127725D01*
X17792Y1127475D01*
X17958Y1127183D01*
X18000Y1126850D01*
G01X17333Y1127183D02*
X18000Y1127683D01*
G01X15917Y1129158D02*
X15667Y1129408D01*
X15542Y1129700D01*
X15500Y1130033D01*
X15583Y1130450D01*
X15792Y1130742D01*
X16042Y1130825D01*
X16292Y1130783D01*
X16500Y1130617D01*
X16917Y1129783D01*
X17208Y1129408D01*
X17625Y1129158D01*
X18000Y1129075D01*
Y1130825D01*
G01Y1133050D02*
X17958Y1133342D01*
X17833Y1133675D01*
X17625Y1133883D01*
X17333Y1133967D01*
X17042Y1133883D01*
X16792Y1133633D01*
X16667Y1133258D01*
Y1132842D01*
X16583Y1132592D01*
X16375Y1132383D01*
X16083Y1132300D01*
X15792Y1132425D01*
X15583Y1132717D01*
X15500Y1133050D01*
X15583Y1133383D01*
X15792Y1133675D01*
X16083Y1133800D01*
X16375Y1133717D01*
X16583Y1133508D01*
X16667Y1133258D01*
Y1132842D01*
X16792Y1132467D01*
X17042Y1132217D01*
X17333Y1132133D01*
X17625Y1132217D01*
X17833Y1132425D01*
X17958Y1132758D01*
X18000Y1133050D01*
G01Y1136067D02*
X17458Y1136150D01*
X17000Y1136275D01*
X16583Y1136442D01*
X16125Y1136650D01*
X15500Y1136983D01*
Y1135317D01*
G01X20295Y1138650D02*
Y1124650D01*
G01D02*
X33295D01*
G01X13255Y1140191D02*
Y1142691D01*
X14296D01*
X14630Y1142566D01*
X14838Y1142399D01*
X14921Y1142066D01*
X14838Y1141733D01*
X14588Y1141524D01*
X14296Y1141399D01*
X13255D01*
G01X14296D02*
X14921Y1140191D01*
G01X16271Y1140566D02*
X16521Y1140358D01*
X16813Y1140233D01*
X17188Y1140191D01*
X17563Y1140274D01*
X17855Y1140441D01*
X18063Y1140733D01*
X18105Y1141066D01*
X18021Y1141399D01*
X17813Y1141608D01*
X17521Y1141774D01*
X17230Y1141816D01*
X16938Y1141774D01*
X16563Y1141608D01*
X16688Y1142691D01*
X17813D01*
G01X19371Y1140566D02*
X19621Y1140358D01*
X19913Y1140233D01*
X20288Y1140191D01*
X20663Y1140274D01*
X20955Y1140441D01*
X21163Y1140733D01*
X21205Y1141066D01*
X21121Y1141399D01*
X20913Y1141608D01*
X20621Y1141774D01*
X20330Y1141816D01*
X20038Y1141774D01*
X19663Y1141608D01*
X19788Y1142691D01*
X20913D01*
G01X22471Y1140691D02*
X22721Y1140399D01*
X23055Y1140233D01*
X23430Y1140191D01*
X23763Y1140233D01*
X24096Y1140441D01*
X24305Y1140691D01*
X24346Y1140941D01*
X24263Y1141233D01*
X23971Y1141441D01*
X23680Y1141524D01*
X23305D01*
G01X23680D02*
X23930Y1141649D01*
X24138Y1141858D01*
X24221Y1142108D01*
X24138Y1142358D01*
X23930Y1142566D01*
X23555Y1142691D01*
X23180Y1142649D01*
X22805Y1142483D01*
G01X33295Y1138650D02*
X20295D01*
G01X22471Y1166325D02*
X22138Y1166367D01*
X21846Y1166533D01*
X21596Y1166783D01*
X21429Y1167075D01*
X21346Y1167408D01*
Y1167742D01*
X21429Y1168075D01*
X21596Y1168367D01*
X21846Y1168617D01*
X22138Y1168783D01*
X22471Y1168825D01*
X22804Y1168783D01*
X23096Y1168617D01*
X23346Y1168367D01*
X23513Y1168075D01*
X23596Y1167742D01*
Y1167408D01*
X23513Y1167075D01*
X23346Y1166783D01*
X23096Y1166533D01*
X22804Y1166367D01*
X22471Y1166325D01*
G01X22804Y1166992D02*
X23304Y1166325D01*
G01X24779Y1168408D02*
X25029Y1168658D01*
X25321Y1168783D01*
X25654Y1168825D01*
X26071Y1168742D01*
X26363Y1168533D01*
X26446Y1168283D01*
X26404Y1168033D01*
X26238Y1167825D01*
X25404Y1167408D01*
X25029Y1167117D01*
X24779Y1166700D01*
X24696Y1166325D01*
X26446D01*
G01X27754Y1166700D02*
X28004Y1166492D01*
X28296Y1166367D01*
X28671Y1166325D01*
X29046Y1166408D01*
X29338Y1166575D01*
X29546Y1166867D01*
X29588Y1167200D01*
X29504Y1167533D01*
X29296Y1167742D01*
X29004Y1167908D01*
X28713Y1167950D01*
X28421Y1167908D01*
X28046Y1167742D01*
X28171Y1168825D01*
X29296D01*
G01X31771Y1166325D02*
Y1168825D01*
X31271Y1168325D01*
G01Y1166325D02*
X32271D01*
G01X20269Y1164001D02*
Y1150001D01*
G01X33269Y1164001D02*
X20269D01*
G01Y1150001D02*
X33269D01*
G01X19941Y1192602D02*
X17441D01*
Y1193643D01*
X17566Y1193977D01*
X17733Y1194185D01*
X18066Y1194268D01*
X18399Y1194185D01*
X18608Y1193935D01*
X18733Y1193643D01*
Y1192602D01*
G01Y1193643D02*
X19941Y1194268D01*
G01X17858Y1195743D02*
X17608Y1195993D01*
X17483Y1196285D01*
X17441Y1196618D01*
X17524Y1197035D01*
X17733Y1197327D01*
X17983Y1197410D01*
X18233Y1197368D01*
X18441Y1197202D01*
X18858Y1196368D01*
X19149Y1195993D01*
X19566Y1195743D01*
X19941Y1195660D01*
Y1197410D01*
G01X17441Y1199635D02*
X17524Y1199302D01*
X17733Y1199052D01*
X17983Y1198885D01*
X18316Y1198760D01*
X18691Y1198718D01*
X19066Y1198760D01*
X19399Y1198885D01*
X19649Y1199052D01*
X19858Y1199302D01*
X19941Y1199635D01*
X19858Y1199968D01*
X19649Y1200218D01*
X19399Y1200385D01*
X19066Y1200510D01*
X18691Y1200552D01*
X18316Y1200510D01*
X17983Y1200385D01*
X17733Y1200218D01*
X17524Y1199968D01*
X17441Y1199635D01*
G01X19941Y1202735D02*
X19899Y1203027D01*
X19774Y1203360D01*
X19566Y1203568D01*
X19274Y1203652D01*
X18983Y1203568D01*
X18733Y1203318D01*
X18608Y1202943D01*
Y1202527D01*
X18524Y1202277D01*
X18316Y1202068D01*
X18024Y1201985D01*
X17733Y1202110D01*
X17524Y1202402D01*
X17441Y1202735D01*
X17524Y1203068D01*
X17733Y1203360D01*
X18024Y1203485D01*
X18316Y1203402D01*
X18524Y1203193D01*
X18608Y1202943D01*
Y1202527D01*
X18733Y1202152D01*
X18983Y1201902D01*
X19274Y1201818D01*
X19566Y1201902D01*
X19774Y1202110D01*
X19899Y1202443D01*
X19941Y1202735D01*
G01X73900Y163017D02*
X71400D01*
Y164058D01*
X71525Y164392D01*
X71692Y164600D01*
X72025Y164683D01*
X72358Y164600D01*
X72567Y164350D01*
X72692Y164058D01*
Y163017D01*
G01Y164058D02*
X73900Y164683D01*
G01X72858Y166158D02*
X72567Y166450D01*
X72400Y166700D01*
X72317Y167033D01*
X72400Y167325D01*
X72567Y167533D01*
X72817Y167700D01*
X73108Y167742D01*
X73358Y167700D01*
X73608Y167533D01*
X73817Y167283D01*
X73900Y166992D01*
X73817Y166658D01*
X73567Y166367D01*
X73192Y166200D01*
X72775Y166158D01*
X72233Y166242D01*
X71942Y166367D01*
X71650Y166575D01*
X71442Y166867D01*
X71400Y167158D01*
X71483Y167450D01*
X71692Y167658D01*
G01X73608Y169342D02*
X73817Y169633D01*
X73900Y169967D01*
X73817Y170300D01*
X73567Y170592D01*
X73192Y170800D01*
X72817Y170883D01*
X72358D01*
X71983Y170800D01*
X71650Y170592D01*
X71483Y170342D01*
X71400Y170050D01*
X71483Y169717D01*
X71650Y169467D01*
X71900Y169300D01*
X72233Y169217D01*
X72525Y169300D01*
X72817Y169508D01*
X72983Y169758D01*
X73025Y170050D01*
X72942Y170383D01*
X72733Y170633D01*
X72358Y170883D01*
G01X73608Y172442D02*
X73817Y172733D01*
X73900Y173067D01*
X73817Y173400D01*
X73567Y173692D01*
X73192Y173900D01*
X72817Y173983D01*
X72358D01*
X71983Y173900D01*
X71650Y173692D01*
X71483Y173442D01*
X71400Y173150D01*
X71483Y172817D01*
X71650Y172567D01*
X71900Y172400D01*
X72233Y172317D01*
X72525Y172400D01*
X72817Y172608D01*
X72983Y172858D01*
X73025Y173150D01*
X72942Y173483D01*
X72733Y173733D01*
X72358Y173983D01*
G01X67334Y163483D02*
X64834D01*
Y164317D01*
X64959Y164650D01*
X65126Y164900D01*
X65376Y165108D01*
X65667Y165275D01*
X66084Y165317D01*
X66501Y165275D01*
X66792Y165108D01*
X67042Y164900D01*
X67209Y164650D01*
X67334Y164317D01*
Y163483D01*
G01X65251Y166708D02*
X65001Y166958D01*
X64876Y167250D01*
X64834Y167583D01*
X64917Y168000D01*
X65126Y168292D01*
X65376Y168375D01*
X65626Y168333D01*
X65834Y168167D01*
X66251Y167333D01*
X66542Y166958D01*
X66959Y166708D01*
X67334Y166625D01*
Y168375D01*
G01Y171100D02*
X64834D01*
X66626Y169558D01*
Y171642D01*
G01X57000Y183517D02*
X54500D01*
Y184558D01*
X54625Y184892D01*
X54792Y185100D01*
X55125Y185183D01*
X55458Y185100D01*
X55667Y184850D01*
X55792Y184558D01*
Y183517D01*
G01Y184558D02*
X57000Y185183D01*
G01X55958Y186658D02*
X55667Y186950D01*
X55500Y187200D01*
X55417Y187533D01*
X55500Y187825D01*
X55667Y188033D01*
X55917Y188200D01*
X56208Y188242D01*
X56458Y188200D01*
X56708Y188033D01*
X56917Y187783D01*
X57000Y187492D01*
X56917Y187158D01*
X56667Y186867D01*
X56292Y186700D01*
X55875Y186658D01*
X55333Y186742D01*
X55042Y186867D01*
X54750Y187075D01*
X54542Y187367D01*
X54500Y187658D01*
X54583Y187950D01*
X54792Y188158D01*
G01X56708Y189842D02*
X56917Y190133D01*
X57000Y190467D01*
X56917Y190800D01*
X56667Y191092D01*
X56292Y191300D01*
X55917Y191383D01*
X55458D01*
X55083Y191300D01*
X54750Y191092D01*
X54583Y190842D01*
X54500Y190550D01*
X54583Y190217D01*
X54750Y189967D01*
X55000Y189800D01*
X55333Y189717D01*
X55625Y189800D01*
X55917Y190008D01*
X56083Y190258D01*
X56125Y190550D01*
X56042Y190883D01*
X55833Y191133D01*
X55458Y191383D01*
G01X57000Y193650D02*
X56958Y193942D01*
X56833Y194275D01*
X56625Y194483D01*
X56333Y194567D01*
X56042Y194483D01*
X55792Y194233D01*
X55667Y193858D01*
Y193442D01*
X55583Y193192D01*
X55375Y192983D01*
X55083Y192900D01*
X54792Y193025D01*
X54583Y193317D01*
X54500Y193650D01*
X54583Y193983D01*
X54792Y194275D01*
X55083Y194400D01*
X55375Y194317D01*
X55583Y194108D01*
X55667Y193858D01*
Y193442D01*
X55792Y193067D01*
X56042Y192817D01*
X56333Y192733D01*
X56625Y192817D01*
X56833Y193025D01*
X56958Y193358D01*
X57000Y193650D01*
G01X57937Y181961D02*
X61937D01*
Y189361D01*
G01X74837Y183361D02*
X70837D01*
Y175961D01*
G01X50254Y200761D02*
Y203261D01*
X51295D01*
X51629Y203136D01*
X51837Y202969D01*
X51920Y202636D01*
X51837Y202303D01*
X51587Y202094D01*
X51295Y201969D01*
X50254D01*
G01X51295D02*
X51920Y200761D01*
G01X53395Y201803D02*
X53687Y202094D01*
X53937Y202261D01*
X54270Y202344D01*
X54562Y202261D01*
X54770Y202094D01*
X54937Y201844D01*
X54979Y201553D01*
X54937Y201303D01*
X54770Y201053D01*
X54520Y200844D01*
X54229Y200761D01*
X53895Y200844D01*
X53604Y201094D01*
X53437Y201469D01*
X53395Y201886D01*
X53479Y202428D01*
X53604Y202719D01*
X53812Y203011D01*
X54104Y203219D01*
X54395Y203261D01*
X54687Y203178D01*
X54895Y202969D01*
G01X57287Y200761D02*
X57579Y200803D01*
X57912Y200928D01*
X58120Y201136D01*
X58204Y201428D01*
X58120Y201719D01*
X57870Y201969D01*
X57495Y202094D01*
X57079D01*
X56829Y202178D01*
X56620Y202386D01*
X56537Y202678D01*
X56662Y202969D01*
X56954Y203178D01*
X57287Y203261D01*
X57620Y203178D01*
X57912Y202969D01*
X58037Y202678D01*
X57954Y202386D01*
X57745Y202178D01*
X57495Y202094D01*
X57079D01*
X56704Y201969D01*
X56454Y201719D01*
X56370Y201428D01*
X56454Y201136D01*
X56662Y200928D01*
X56995Y200803D01*
X57287Y200761D01*
G01X59679Y201053D02*
X59970Y200844D01*
X60304Y200761D01*
X60637Y200844D01*
X60929Y201094D01*
X61137Y201469D01*
X61220Y201844D01*
Y202303D01*
X61137Y202678D01*
X60929Y203011D01*
X60679Y203178D01*
X60387Y203261D01*
X60054Y203178D01*
X59804Y203011D01*
X59637Y202761D01*
X59554Y202428D01*
X59637Y202136D01*
X59845Y201844D01*
X60095Y201678D01*
X60387Y201636D01*
X60720Y201719D01*
X60970Y201928D01*
X61220Y202303D01*
G01X62537Y207261D02*
Y203261D01*
X69937D01*
G01X49917Y173900D02*
Y176400D01*
X50958D01*
X51292Y176275D01*
X51500Y176108D01*
X51583Y175775D01*
X51500Y175442D01*
X51250Y175233D01*
X50958Y175108D01*
X49917D01*
G01X50958D02*
X51583Y173900D01*
G01X53058Y174942D02*
X53350Y175233D01*
X53600Y175400D01*
X53933Y175483D01*
X54225Y175400D01*
X54433Y175233D01*
X54600Y174983D01*
X54642Y174692D01*
X54600Y174442D01*
X54433Y174192D01*
X54183Y173983D01*
X53892Y173900D01*
X53558Y173983D01*
X53267Y174233D01*
X53100Y174608D01*
X53058Y175025D01*
X53142Y175567D01*
X53267Y175858D01*
X53475Y176150D01*
X53767Y176358D01*
X54058Y176400D01*
X54350Y176317D01*
X54558Y176108D01*
G01X56242Y174192D02*
X56533Y173983D01*
X56867Y173900D01*
X57200Y173983D01*
X57492Y174233D01*
X57700Y174608D01*
X57783Y174983D01*
Y175442D01*
X57700Y175817D01*
X57492Y176150D01*
X57242Y176317D01*
X56950Y176400D01*
X56617Y176317D01*
X56367Y176150D01*
X56200Y175900D01*
X56117Y175567D01*
X56200Y175275D01*
X56408Y174983D01*
X56658Y174817D01*
X56950Y174775D01*
X57283Y174858D01*
X57533Y175067D01*
X57783Y175442D01*
G01X59258Y174942D02*
X59550Y175233D01*
X59800Y175400D01*
X60133Y175483D01*
X60425Y175400D01*
X60633Y175233D01*
X60800Y174983D01*
X60842Y174692D01*
X60800Y174442D01*
X60633Y174192D01*
X60383Y173983D01*
X60092Y173900D01*
X59758Y173983D01*
X59467Y174233D01*
X59300Y174608D01*
X59258Y175025D01*
X59342Y175567D01*
X59467Y175858D01*
X59675Y176150D01*
X59967Y176358D01*
X60258Y176400D01*
X60550Y176317D01*
X60758Y176108D01*
G01X54637Y181561D02*
Y177561D01*
X62037D01*
G01X42954Y209561D02*
Y212061D01*
X43995D01*
X44329Y211936D01*
X44537Y211769D01*
X44620Y211436D01*
X44537Y211103D01*
X44287Y210894D01*
X43995Y210769D01*
X42954D01*
G01X43995D02*
X44620Y209561D01*
G01X46095Y210603D02*
X46387Y210894D01*
X46637Y211061D01*
X46970Y211144D01*
X47262Y211061D01*
X47470Y210894D01*
X47637Y210644D01*
X47679Y210353D01*
X47637Y210103D01*
X47470Y209853D01*
X47220Y209644D01*
X46929Y209561D01*
X46595Y209644D01*
X46304Y209894D01*
X46137Y210269D01*
X46095Y210686D01*
X46179Y211228D01*
X46304Y211519D01*
X46512Y211811D01*
X46804Y212019D01*
X47095Y212061D01*
X47387Y211978D01*
X47595Y211769D01*
G01X49279Y209853D02*
X49570Y209644D01*
X49904Y209561D01*
X50237Y209644D01*
X50529Y209894D01*
X50737Y210269D01*
X50820Y210644D01*
Y211103D01*
X50737Y211478D01*
X50529Y211811D01*
X50279Y211978D01*
X49987Y212061D01*
X49654Y211978D01*
X49404Y211811D01*
X49237Y211561D01*
X49154Y211228D01*
X49237Y210936D01*
X49445Y210644D01*
X49695Y210478D01*
X49987Y210436D01*
X50320Y210519D01*
X50570Y210728D01*
X50820Y211103D01*
G01X53004Y209561D02*
X53087Y210103D01*
X53212Y210561D01*
X53379Y210978D01*
X53587Y211436D01*
X53920Y212061D01*
X52254D01*
G01X62137Y208561D02*
Y212561D01*
X54737D01*
G01X63350Y193500D02*
X63017Y193542D01*
X62725Y193708D01*
X62475Y193958D01*
X62308Y194250D01*
X62225Y194583D01*
Y194917D01*
X62308Y195250D01*
X62475Y195542D01*
X62725Y195792D01*
X63017Y195958D01*
X63350Y196000D01*
X63683Y195958D01*
X63975Y195792D01*
X64225Y195542D01*
X64392Y195250D01*
X64475Y194917D01*
Y194583D01*
X64392Y194250D01*
X64225Y193958D01*
X63975Y193708D01*
X63683Y193542D01*
X63350Y193500D01*
G01X63683Y194167D02*
X64183Y193500D01*
G01X66450D02*
Y196000D01*
X65950Y195500D01*
G01Y193500D02*
X66950D01*
G01X70050D02*
Y196000D01*
X68508Y194208D01*
X70592D01*
G01X71733Y193875D02*
X71983Y193667D01*
X72275Y193542D01*
X72650Y193500D01*
X73025Y193583D01*
X73317Y193750D01*
X73525Y194042D01*
X73567Y194375D01*
X73483Y194708D01*
X73275Y194917D01*
X72983Y195083D01*
X72692Y195125D01*
X72400Y195083D01*
X72025Y194917D01*
X72150Y196000D01*
X73275D01*
G01X69937Y176061D02*
X62937D01*
G01D02*
Y192161D01*
G01D02*
X69937D01*
G01D02*
Y176061D01*
G01X52004Y207153D02*
X51754Y207278D01*
X51462Y207361D01*
X51129D01*
X50754Y207236D01*
X50462Y207028D01*
X50254Y206778D01*
X50087Y206361D01*
X50045Y205986D01*
X50129Y205611D01*
X50254Y205361D01*
X50504Y205111D01*
X50795Y204944D01*
X51087Y204861D01*
X51379D01*
X51670Y204944D01*
X51920Y205069D01*
X52129Y205236D01*
G01X53270Y205361D02*
X53520Y205069D01*
X53854Y204903D01*
X54229Y204861D01*
X54562Y204903D01*
X54895Y205111D01*
X55104Y205361D01*
X55145Y205611D01*
X55062Y205903D01*
X54770Y206111D01*
X54479Y206194D01*
X54104D01*
G01X54479D02*
X54729Y206319D01*
X54937Y206528D01*
X55020Y206778D01*
X54937Y207028D01*
X54729Y207236D01*
X54354Y207361D01*
X53979Y207319D01*
X53604Y207153D01*
G01X56495Y205903D02*
X56787Y206194D01*
X57037Y206361D01*
X57370Y206444D01*
X57662Y206361D01*
X57870Y206194D01*
X58037Y205944D01*
X58079Y205653D01*
X58037Y205403D01*
X57870Y205153D01*
X57620Y204944D01*
X57329Y204861D01*
X56995Y204944D01*
X56704Y205194D01*
X56537Y205569D01*
X56495Y205986D01*
X56579Y206528D01*
X56704Y206819D01*
X56912Y207111D01*
X57204Y207319D01*
X57495Y207361D01*
X57787Y207278D01*
X57995Y207069D01*
G01X60387Y207361D02*
X60054Y207278D01*
X59804Y207069D01*
X59637Y206819D01*
X59512Y206486D01*
X59470Y206111D01*
X59512Y205736D01*
X59637Y205403D01*
X59804Y205153D01*
X60054Y204944D01*
X60387Y204861D01*
X60720Y204944D01*
X60970Y205153D01*
X61137Y205403D01*
X61262Y205736D01*
X61304Y206111D01*
X61262Y206486D01*
X61137Y206819D01*
X60970Y207069D01*
X60720Y207278D01*
X60387Y207361D01*
G01X65637Y250661D02*
Y258661D01*
X83237D01*
Y250661D01*
X65637D01*
G01X54767Y261792D02*
X54517Y261917D01*
X54225Y262000D01*
X53892D01*
X53517Y261875D01*
X53225Y261667D01*
X53017Y261417D01*
X52850Y261000D01*
X52808Y260625D01*
X52892Y260250D01*
X53017Y260000D01*
X53267Y259750D01*
X53558Y259583D01*
X53850Y259500D01*
X54142D01*
X54433Y259583D01*
X54683Y259708D01*
X54892Y259875D01*
G01X56033Y260000D02*
X56283Y259708D01*
X56617Y259542D01*
X56992Y259500D01*
X57325Y259542D01*
X57658Y259750D01*
X57867Y260000D01*
X57908Y260250D01*
X57825Y260542D01*
X57533Y260750D01*
X57242Y260833D01*
X56867D01*
G01X57242D02*
X57492Y260958D01*
X57700Y261167D01*
X57783Y261417D01*
X57700Y261667D01*
X57492Y261875D01*
X57117Y262000D01*
X56742Y261958D01*
X56367Y261792D01*
G01X59133Y259875D02*
X59383Y259667D01*
X59675Y259542D01*
X60050Y259500D01*
X60425Y259583D01*
X60717Y259750D01*
X60925Y260042D01*
X60967Y260375D01*
X60883Y260708D01*
X60675Y260917D01*
X60383Y261083D01*
X60092Y261125D01*
X59800Y261083D01*
X59425Y260917D01*
X59550Y262000D01*
X60675D01*
G01X62358Y260542D02*
X62650Y260833D01*
X62900Y261000D01*
X63233Y261083D01*
X63525Y261000D01*
X63733Y260833D01*
X63900Y260583D01*
X63942Y260292D01*
X63900Y260042D01*
X63733Y259792D01*
X63483Y259583D01*
X63192Y259500D01*
X62858Y259583D01*
X62567Y259833D01*
X62400Y260208D01*
X62358Y260625D01*
X62442Y261167D01*
X62567Y261458D01*
X62775Y261750D01*
X63067Y261958D01*
X63358Y262000D01*
X63650Y261917D01*
X63858Y261708D01*
G01X75637Y236161D02*
X70137D01*
G01D02*
Y244161D01*
G01D02*
X75637D01*
G01X46000Y222850D02*
X45958Y222517D01*
X45792Y222225D01*
X45542Y221975D01*
X45250Y221808D01*
X44917Y221725D01*
X44583D01*
X44250Y221808D01*
X43958Y221975D01*
X43708Y222225D01*
X43542Y222517D01*
X43500Y222850D01*
X43542Y223183D01*
X43708Y223475D01*
X43958Y223725D01*
X44250Y223892D01*
X44583Y223975D01*
X44917D01*
X45250Y223892D01*
X45542Y223725D01*
X45792Y223475D01*
X45958Y223183D01*
X46000Y222850D01*
G01X45333Y223183D02*
X46000Y223683D01*
G01Y225950D02*
X43500D01*
X44000Y225450D01*
G01X46000D02*
Y226450D01*
G01Y229550D02*
X43500D01*
X45292Y228008D01*
Y230092D01*
G01X44958Y231358D02*
X44667Y231650D01*
X44500Y231900D01*
X44417Y232233D01*
X44500Y232525D01*
X44667Y232733D01*
X44917Y232900D01*
X45208Y232942D01*
X45458Y232900D01*
X45708Y232733D01*
X45917Y232483D01*
X46000Y232192D01*
X45917Y231858D01*
X45667Y231567D01*
X45292Y231400D01*
X44875Y231358D01*
X44333Y231442D01*
X44042Y231567D01*
X43750Y231775D01*
X43542Y232067D01*
X43500Y232358D01*
X43583Y232650D01*
X43792Y232858D01*
G01X47637Y230061D02*
X66837D01*
Y241261D01*
X47637D01*
Y230061D01*
X48037D01*
G01X47737Y237661D02*
X49837Y235861D01*
X47737Y233661D01*
G01X44704Y215953D02*
X44454Y216078D01*
X44162Y216161D01*
X43829D01*
X43454Y216036D01*
X43162Y215828D01*
X42954Y215578D01*
X42787Y215161D01*
X42745Y214786D01*
X42829Y214411D01*
X42954Y214161D01*
X43204Y213911D01*
X43495Y213744D01*
X43787Y213661D01*
X44079D01*
X44370Y213744D01*
X44620Y213869D01*
X44829Y214036D01*
G01X45970Y214161D02*
X46220Y213869D01*
X46554Y213703D01*
X46929Y213661D01*
X47262Y213703D01*
X47595Y213911D01*
X47804Y214161D01*
X47845Y214411D01*
X47762Y214703D01*
X47470Y214911D01*
X47179Y214994D01*
X46804D01*
G01X47179D02*
X47429Y215119D01*
X47637Y215328D01*
X47720Y215578D01*
X47637Y215828D01*
X47429Y216036D01*
X47054Y216161D01*
X46679Y216119D01*
X46304Y215953D01*
G01X49195Y214703D02*
X49487Y214994D01*
X49737Y215161D01*
X50070Y215244D01*
X50362Y215161D01*
X50570Y214994D01*
X50737Y214744D01*
X50779Y214453D01*
X50737Y214203D01*
X50570Y213953D01*
X50320Y213744D01*
X50029Y213661D01*
X49695Y213744D01*
X49404Y213994D01*
X49237Y214369D01*
X49195Y214786D01*
X49279Y215328D01*
X49404Y215619D01*
X49612Y215911D01*
X49904Y216119D01*
X50195Y216161D01*
X50487Y216078D01*
X50695Y215869D01*
G01X53087Y213661D02*
Y216161D01*
X52587Y215661D01*
G01Y213661D02*
X53587D01*
G01X71517Y271500D02*
Y274000D01*
X72558D01*
X72892Y273875D01*
X73100Y273708D01*
X73183Y273375D01*
X73100Y273042D01*
X72850Y272833D01*
X72558Y272708D01*
X71517D01*
G01X72558D02*
X73183Y271500D01*
G01X74658Y272542D02*
X74950Y272833D01*
X75200Y273000D01*
X75533Y273083D01*
X75825Y273000D01*
X76033Y272833D01*
X76200Y272583D01*
X76242Y272292D01*
X76200Y272042D01*
X76033Y271792D01*
X75783Y271583D01*
X75492Y271500D01*
X75158Y271583D01*
X74867Y271833D01*
X74700Y272208D01*
X74658Y272625D01*
X74742Y273167D01*
X74867Y273458D01*
X75075Y273750D01*
X75367Y273958D01*
X75658Y274000D01*
X75950Y273917D01*
X76158Y273708D01*
G01X78550Y271500D02*
X78842Y271542D01*
X79175Y271667D01*
X79383Y271875D01*
X79467Y272167D01*
X79383Y272458D01*
X79133Y272708D01*
X78758Y272833D01*
X78342D01*
X78092Y272917D01*
X77883Y273125D01*
X77800Y273417D01*
X77925Y273708D01*
X78217Y273917D01*
X78550Y274000D01*
X78883Y273917D01*
X79175Y273708D01*
X79300Y273417D01*
X79217Y273125D01*
X79008Y272917D01*
X78758Y272833D01*
X78342D01*
X77967Y272708D01*
X77717Y272458D01*
X77633Y272167D01*
X77717Y271875D01*
X77925Y271667D01*
X78258Y271542D01*
X78550Y271500D01*
G01X80733Y272000D02*
X80983Y271708D01*
X81317Y271542D01*
X81692Y271500D01*
X82025Y271542D01*
X82358Y271750D01*
X82567Y272000D01*
X82608Y272250D01*
X82525Y272542D01*
X82233Y272750D01*
X81942Y272833D01*
X81567D01*
G01X81942D02*
X82192Y272958D01*
X82400Y273167D01*
X82483Y273417D01*
X82400Y273667D01*
X82192Y273875D01*
X81817Y274000D01*
X81442Y273958D01*
X81067Y273792D01*
G01X73267Y265792D02*
X73017Y265917D01*
X72725Y266000D01*
X72392D01*
X72017Y265875D01*
X71725Y265667D01*
X71517Y265417D01*
X71350Y265000D01*
X71308Y264625D01*
X71392Y264250D01*
X71517Y264000D01*
X71767Y263750D01*
X72058Y263583D01*
X72350Y263500D01*
X72642D01*
X72933Y263583D01*
X73183Y263708D01*
X73392Y263875D01*
G01X74533Y264000D02*
X74783Y263708D01*
X75117Y263542D01*
X75492Y263500D01*
X75825Y263542D01*
X76158Y263750D01*
X76367Y264000D01*
X76408Y264250D01*
X76325Y264542D01*
X76033Y264750D01*
X75742Y264833D01*
X75367D01*
G01X75742D02*
X75992Y264958D01*
X76200Y265167D01*
X76283Y265417D01*
X76200Y265667D01*
X75992Y265875D01*
X75617Y266000D01*
X75242Y265958D01*
X74867Y265792D01*
G01X77633Y263875D02*
X77883Y263667D01*
X78175Y263542D01*
X78550Y263500D01*
X78925Y263583D01*
X79217Y263750D01*
X79425Y264042D01*
X79467Y264375D01*
X79383Y264708D01*
X79175Y264917D01*
X78883Y265083D01*
X78592Y265125D01*
X78300Y265083D01*
X77925Y264917D01*
X78050Y266000D01*
X79175D01*
G01X80733Y264000D02*
X80983Y263708D01*
X81317Y263542D01*
X81692Y263500D01*
X82025Y263542D01*
X82358Y263750D01*
X82567Y264000D01*
X82608Y264250D01*
X82525Y264542D01*
X82233Y264750D01*
X81942Y264833D01*
X81567D01*
G01X81942D02*
X82192Y264958D01*
X82400Y265167D01*
X82483Y265417D01*
X82400Y265667D01*
X82192Y265875D01*
X81817Y266000D01*
X81442Y265958D01*
X81067Y265792D01*
G01X73267Y269792D02*
X73017Y269917D01*
X72725Y270000D01*
X72392D01*
X72017Y269875D01*
X71725Y269667D01*
X71517Y269417D01*
X71350Y269000D01*
X71308Y268625D01*
X71392Y268250D01*
X71517Y268000D01*
X71767Y267750D01*
X72058Y267583D01*
X72350Y267500D01*
X72642D01*
X72933Y267583D01*
X73183Y267708D01*
X73392Y267875D01*
G01X74533Y268000D02*
X74783Y267708D01*
X75117Y267542D01*
X75492Y267500D01*
X75825Y267542D01*
X76158Y267750D01*
X76367Y268000D01*
X76408Y268250D01*
X76325Y268542D01*
X76033Y268750D01*
X75742Y268833D01*
X75367D01*
G01X75742D02*
X75992Y268958D01*
X76200Y269167D01*
X76283Y269417D01*
X76200Y269667D01*
X75992Y269875D01*
X75617Y270000D01*
X75242Y269958D01*
X74867Y269792D01*
G01X77633Y267875D02*
X77883Y267667D01*
X78175Y267542D01*
X78550Y267500D01*
X78925Y267583D01*
X79217Y267750D01*
X79425Y268042D01*
X79467Y268375D01*
X79383Y268708D01*
X79175Y268917D01*
X78883Y269083D01*
X78592Y269125D01*
X78300Y269083D01*
X77925Y268917D01*
X78050Y270000D01*
X79175D01*
G01X80858Y269583D02*
X81108Y269833D01*
X81400Y269958D01*
X81733Y270000D01*
X82150Y269917D01*
X82442Y269708D01*
X82525Y269458D01*
X82483Y269208D01*
X82317Y269000D01*
X81483Y268583D01*
X81108Y268292D01*
X80858Y267875D01*
X80775Y267500D01*
X82525D01*
G01X63037Y381654D02*
Y384154D01*
X64621D01*
G01X64037Y382946D02*
X63037D01*
G01X66096Y384154D02*
Y381654D01*
X67762D01*
G01X70862D02*
X69196D01*
Y384154D01*
X70862D01*
G01X70196Y382946D02*
X69196D01*
G01X72212Y381654D02*
Y384154D01*
X73046D01*
X73379Y384029D01*
X73629Y383862D01*
X73837Y383612D01*
X74004Y383321D01*
X74046Y382904D01*
X74004Y382487D01*
X73837Y382196D01*
X73629Y381946D01*
X73379Y381779D01*
X73046Y381654D01*
X72212D01*
G01X76229D02*
Y384154D01*
X75729Y383654D01*
G01Y381654D02*
X76729D01*
G01X78412Y382154D02*
X78662Y381862D01*
X78996Y381696D01*
X79371Y381654D01*
X79704Y381696D01*
X80037Y381904D01*
X80246Y382154D01*
X80287Y382404D01*
X80204Y382696D01*
X79912Y382904D01*
X79621Y382987D01*
X79246D01*
G01X79621D02*
X79871Y383112D01*
X80079Y383321D01*
X80162Y383571D01*
X80079Y383821D01*
X79871Y384029D01*
X79496Y384154D01*
X79121Y384112D01*
X78746Y383946D01*
G01X65679Y366054D02*
Y377254D01*
X74479D01*
Y366054D01*
X65679D01*
G01X38578Y491684D02*
X38245Y491726D01*
X37953Y491892D01*
X37703Y492142D01*
X37536Y492434D01*
X37453Y492767D01*
Y493101D01*
X37536Y493434D01*
X37703Y493726D01*
X37953Y493976D01*
X38245Y494142D01*
X38578Y494184D01*
X38911Y494142D01*
X39203Y493976D01*
X39453Y493726D01*
X39620Y493434D01*
X39703Y493101D01*
Y492767D01*
X39620Y492434D01*
X39453Y492142D01*
X39203Y491892D01*
X38911Y491726D01*
X38578Y491684D01*
G01X38911Y492351D02*
X39411Y491684D01*
G01X40886Y493767D02*
X41136Y494017D01*
X41428Y494142D01*
X41761Y494184D01*
X42178Y494101D01*
X42470Y493892D01*
X42553Y493642D01*
X42511Y493392D01*
X42345Y493184D01*
X41511Y492767D01*
X41136Y492476D01*
X40886Y492059D01*
X40803Y491684D01*
X42553D01*
G01X44695D02*
X44778Y492226D01*
X44903Y492684D01*
X45070Y493101D01*
X45278Y493559D01*
X45611Y494184D01*
X43945D01*
G01X46961Y492059D02*
X47211Y491851D01*
X47503Y491726D01*
X47878Y491684D01*
X48253Y491767D01*
X48545Y491934D01*
X48753Y492226D01*
X48795Y492559D01*
X48711Y492892D01*
X48503Y493101D01*
X48211Y493267D01*
X47920Y493309D01*
X47628Y493267D01*
X47253Y493101D01*
X47378Y494184D01*
X48503D01*
G01X50228Y496184D02*
Y510184D01*
G01X37228Y496184D02*
X50228D01*
G01X37228Y510184D02*
Y496184D01*
G01X52813Y491647D02*
X52480Y491689D01*
X52188Y491855D01*
X51938Y492105D01*
X51771Y492397D01*
X51688Y492730D01*
Y493064D01*
X51771Y493397D01*
X51938Y493689D01*
X52188Y493939D01*
X52480Y494105D01*
X52813Y494147D01*
X53146Y494105D01*
X53438Y493939D01*
X53688Y493689D01*
X53855Y493397D01*
X53938Y493064D01*
Y492730D01*
X53855Y492397D01*
X53688Y492105D01*
X53438Y491855D01*
X53146Y491689D01*
X52813Y491647D01*
G01X53146Y492314D02*
X53646Y491647D01*
G01X55121Y493730D02*
X55371Y493980D01*
X55663Y494105D01*
X55996Y494147D01*
X56413Y494064D01*
X56705Y493855D01*
X56788Y493605D01*
X56746Y493355D01*
X56580Y493147D01*
X55746Y492730D01*
X55371Y492439D01*
X55121Y492022D01*
X55038Y491647D01*
X56788D01*
G01X58096Y492147D02*
X58346Y491855D01*
X58680Y491689D01*
X59055Y491647D01*
X59388Y491689D01*
X59721Y491897D01*
X59930Y492147D01*
X59971Y492397D01*
X59888Y492689D01*
X59596Y492897D01*
X59305Y492980D01*
X58930D01*
G01X59305D02*
X59555Y493105D01*
X59763Y493314D01*
X59846Y493564D01*
X59763Y493814D01*
X59555Y494022D01*
X59180Y494147D01*
X58805Y494105D01*
X58430Y493939D01*
G01X61405Y491939D02*
X61696Y491730D01*
X62030Y491647D01*
X62363Y491730D01*
X62655Y491980D01*
X62863Y492355D01*
X62946Y492730D01*
Y493189D01*
X62863Y493564D01*
X62655Y493897D01*
X62405Y494064D01*
X62113Y494147D01*
X61780Y494064D01*
X61530Y493897D01*
X61363Y493647D01*
X61280Y493314D01*
X61363Y493022D01*
X61571Y492730D01*
X61821Y492564D01*
X62113Y492522D01*
X62446Y492605D01*
X62696Y492814D01*
X62946Y493189D01*
G01X64463Y496147D02*
Y510147D01*
G01X51463Y496147D02*
X64463D01*
G01X51463Y510147D02*
Y496147D01*
G01X53601Y523020D02*
Y525520D01*
X54642D01*
X54976Y525395D01*
X55184Y525228D01*
X55267Y524895D01*
X55184Y524562D01*
X54934Y524353D01*
X54642Y524228D01*
X53601D01*
G01X54642D02*
X55267Y523020D01*
G01X56617Y523395D02*
X56867Y523187D01*
X57159Y523062D01*
X57534Y523020D01*
X57909Y523103D01*
X58201Y523270D01*
X58409Y523562D01*
X58451Y523895D01*
X58367Y524228D01*
X58159Y524437D01*
X57867Y524603D01*
X57576Y524645D01*
X57284Y524603D01*
X56909Y524437D01*
X57034Y525520D01*
X58159D01*
G01X60634D02*
X60301Y525437D01*
X60051Y525228D01*
X59884Y524978D01*
X59759Y524645D01*
X59717Y524270D01*
X59759Y523895D01*
X59884Y523562D01*
X60051Y523312D01*
X60301Y523103D01*
X60634Y523020D01*
X60967Y523103D01*
X61217Y523312D01*
X61384Y523562D01*
X61509Y523895D01*
X61551Y524270D01*
X61509Y524645D01*
X61384Y524978D01*
X61217Y525228D01*
X60967Y525437D01*
X60634Y525520D01*
G01X62817Y523520D02*
X63067Y523228D01*
X63401Y523062D01*
X63776Y523020D01*
X64109Y523062D01*
X64442Y523270D01*
X64651Y523520D01*
X64692Y523770D01*
X64609Y524062D01*
X64317Y524270D01*
X64026Y524353D01*
X63651D01*
G01X64026D02*
X64276Y524478D01*
X64484Y524687D01*
X64567Y524937D01*
X64484Y525187D01*
X64276Y525395D01*
X63901Y525520D01*
X63526Y525478D01*
X63151Y525312D01*
G01X63784Y511020D02*
Y515020D01*
X56384D01*
G01X39374Y523016D02*
Y525516D01*
X40415D01*
X40749Y525391D01*
X40957Y525224D01*
X41040Y524891D01*
X40957Y524558D01*
X40707Y524349D01*
X40415Y524224D01*
X39374D01*
G01X40415D02*
X41040Y523016D01*
G01X42390Y523391D02*
X42640Y523183D01*
X42932Y523058D01*
X43307Y523016D01*
X43682Y523099D01*
X43974Y523266D01*
X44182Y523558D01*
X44224Y523891D01*
X44140Y524224D01*
X43932Y524433D01*
X43640Y524599D01*
X43349Y524641D01*
X43057Y524599D01*
X42682Y524433D01*
X42807Y525516D01*
X43932D01*
G01X46407D02*
X46074Y525433D01*
X45824Y525224D01*
X45657Y524974D01*
X45532Y524641D01*
X45490Y524266D01*
X45532Y523891D01*
X45657Y523558D01*
X45824Y523308D01*
X46074Y523099D01*
X46407Y523016D01*
X46740Y523099D01*
X46990Y523308D01*
X47157Y523558D01*
X47282Y523891D01*
X47324Y524266D01*
X47282Y524641D01*
X47157Y524974D01*
X46990Y525224D01*
X46740Y525433D01*
X46407Y525516D01*
G01X49507Y523016D02*
Y525516D01*
X49007Y525016D01*
G01Y523016D02*
X50007D01*
G01X49557Y511016D02*
Y515016D01*
X42157D01*
G01X50228Y510184D02*
X37228D01*
G01X64463Y510147D02*
X51463D01*
G01X50417Y626400D02*
Y628900D01*
X51458D01*
X51792Y628775D01*
X52000Y628608D01*
X52083Y628275D01*
X52000Y627942D01*
X51750Y627733D01*
X51458Y627608D01*
X50417D01*
G01X51458D02*
X52083Y626400D01*
G01X54850D02*
Y628900D01*
X53308Y627108D01*
X55392D01*
G01X56658Y628483D02*
X56908Y628733D01*
X57200Y628858D01*
X57533Y628900D01*
X57950Y628817D01*
X58242Y628608D01*
X58325Y628358D01*
X58283Y628108D01*
X58117Y627900D01*
X57283Y627483D01*
X56908Y627192D01*
X56658Y626775D01*
X56575Y626400D01*
X58325D01*
G01X60550Y628900D02*
X60217Y628817D01*
X59967Y628608D01*
X59800Y628358D01*
X59675Y628025D01*
X59633Y627650D01*
X59675Y627275D01*
X59800Y626942D01*
X59967Y626692D01*
X60217Y626483D01*
X60550Y626400D01*
X60883Y626483D01*
X61133Y626692D01*
X61300Y626942D01*
X61425Y627275D01*
X61467Y627650D01*
X61425Y628025D01*
X61300Y628358D01*
X61133Y628608D01*
X60883Y628817D01*
X60550Y628900D01*
G01X54637Y634317D02*
Y630317D01*
X62037D01*
G01X56500Y636017D02*
X54000D01*
Y637058D01*
X54125Y637392D01*
X54292Y637600D01*
X54625Y637683D01*
X54958Y637600D01*
X55167Y637350D01*
X55292Y637058D01*
Y636017D01*
G01Y637058D02*
X56500Y637683D01*
G01Y640450D02*
X54000D01*
X55792Y638908D01*
Y640992D01*
G01X54417Y642258D02*
X54167Y642508D01*
X54042Y642800D01*
X54000Y643133D01*
X54083Y643550D01*
X54292Y643842D01*
X54542Y643925D01*
X54792Y643883D01*
X55000Y643717D01*
X55417Y642883D01*
X55708Y642508D01*
X56125Y642258D01*
X56500Y642175D01*
Y643925D01*
G01X54417Y645358D02*
X54167Y645608D01*
X54042Y645900D01*
X54000Y646233D01*
X54083Y646650D01*
X54292Y646942D01*
X54542Y647025D01*
X54792Y646983D01*
X55000Y646817D01*
X55417Y645983D01*
X55708Y645608D01*
X56125Y645358D01*
X56500Y645275D01*
Y647025D01*
G01X57937Y634717D02*
X61937D01*
Y642117D01*
G01X71900Y616017D02*
X69400D01*
Y617058D01*
X69525Y617392D01*
X69692Y617600D01*
X70025Y617683D01*
X70358Y617600D01*
X70567Y617350D01*
X70692Y617058D01*
Y616017D01*
G01Y617058D02*
X71900Y617683D01*
G01Y620450D02*
X69400D01*
X71192Y618908D01*
Y620992D01*
G01X69817Y622258D02*
X69567Y622508D01*
X69442Y622800D01*
X69400Y623133D01*
X69483Y623550D01*
X69692Y623842D01*
X69942Y623925D01*
X70192Y623883D01*
X70400Y623717D01*
X70817Y622883D01*
X71108Y622508D01*
X71525Y622258D01*
X71900Y622175D01*
Y623925D01*
G01X71400Y625233D02*
X71692Y625483D01*
X71858Y625817D01*
X71900Y626192D01*
X71858Y626525D01*
X71650Y626858D01*
X71400Y627067D01*
X71150Y627108D01*
X70858Y627025D01*
X70650Y626733D01*
X70567Y626442D01*
Y626067D01*
G01Y626442D02*
X70442Y626692D01*
X70233Y626900D01*
X69983Y626983D01*
X69733Y626900D01*
X69525Y626692D01*
X69400Y626317D01*
X69442Y625942D01*
X69608Y625567D01*
G01X74837Y636117D02*
X70837D01*
Y628717D01*
G01X67500Y618983D02*
X65000D01*
Y619817D01*
X65125Y620150D01*
X65292Y620400D01*
X65542Y620608D01*
X65833Y620775D01*
X66250Y620817D01*
X66667Y620775D01*
X66958Y620608D01*
X67208Y620400D01*
X67375Y620150D01*
X67500Y619817D01*
Y618983D01*
G01Y623000D02*
X65000D01*
X65500Y622500D01*
G01X67500D02*
Y623500D01*
G01X65417Y625308D02*
X65167Y625558D01*
X65042Y625850D01*
X65000Y626183D01*
X65083Y626600D01*
X65292Y626892D01*
X65542Y626975D01*
X65792Y626933D01*
X66000Y626767D01*
X66417Y625933D01*
X66708Y625558D01*
X67125Y625308D01*
X67500Y625225D01*
Y626975D01*
G01X69937Y644917D02*
Y628817D01*
G01X62937Y644917D02*
X69937D01*
G01X62937Y628817D02*
Y644917D01*
G01X69937Y628817D02*
X62937D01*
G01X50754Y653917D02*
Y656417D01*
X51795D01*
X52129Y656292D01*
X52337Y656125D01*
X52420Y655792D01*
X52337Y655459D01*
X52087Y655250D01*
X51795Y655125D01*
X50754D01*
G01X51795D02*
X52420Y653917D01*
G01X55187D02*
Y656417D01*
X53645Y654625D01*
X55729D01*
G01X57787Y653917D02*
Y656417D01*
X57287Y655917D01*
G01Y653917D02*
X58287D01*
G01X59970Y654417D02*
X60220Y654125D01*
X60554Y653959D01*
X60929Y653917D01*
X61262Y653959D01*
X61595Y654167D01*
X61804Y654417D01*
X61845Y654667D01*
X61762Y654959D01*
X61470Y655167D01*
X61179Y655250D01*
X60804D01*
G01X61179D02*
X61429Y655375D01*
X61637Y655584D01*
X61720Y655834D01*
X61637Y656084D01*
X61429Y656292D01*
X61054Y656417D01*
X60679Y656375D01*
X60304Y656209D01*
G01X62537Y659917D02*
Y655917D01*
X69937D01*
G01X42454Y662317D02*
Y664817D01*
X43495D01*
X43829Y664692D01*
X44037Y664525D01*
X44120Y664192D01*
X44037Y663859D01*
X43787Y663650D01*
X43495Y663525D01*
X42454D01*
G01X43495D02*
X44120Y662317D01*
G01X46887D02*
Y664817D01*
X45345Y663025D01*
X47429D01*
G01X48695Y664400D02*
X48945Y664650D01*
X49237Y664775D01*
X49570Y664817D01*
X49987Y664734D01*
X50279Y664525D01*
X50362Y664275D01*
X50320Y664025D01*
X50154Y663817D01*
X49320Y663400D01*
X48945Y663109D01*
X48695Y662692D01*
X48612Y662317D01*
X50362D01*
G01X52587D02*
Y664817D01*
X52087Y664317D01*
G01Y662317D02*
X53087D01*
G01X62137Y661317D02*
Y665317D01*
X54737D01*
G01X25593Y694869D02*
Y690869D01*
X32993D01*
G01X25226Y669518D02*
Y665518D01*
X32626D01*
G01X33322Y671683D02*
Y685683D01*
G01X70137Y688917D02*
Y696917D01*
G01X75637Y688917D02*
X70137D01*
G01X45500Y675400D02*
X45458Y675067D01*
X45292Y674775D01*
X45042Y674525D01*
X44750Y674358D01*
X44417Y674275D01*
X44083D01*
X43750Y674358D01*
X43458Y674525D01*
X43208Y674775D01*
X43042Y675067D01*
X43000Y675400D01*
X43042Y675733D01*
X43208Y676025D01*
X43458Y676275D01*
X43750Y676442D01*
X44083Y676525D01*
X44417D01*
X44750Y676442D01*
X45042Y676275D01*
X45292Y676025D01*
X45458Y675733D01*
X45500Y675400D01*
G01X44833Y675733D02*
X45500Y676233D01*
G01Y678417D02*
X44958Y678500D01*
X44500Y678625D01*
X44083Y678792D01*
X43625Y679000D01*
X43000Y679333D01*
Y677667D01*
G01X45500Y682100D02*
X43000D01*
X44792Y680558D01*
Y682642D01*
G01X47737Y690417D02*
X49837Y688617D01*
X47737Y686417D01*
G01X47637Y682817D02*
X66837D01*
Y694017D01*
X47637D01*
Y682817D01*
X48037D01*
G01X44204Y668709D02*
X43954Y668834D01*
X43662Y668917D01*
X43329D01*
X42954Y668792D01*
X42662Y668584D01*
X42454Y668334D01*
X42287Y667917D01*
X42245Y667542D01*
X42329Y667167D01*
X42454Y666917D01*
X42704Y666667D01*
X42995Y666500D01*
X43287Y666417D01*
X43579D01*
X43870Y666500D01*
X44120Y666625D01*
X44329Y666792D01*
G01X45595Y668500D02*
X45845Y668750D01*
X46137Y668875D01*
X46470Y668917D01*
X46887Y668834D01*
X47179Y668625D01*
X47262Y668375D01*
X47220Y668125D01*
X47054Y667917D01*
X46220Y667500D01*
X45845Y667209D01*
X45595Y666792D01*
X45512Y666417D01*
X47262D01*
G01X49487Y668917D02*
X49154Y668834D01*
X48904Y668625D01*
X48737Y668375D01*
X48612Y668042D01*
X48570Y667667D01*
X48612Y667292D01*
X48737Y666959D01*
X48904Y666709D01*
X49154Y666500D01*
X49487Y666417D01*
X49820Y666500D01*
X50070Y666709D01*
X50237Y666959D01*
X50362Y667292D01*
X50404Y667667D01*
X50362Y668042D01*
X50237Y668375D01*
X50070Y668625D01*
X49820Y668834D01*
X49487Y668917D01*
G01X51670Y666792D02*
X51920Y666584D01*
X52212Y666459D01*
X52587Y666417D01*
X52962Y666500D01*
X53254Y666667D01*
X53462Y666959D01*
X53504Y667292D01*
X53420Y667625D01*
X53212Y667834D01*
X52920Y668000D01*
X52629Y668042D01*
X52337Y668000D01*
X51962Y667834D01*
X52087Y668917D01*
X53212D01*
G01X52504Y660309D02*
X52254Y660434D01*
X51962Y660517D01*
X51629D01*
X51254Y660392D01*
X50962Y660184D01*
X50754Y659934D01*
X50587Y659517D01*
X50545Y659142D01*
X50629Y658767D01*
X50754Y658517D01*
X51004Y658267D01*
X51295Y658100D01*
X51587Y658017D01*
X51879D01*
X52170Y658100D01*
X52420Y658225D01*
X52629Y658392D01*
G01X53895Y660100D02*
X54145Y660350D01*
X54437Y660475D01*
X54770Y660517D01*
X55187Y660434D01*
X55479Y660225D01*
X55562Y659975D01*
X55520Y659725D01*
X55354Y659517D01*
X54520Y659100D01*
X54145Y658809D01*
X53895Y658392D01*
X53812Y658017D01*
X55562D01*
G01X57787Y660517D02*
X57454Y660434D01*
X57204Y660225D01*
X57037Y659975D01*
X56912Y659642D01*
X56870Y659267D01*
X56912Y658892D01*
X57037Y658559D01*
X57204Y658309D01*
X57454Y658100D01*
X57787Y658017D01*
X58120Y658100D01*
X58370Y658309D01*
X58537Y658559D01*
X58662Y658892D01*
X58704Y659267D01*
X58662Y659642D01*
X58537Y659975D01*
X58370Y660225D01*
X58120Y660434D01*
X57787Y660517D01*
G01X61387Y658017D02*
Y660517D01*
X59845Y658725D01*
X61929D01*
G01X71517Y723500D02*
Y726000D01*
X72558D01*
X72892Y725875D01*
X73100Y725708D01*
X73183Y725375D01*
X73100Y725042D01*
X72850Y724833D01*
X72558Y724708D01*
X71517D01*
G01X72558D02*
X73183Y723500D01*
G01X75950D02*
Y726000D01*
X74408Y724208D01*
X76492D01*
G01X78550Y726000D02*
X78217Y725917D01*
X77967Y725708D01*
X77800Y725458D01*
X77675Y725125D01*
X77633Y724750D01*
X77675Y724375D01*
X77800Y724042D01*
X77967Y723792D01*
X78217Y723583D01*
X78550Y723500D01*
X78883Y723583D01*
X79133Y723792D01*
X79300Y724042D01*
X79425Y724375D01*
X79467Y724750D01*
X79425Y725125D01*
X79300Y725458D01*
X79133Y725708D01*
X78883Y725917D01*
X78550Y726000D01*
G01X81567Y723500D02*
X81650Y724042D01*
X81775Y724500D01*
X81942Y724917D01*
X82150Y725375D01*
X82483Y726000D01*
X80817D01*
G01X65637Y703417D02*
Y711417D01*
X83237D01*
Y703417D01*
X65637D01*
G01X33689Y697034D02*
Y711034D01*
G01X55267Y715292D02*
X55017Y715417D01*
X54725Y715500D01*
X54392D01*
X54017Y715375D01*
X53725Y715167D01*
X53517Y714917D01*
X53350Y714500D01*
X53308Y714125D01*
X53392Y713750D01*
X53517Y713500D01*
X53767Y713250D01*
X54058Y713083D01*
X54350Y713000D01*
X54642D01*
X54933Y713083D01*
X55183Y713208D01*
X55392Y713375D01*
G01X56658Y715083D02*
X56908Y715333D01*
X57200Y715458D01*
X57533Y715500D01*
X57950Y715417D01*
X58242Y715208D01*
X58325Y714958D01*
X58283Y714708D01*
X58117Y714500D01*
X57283Y714083D01*
X56908Y713792D01*
X56658Y713375D01*
X56575Y713000D01*
X58325D01*
G01X60550Y715500D02*
X60217Y715417D01*
X59967Y715208D01*
X59800Y714958D01*
X59675Y714625D01*
X59633Y714250D01*
X59675Y713875D01*
X59800Y713542D01*
X59967Y713292D01*
X60217Y713083D01*
X60550Y713000D01*
X60883Y713083D01*
X61133Y713292D01*
X61300Y713542D01*
X61425Y713875D01*
X61467Y714250D01*
X61425Y714625D01*
X61300Y714958D01*
X61133Y715208D01*
X60883Y715417D01*
X60550Y715500D01*
G01X63650Y713000D02*
Y715500D01*
X63150Y715000D01*
G01Y713000D02*
X64150D01*
G01X73267Y717792D02*
X73017Y717917D01*
X72725Y718000D01*
X72392D01*
X72017Y717875D01*
X71725Y717667D01*
X71517Y717417D01*
X71350Y717000D01*
X71308Y716625D01*
X71392Y716250D01*
X71517Y716000D01*
X71767Y715750D01*
X72058Y715583D01*
X72350Y715500D01*
X72642D01*
X72933Y715583D01*
X73183Y715708D01*
X73392Y715875D01*
G01X75450Y715500D02*
Y718000D01*
X74950Y717500D01*
G01Y715500D02*
X75950D01*
G01X77842Y715792D02*
X78133Y715583D01*
X78467Y715500D01*
X78800Y715583D01*
X79092Y715833D01*
X79300Y716208D01*
X79383Y716583D01*
Y717042D01*
X79300Y717417D01*
X79092Y717750D01*
X78842Y717917D01*
X78550Y718000D01*
X78217Y717917D01*
X77967Y717750D01*
X77800Y717500D01*
X77717Y717167D01*
X77800Y716875D01*
X78008Y716583D01*
X78258Y716417D01*
X78550Y716375D01*
X78883Y716458D01*
X79133Y716667D01*
X79383Y717042D01*
G01X81567Y715500D02*
X81650Y716042D01*
X81775Y716500D01*
X81942Y716917D01*
X82150Y717375D01*
X82483Y718000D01*
X80817D01*
G01X70137Y696917D02*
X75637D01*
G01X73267Y721792D02*
X73017Y721917D01*
X72725Y722000D01*
X72392D01*
X72017Y721875D01*
X71725Y721667D01*
X71517Y721417D01*
X71350Y721000D01*
X71308Y720625D01*
X71392Y720250D01*
X71517Y720000D01*
X71767Y719750D01*
X72058Y719583D01*
X72350Y719500D01*
X72642D01*
X72933Y719583D01*
X73183Y719708D01*
X73392Y719875D01*
G01X75450Y719500D02*
Y722000D01*
X74950Y721500D01*
G01Y719500D02*
X75950D01*
G01X77842Y719792D02*
X78133Y719583D01*
X78467Y719500D01*
X78800Y719583D01*
X79092Y719833D01*
X79300Y720208D01*
X79383Y720583D01*
Y721042D01*
X79300Y721417D01*
X79092Y721750D01*
X78842Y721917D01*
X78550Y722000D01*
X78217Y721917D01*
X77967Y721750D01*
X77800Y721500D01*
X77717Y721167D01*
X77800Y720875D01*
X78008Y720583D01*
X78258Y720417D01*
X78550Y720375D01*
X78883Y720458D01*
X79133Y720667D01*
X79383Y721042D01*
G01X80858Y720542D02*
X81150Y720833D01*
X81400Y721000D01*
X81733Y721083D01*
X82025Y721000D01*
X82233Y720833D01*
X82400Y720583D01*
X82442Y720292D01*
X82400Y720042D01*
X82233Y719792D01*
X81983Y719583D01*
X81692Y719500D01*
X81358Y719583D01*
X81067Y719833D01*
X80900Y720208D01*
X80858Y720625D01*
X80942Y721167D01*
X81067Y721458D01*
X81275Y721750D01*
X81567Y721958D01*
X81858Y722000D01*
X82150Y721917D01*
X82358Y721708D01*
G01X65679Y818809D02*
Y830009D01*
X74479D01*
Y818809D01*
X65679D01*
G01X62400Y949272D02*
X59900D01*
Y950313D01*
X60025Y950647D01*
X60192Y950855D01*
X60525Y950938D01*
X60858Y950855D01*
X61067Y950605D01*
X61192Y950313D01*
Y949272D01*
G01Y950313D02*
X62400Y950938D01*
G01Y953205D02*
X59900D01*
X60400Y952705D01*
G01X62400D02*
Y953705D01*
G01X62108Y955597D02*
X62317Y955888D01*
X62400Y956222D01*
X62317Y956555D01*
X62067Y956847D01*
X61692Y957055D01*
X61317Y957138D01*
X60858D01*
X60483Y957055D01*
X60150Y956847D01*
X59983Y956597D01*
X59900Y956305D01*
X59983Y955972D01*
X60150Y955722D01*
X60400Y955555D01*
X60733Y955472D01*
X61025Y955555D01*
X61317Y955763D01*
X61483Y956013D01*
X61525Y956305D01*
X61442Y956638D01*
X61233Y956888D01*
X60858Y957138D01*
G01X62025Y958488D02*
X62233Y958738D01*
X62358Y959030D01*
X62400Y959405D01*
X62317Y959780D01*
X62150Y960072D01*
X61858Y960280D01*
X61525Y960322D01*
X61192Y960238D01*
X60983Y960030D01*
X60817Y959738D01*
X60775Y959447D01*
X60817Y959155D01*
X60983Y958780D01*
X59900Y958905D01*
Y960030D01*
G01X73900Y1069017D02*
X71400D01*
Y1070058D01*
X71525Y1070392D01*
X71692Y1070600D01*
X72025Y1070683D01*
X72358Y1070600D01*
X72567Y1070350D01*
X72692Y1070058D01*
Y1069017D01*
G01Y1070058D02*
X73900Y1070683D01*
G01X73608Y1072242D02*
X73817Y1072533D01*
X73900Y1072867D01*
X73817Y1073200D01*
X73567Y1073492D01*
X73192Y1073700D01*
X72817Y1073783D01*
X72358D01*
X71983Y1073700D01*
X71650Y1073492D01*
X71483Y1073242D01*
X71400Y1072950D01*
X71483Y1072617D01*
X71650Y1072367D01*
X71900Y1072200D01*
X72233Y1072117D01*
X72525Y1072200D01*
X72817Y1072408D01*
X72983Y1072658D01*
X73025Y1072950D01*
X72942Y1073283D01*
X72733Y1073533D01*
X72358Y1073783D01*
G01X73900Y1075967D02*
X73358Y1076050D01*
X72900Y1076175D01*
X72483Y1076342D01*
X72025Y1076550D01*
X71400Y1076883D01*
Y1075217D01*
G01X73525Y1078233D02*
X73733Y1078483D01*
X73858Y1078775D01*
X73900Y1079150D01*
X73817Y1079525D01*
X73650Y1079817D01*
X73358Y1080025D01*
X73025Y1080067D01*
X72692Y1079983D01*
X72483Y1079775D01*
X72317Y1079483D01*
X72275Y1079192D01*
X72317Y1078900D01*
X72483Y1078525D01*
X71400Y1078650D01*
Y1079775D01*
G01X74837Y1088873D02*
X70837D01*
Y1081473D01*
G01X67045Y1070917D02*
X64545D01*
Y1071751D01*
X64670Y1072084D01*
X64837Y1072334D01*
X65087Y1072542D01*
X65378Y1072709D01*
X65795Y1072751D01*
X66212Y1072709D01*
X66503Y1072542D01*
X66753Y1072334D01*
X66920Y1072084D01*
X67045Y1071751D01*
Y1070917D01*
G01X66545Y1074017D02*
X66837Y1074267D01*
X67003Y1074601D01*
X67045Y1074976D01*
X67003Y1075309D01*
X66795Y1075642D01*
X66545Y1075851D01*
X66295Y1075892D01*
X66003Y1075809D01*
X65795Y1075517D01*
X65712Y1075226D01*
Y1074851D01*
G01Y1075226D02*
X65587Y1075476D01*
X65378Y1075684D01*
X65128Y1075767D01*
X64878Y1075684D01*
X64670Y1075476D01*
X64545Y1075101D01*
X64587Y1074726D01*
X64753Y1074351D01*
G01X66003Y1077242D02*
X65712Y1077534D01*
X65545Y1077784D01*
X65462Y1078117D01*
X65545Y1078409D01*
X65712Y1078617D01*
X65962Y1078784D01*
X66253Y1078826D01*
X66503Y1078784D01*
X66753Y1078617D01*
X66962Y1078367D01*
X67045Y1078076D01*
X66962Y1077742D01*
X66712Y1077451D01*
X66337Y1077284D01*
X65920Y1077242D01*
X65378Y1077326D01*
X65087Y1077451D01*
X64795Y1077659D01*
X64587Y1077951D01*
X64545Y1078242D01*
X64628Y1078534D01*
X64837Y1078742D01*
G01X69937Y1097673D02*
Y1081573D01*
G01X62937D02*
Y1097673D01*
G01X69937Y1081573D02*
X62937D01*
G01X49754Y1106173D02*
Y1108673D01*
X50795D01*
X51129Y1108548D01*
X51337Y1108381D01*
X51420Y1108048D01*
X51337Y1107715D01*
X51087Y1107506D01*
X50795Y1107381D01*
X49754D01*
G01X50795D02*
X51420Y1106173D01*
G01X52979Y1106465D02*
X53270Y1106256D01*
X53604Y1106173D01*
X53937Y1106256D01*
X54229Y1106506D01*
X54437Y1106881D01*
X54520Y1107256D01*
Y1107715D01*
X54437Y1108090D01*
X54229Y1108423D01*
X53979Y1108590D01*
X53687Y1108673D01*
X53354Y1108590D01*
X53104Y1108423D01*
X52937Y1108173D01*
X52854Y1107840D01*
X52937Y1107548D01*
X53145Y1107256D01*
X53395Y1107090D01*
X53687Y1107048D01*
X54020Y1107131D01*
X54270Y1107340D01*
X54520Y1107715D01*
G01X55995Y1107215D02*
X56287Y1107506D01*
X56537Y1107673D01*
X56870Y1107756D01*
X57162Y1107673D01*
X57370Y1107506D01*
X57537Y1107256D01*
X57579Y1106965D01*
X57537Y1106715D01*
X57370Y1106465D01*
X57120Y1106256D01*
X56829Y1106173D01*
X56495Y1106256D01*
X56204Y1106506D01*
X56037Y1106881D01*
X55995Y1107298D01*
X56079Y1107840D01*
X56204Y1108131D01*
X56412Y1108423D01*
X56704Y1108631D01*
X56995Y1108673D01*
X57287Y1108590D01*
X57495Y1108381D01*
G01X58970Y1106548D02*
X59220Y1106340D01*
X59512Y1106215D01*
X59887Y1106173D01*
X60262Y1106256D01*
X60554Y1106423D01*
X60762Y1106715D01*
X60804Y1107048D01*
X60720Y1107381D01*
X60512Y1107590D01*
X60220Y1107756D01*
X59929Y1107798D01*
X59637Y1107756D01*
X59262Y1107590D01*
X59387Y1108673D01*
X60512D01*
G01X62537Y1112673D02*
Y1108673D01*
X69937D01*
G01X40317Y1083900D02*
Y1086400D01*
X41358D01*
X41692Y1086275D01*
X41900Y1086108D01*
X41983Y1085775D01*
X41900Y1085442D01*
X41650Y1085233D01*
X41358Y1085108D01*
X40317D01*
G01X41358D02*
X41983Y1083900D01*
G01X43542Y1084192D02*
X43833Y1083983D01*
X44167Y1083900D01*
X44500Y1083983D01*
X44792Y1084233D01*
X45000Y1084608D01*
X45083Y1084983D01*
Y1085442D01*
X45000Y1085817D01*
X44792Y1086150D01*
X44542Y1086317D01*
X44250Y1086400D01*
X43917Y1086317D01*
X43667Y1086150D01*
X43500Y1085900D01*
X43417Y1085567D01*
X43500Y1085275D01*
X43708Y1084983D01*
X43958Y1084817D01*
X44250Y1084775D01*
X44583Y1084858D01*
X44833Y1085067D01*
X45083Y1085442D01*
G01X47267Y1083900D02*
X47350Y1084442D01*
X47475Y1084900D01*
X47642Y1085317D01*
X47850Y1085775D01*
X48183Y1086400D01*
X46517D01*
G01X49658Y1085983D02*
X49908Y1086233D01*
X50200Y1086358D01*
X50533Y1086400D01*
X50950Y1086317D01*
X51242Y1086108D01*
X51325Y1085858D01*
X51283Y1085608D01*
X51117Y1085400D01*
X50283Y1084983D01*
X49908Y1084692D01*
X49658Y1084275D01*
X49575Y1083900D01*
X51325D01*
G01X54537Y1087073D02*
Y1083073D01*
X61937D01*
G01X41454Y1114573D02*
Y1117073D01*
X42495D01*
X42829Y1116948D01*
X43037Y1116781D01*
X43120Y1116448D01*
X43037Y1116115D01*
X42787Y1115906D01*
X42495Y1115781D01*
X41454D01*
G01X42495D02*
X43120Y1114573D01*
G01X44679Y1114865D02*
X44970Y1114656D01*
X45304Y1114573D01*
X45637Y1114656D01*
X45929Y1114906D01*
X46137Y1115281D01*
X46220Y1115656D01*
Y1116115D01*
X46137Y1116490D01*
X45929Y1116823D01*
X45679Y1116990D01*
X45387Y1117073D01*
X45054Y1116990D01*
X44804Y1116823D01*
X44637Y1116573D01*
X44554Y1116240D01*
X44637Y1115948D01*
X44845Y1115656D01*
X45095Y1115490D01*
X45387Y1115448D01*
X45720Y1115531D01*
X45970Y1115740D01*
X46220Y1116115D01*
G01X48404Y1114573D02*
X48487Y1115115D01*
X48612Y1115573D01*
X48779Y1115990D01*
X48987Y1116448D01*
X49320Y1117073D01*
X47654D01*
G01X50670Y1115073D02*
X50920Y1114781D01*
X51254Y1114615D01*
X51629Y1114573D01*
X51962Y1114615D01*
X52295Y1114823D01*
X52504Y1115073D01*
X52545Y1115323D01*
X52462Y1115615D01*
X52170Y1115823D01*
X51879Y1115906D01*
X51504D01*
G01X51879D02*
X52129Y1116031D01*
X52337Y1116240D01*
X52420Y1116490D01*
X52337Y1116740D01*
X52129Y1116948D01*
X51754Y1117073D01*
X51379Y1117031D01*
X51004Y1116865D01*
G01X62137Y1114073D02*
Y1118073D01*
X54737D01*
G01X55955Y1089791D02*
X53455D01*
Y1090832D01*
X53580Y1091166D01*
X53747Y1091374D01*
X54080Y1091457D01*
X54413Y1091374D01*
X54622Y1091124D01*
X54747Y1090832D01*
Y1089791D01*
G01Y1090832D02*
X55955Y1091457D01*
G01X55663Y1093016D02*
X55872Y1093307D01*
X55955Y1093641D01*
X55872Y1093974D01*
X55622Y1094266D01*
X55247Y1094474D01*
X54872Y1094557D01*
X54413D01*
X54038Y1094474D01*
X53705Y1094266D01*
X53538Y1094016D01*
X53455Y1093724D01*
X53538Y1093391D01*
X53705Y1093141D01*
X53955Y1092974D01*
X54288Y1092891D01*
X54580Y1092974D01*
X54872Y1093182D01*
X55038Y1093432D01*
X55080Y1093724D01*
X54997Y1094057D01*
X54788Y1094307D01*
X54413Y1094557D01*
G01X55955Y1096741D02*
X55413Y1096824D01*
X54955Y1096949D01*
X54538Y1097116D01*
X54080Y1097324D01*
X53455Y1097657D01*
Y1095991D01*
G01X55955Y1100424D02*
X53455D01*
X55247Y1098882D01*
Y1100966D01*
G01X57937Y1087473D02*
X61937D01*
Y1094873D01*
G01X24806Y1122485D02*
Y1118485D01*
X32206D01*
G01X33295Y1124650D02*
Y1138650D01*
G01X73500Y1094350D02*
X73458Y1094017D01*
X73292Y1093725D01*
X73042Y1093475D01*
X72750Y1093308D01*
X72417Y1093225D01*
X72083D01*
X71750Y1093308D01*
X71458Y1093475D01*
X71208Y1093725D01*
X71042Y1094017D01*
X71000Y1094350D01*
X71042Y1094683D01*
X71208Y1094975D01*
X71458Y1095225D01*
X71750Y1095392D01*
X72083Y1095475D01*
X72417D01*
X72750Y1095392D01*
X73042Y1095225D01*
X73292Y1094975D01*
X73458Y1094683D01*
X73500Y1094350D01*
G01X72833Y1094683D02*
X73500Y1095183D01*
G01X71417Y1096658D02*
X71167Y1096908D01*
X71042Y1097200D01*
X71000Y1097533D01*
X71083Y1097950D01*
X71292Y1098242D01*
X71542Y1098325D01*
X71792Y1098283D01*
X72000Y1098117D01*
X72417Y1097283D01*
X72708Y1096908D01*
X73125Y1096658D01*
X73500Y1096575D01*
Y1098325D01*
G01Y1100550D02*
X71000D01*
X71500Y1100050D01*
G01X73500D02*
Y1101050D01*
G01Y1103567D02*
X72958Y1103650D01*
X72500Y1103775D01*
X72083Y1103942D01*
X71625Y1104150D01*
X71000Y1104483D01*
Y1102817D01*
G01X62937Y1097673D02*
X69937D01*
G01X43204Y1120965D02*
X42954Y1121090D01*
X42662Y1121173D01*
X42329D01*
X41954Y1121048D01*
X41662Y1120840D01*
X41454Y1120590D01*
X41287Y1120173D01*
X41245Y1119798D01*
X41329Y1119423D01*
X41454Y1119173D01*
X41704Y1118923D01*
X41995Y1118756D01*
X42287Y1118673D01*
X42579D01*
X42870Y1118756D01*
X43120Y1118881D01*
X43329Y1119048D01*
G01X44470D02*
X44720Y1118840D01*
X45012Y1118715D01*
X45387Y1118673D01*
X45762Y1118756D01*
X46054Y1118923D01*
X46262Y1119215D01*
X46304Y1119548D01*
X46220Y1119881D01*
X46012Y1120090D01*
X45720Y1120256D01*
X45429Y1120298D01*
X45137Y1120256D01*
X44762Y1120090D01*
X44887Y1121173D01*
X46012D01*
G01X48487Y1118673D02*
Y1121173D01*
X47987Y1120673D01*
G01Y1118673D02*
X48987D01*
G01X51504D02*
X51587Y1119215D01*
X51712Y1119673D01*
X51879Y1120090D01*
X52087Y1120548D01*
X52420Y1121173D01*
X50754D01*
G01X51504Y1112565D02*
X51254Y1112690D01*
X50962Y1112773D01*
X50629D01*
X50254Y1112648D01*
X49962Y1112440D01*
X49754Y1112190D01*
X49587Y1111773D01*
X49545Y1111398D01*
X49629Y1111023D01*
X49754Y1110773D01*
X50004Y1110523D01*
X50295Y1110356D01*
X50587Y1110273D01*
X50879D01*
X51170Y1110356D01*
X51420Y1110481D01*
X51629Y1110648D01*
G01X52770D02*
X53020Y1110440D01*
X53312Y1110315D01*
X53687Y1110273D01*
X54062Y1110356D01*
X54354Y1110523D01*
X54562Y1110815D01*
X54604Y1111148D01*
X54520Y1111481D01*
X54312Y1111690D01*
X54020Y1111856D01*
X53729Y1111898D01*
X53437Y1111856D01*
X53062Y1111690D01*
X53187Y1112773D01*
X54312D01*
G01X56787Y1110273D02*
Y1112773D01*
X56287Y1112273D01*
G01Y1110273D02*
X57287D01*
G01X59095Y1111315D02*
X59387Y1111606D01*
X59637Y1111773D01*
X59970Y1111856D01*
X60262Y1111773D01*
X60470Y1111606D01*
X60637Y1111356D01*
X60679Y1111065D01*
X60637Y1110815D01*
X60470Y1110565D01*
X60220Y1110356D01*
X59929Y1110273D01*
X59595Y1110356D01*
X59304Y1110606D01*
X59137Y1110981D01*
X59095Y1111398D01*
X59179Y1111940D01*
X59304Y1112231D01*
X59512Y1112523D01*
X59804Y1112731D01*
X60095Y1112773D01*
X60387Y1112690D01*
X60595Y1112481D01*
G01X25173Y1147836D02*
Y1143836D01*
X32573D01*
G01X70954Y1176173D02*
Y1178673D01*
X71995D01*
X72329Y1178548D01*
X72537Y1178381D01*
X72620Y1178048D01*
X72537Y1177715D01*
X72287Y1177506D01*
X71995Y1177381D01*
X70954D01*
G01X71995D02*
X72620Y1176173D01*
G01X74179Y1176465D02*
X74470Y1176256D01*
X74804Y1176173D01*
X75137Y1176256D01*
X75429Y1176506D01*
X75637Y1176881D01*
X75720Y1177256D01*
Y1177715D01*
X75637Y1178090D01*
X75429Y1178423D01*
X75179Y1178590D01*
X74887Y1178673D01*
X74554Y1178590D01*
X74304Y1178423D01*
X74137Y1178173D01*
X74054Y1177840D01*
X74137Y1177548D01*
X74345Y1177256D01*
X74595Y1177090D01*
X74887Y1177048D01*
X75220Y1177131D01*
X75470Y1177340D01*
X75720Y1177715D01*
G01X77070Y1176548D02*
X77320Y1176340D01*
X77612Y1176215D01*
X77987Y1176173D01*
X78362Y1176256D01*
X78654Y1176423D01*
X78862Y1176715D01*
X78904Y1177048D01*
X78820Y1177381D01*
X78612Y1177590D01*
X78320Y1177756D01*
X78029Y1177798D01*
X77737Y1177756D01*
X77362Y1177590D01*
X77487Y1178673D01*
X78612D01*
G01X80379Y1176465D02*
X80670Y1176256D01*
X81004Y1176173D01*
X81337Y1176256D01*
X81629Y1176506D01*
X81837Y1176881D01*
X81920Y1177256D01*
Y1177715D01*
X81837Y1178090D01*
X81629Y1178423D01*
X81379Y1178590D01*
X81087Y1178673D01*
X80754Y1178590D01*
X80504Y1178423D01*
X80337Y1178173D01*
X80254Y1177840D01*
X80337Y1177548D01*
X80545Y1177256D01*
X80795Y1177090D01*
X81087Y1177048D01*
X81420Y1177131D01*
X81670Y1177340D01*
X81920Y1177715D01*
G01X65637Y1156173D02*
Y1164173D01*
X83237D01*
Y1156173D01*
X65637D01*
G01X33269Y1150001D02*
Y1164001D01*
G01X56204Y1170965D02*
X55954Y1171090D01*
X55662Y1171173D01*
X55329D01*
X54954Y1171048D01*
X54662Y1170840D01*
X54454Y1170590D01*
X54287Y1170173D01*
X54245Y1169798D01*
X54329Y1169423D01*
X54454Y1169173D01*
X54704Y1168923D01*
X54995Y1168756D01*
X55287Y1168673D01*
X55579D01*
X55870Y1168756D01*
X56120Y1168881D01*
X56329Y1169048D01*
G01X57470D02*
X57720Y1168840D01*
X58012Y1168715D01*
X58387Y1168673D01*
X58762Y1168756D01*
X59054Y1168923D01*
X59262Y1169215D01*
X59304Y1169548D01*
X59220Y1169881D01*
X59012Y1170090D01*
X58720Y1170256D01*
X58429Y1170298D01*
X58137Y1170256D01*
X57762Y1170090D01*
X57887Y1171173D01*
X59012D01*
G01X61487Y1168673D02*
Y1171173D01*
X60987Y1170673D01*
G01Y1168673D02*
X61987D01*
G01X63795Y1170756D02*
X64045Y1171006D01*
X64337Y1171131D01*
X64670Y1171173D01*
X65087Y1171090D01*
X65379Y1170881D01*
X65462Y1170631D01*
X65420Y1170381D01*
X65254Y1170173D01*
X64420Y1169756D01*
X64045Y1169465D01*
X63795Y1169048D01*
X63712Y1168673D01*
X65462D01*
G01X72767Y1170292D02*
X72517Y1170417D01*
X72225Y1170500D01*
X71892D01*
X71517Y1170375D01*
X71225Y1170167D01*
X71017Y1169917D01*
X70850Y1169500D01*
X70808Y1169125D01*
X70892Y1168750D01*
X71017Y1168500D01*
X71267Y1168250D01*
X71558Y1168083D01*
X71850Y1168000D01*
X72142D01*
X72433Y1168083D01*
X72683Y1168208D01*
X72892Y1168375D01*
G01X74033D02*
X74283Y1168167D01*
X74575Y1168042D01*
X74950Y1168000D01*
X75325Y1168083D01*
X75617Y1168250D01*
X75825Y1168542D01*
X75867Y1168875D01*
X75783Y1169208D01*
X75575Y1169417D01*
X75283Y1169583D01*
X74992Y1169625D01*
X74700Y1169583D01*
X74325Y1169417D01*
X74450Y1170500D01*
X75575D01*
G01X78050D02*
X77717Y1170417D01*
X77467Y1170208D01*
X77300Y1169958D01*
X77175Y1169625D01*
X77133Y1169250D01*
X77175Y1168875D01*
X77300Y1168542D01*
X77467Y1168292D01*
X77717Y1168083D01*
X78050Y1168000D01*
X78383Y1168083D01*
X78633Y1168292D01*
X78800Y1168542D01*
X78925Y1168875D01*
X78967Y1169250D01*
X78925Y1169625D01*
X78800Y1169958D01*
X78633Y1170208D01*
X78383Y1170417D01*
X78050Y1170500D01*
G01X80442Y1168292D02*
X80733Y1168083D01*
X81067Y1168000D01*
X81400Y1168083D01*
X81692Y1168333D01*
X81900Y1168708D01*
X81983Y1169083D01*
Y1169542D01*
X81900Y1169917D01*
X81692Y1170250D01*
X81442Y1170417D01*
X81150Y1170500D01*
X80817Y1170417D01*
X80567Y1170250D01*
X80400Y1170000D01*
X80317Y1169667D01*
X80400Y1169375D01*
X80608Y1169083D01*
X80858Y1168917D01*
X81150Y1168875D01*
X81483Y1168958D01*
X81733Y1169167D01*
X81983Y1169542D01*
G01X70137Y1149673D02*
X75637D01*
G01X70137Y1141673D02*
Y1149673D01*
G01X75637Y1141673D02*
X70137D01*
G01X45500Y1134850D02*
X45458Y1134517D01*
X45292Y1134225D01*
X45042Y1133975D01*
X44750Y1133808D01*
X44417Y1133725D01*
X44083D01*
X43750Y1133808D01*
X43458Y1133975D01*
X43208Y1134225D01*
X43042Y1134517D01*
X43000Y1134850D01*
X43042Y1135183D01*
X43208Y1135475D01*
X43458Y1135725D01*
X43750Y1135892D01*
X44083Y1135975D01*
X44417D01*
X44750Y1135892D01*
X45042Y1135725D01*
X45292Y1135475D01*
X45458Y1135183D01*
X45500Y1134850D01*
G01X44833Y1135183D02*
X45500Y1135683D01*
G01X43417Y1137158D02*
X43167Y1137408D01*
X43042Y1137700D01*
X43000Y1138033D01*
X43083Y1138450D01*
X43292Y1138742D01*
X43542Y1138825D01*
X43792Y1138783D01*
X44000Y1138617D01*
X44417Y1137783D01*
X44708Y1137408D01*
X45125Y1137158D01*
X45500Y1137075D01*
Y1138825D01*
G01Y1141050D02*
X43000D01*
X43500Y1140550D01*
G01X45500D02*
Y1141550D01*
G01Y1144150D02*
X45458Y1144442D01*
X45333Y1144775D01*
X45125Y1144983D01*
X44833Y1145067D01*
X44542Y1144983D01*
X44292Y1144733D01*
X44167Y1144358D01*
Y1143942D01*
X44083Y1143692D01*
X43875Y1143483D01*
X43583Y1143400D01*
X43292Y1143525D01*
X43083Y1143817D01*
X43000Y1144150D01*
X43083Y1144483D01*
X43292Y1144775D01*
X43583Y1144900D01*
X43875Y1144817D01*
X44083Y1144608D01*
X44167Y1144358D01*
Y1143942D01*
X44292Y1143567D01*
X44542Y1143317D01*
X44833Y1143233D01*
X45125Y1143317D01*
X45333Y1143525D01*
X45458Y1143858D01*
X45500Y1144150D01*
G01X47737Y1143173D02*
X49837Y1141373D01*
X47737Y1139173D01*
G01X47637Y1135573D02*
X66837D01*
Y1146773D01*
X47637D01*
Y1135573D01*
X48037D01*
G01X72767Y1174292D02*
X72517Y1174417D01*
X72225Y1174500D01*
X71892D01*
X71517Y1174375D01*
X71225Y1174167D01*
X71017Y1173917D01*
X70850Y1173500D01*
X70808Y1173125D01*
X70892Y1172750D01*
X71017Y1172500D01*
X71267Y1172250D01*
X71558Y1172083D01*
X71850Y1172000D01*
X72142D01*
X72433Y1172083D01*
X72683Y1172208D01*
X72892Y1172375D01*
G01X74033D02*
X74283Y1172167D01*
X74575Y1172042D01*
X74950Y1172000D01*
X75325Y1172083D01*
X75617Y1172250D01*
X75825Y1172542D01*
X75867Y1172875D01*
X75783Y1173208D01*
X75575Y1173417D01*
X75283Y1173583D01*
X74992Y1173625D01*
X74700Y1173583D01*
X74325Y1173417D01*
X74450Y1174500D01*
X75575D01*
G01X78050D02*
X77717Y1174417D01*
X77467Y1174208D01*
X77300Y1173958D01*
X77175Y1173625D01*
X77133Y1173250D01*
X77175Y1172875D01*
X77300Y1172542D01*
X77467Y1172292D01*
X77717Y1172083D01*
X78050Y1172000D01*
X78383Y1172083D01*
X78633Y1172292D01*
X78800Y1172542D01*
X78925Y1172875D01*
X78967Y1173250D01*
X78925Y1173625D01*
X78800Y1173958D01*
X78633Y1174208D01*
X78383Y1174417D01*
X78050Y1174500D01*
G01X81150Y1172000D02*
X81442Y1172042D01*
X81775Y1172167D01*
X81983Y1172375D01*
X82067Y1172667D01*
X81983Y1172958D01*
X81733Y1173208D01*
X81358Y1173333D01*
X80942D01*
X80692Y1173417D01*
X80483Y1173625D01*
X80400Y1173917D01*
X80525Y1174208D01*
X80817Y1174417D01*
X81150Y1174500D01*
X81483Y1174417D01*
X81775Y1174208D01*
X81900Y1173917D01*
X81817Y1173625D01*
X81608Y1173417D01*
X81358Y1173333D01*
X80942D01*
X80567Y1173208D01*
X80317Y1172958D01*
X80233Y1172667D01*
X80317Y1172375D01*
X80525Y1172167D01*
X80858Y1172042D01*
X81150Y1172000D01*
G01X37107Y1192602D02*
X34607D01*
Y1193643D01*
X34732Y1193977D01*
X34899Y1194185D01*
X35232Y1194268D01*
X35565Y1194185D01*
X35774Y1193935D01*
X35899Y1193643D01*
Y1192602D01*
G01Y1193643D02*
X37107Y1194268D01*
G01X35024Y1195743D02*
X34774Y1195993D01*
X34649Y1196285D01*
X34607Y1196618D01*
X34690Y1197035D01*
X34899Y1197327D01*
X35149Y1197410D01*
X35399Y1197368D01*
X35607Y1197202D01*
X36024Y1196368D01*
X36315Y1195993D01*
X36732Y1195743D01*
X37107Y1195660D01*
Y1197410D01*
G01X34607Y1199635D02*
X34690Y1199302D01*
X34899Y1199052D01*
X35149Y1198885D01*
X35482Y1198760D01*
X35857Y1198718D01*
X36232Y1198760D01*
X36565Y1198885D01*
X36815Y1199052D01*
X37024Y1199302D01*
X37107Y1199635D01*
X37024Y1199968D01*
X36815Y1200218D01*
X36565Y1200385D01*
X36232Y1200510D01*
X35857Y1200552D01*
X35482Y1200510D01*
X35149Y1200385D01*
X34899Y1200218D01*
X34690Y1199968D01*
X34607Y1199635D01*
G01X36732Y1201818D02*
X36940Y1202068D01*
X37065Y1202360D01*
X37107Y1202735D01*
X37024Y1203110D01*
X36857Y1203402D01*
X36565Y1203610D01*
X36232Y1203652D01*
X35899Y1203568D01*
X35690Y1203360D01*
X35524Y1203068D01*
X35482Y1202777D01*
X35524Y1202485D01*
X35690Y1202110D01*
X34607Y1202235D01*
Y1203360D01*
G01X65679Y1271565D02*
Y1282765D01*
X74479D01*
Y1271565D01*
X65679D01*
G01X94124Y221492D02*
X99174D01*
Y320192D01*
X123824D01*
Y135792D01*
X99174D01*
Y194492D01*
X94124D01*
Y221492D01*
G01X84517Y162500D02*
Y165000D01*
X85558D01*
X85892Y164875D01*
X86100Y164708D01*
X86183Y164375D01*
X86100Y164042D01*
X85850Y163833D01*
X85558Y163708D01*
X84517D01*
G01X85558D02*
X86183Y162500D01*
G01X87658Y163542D02*
X87950Y163833D01*
X88200Y164000D01*
X88533Y164083D01*
X88825Y164000D01*
X89033Y163833D01*
X89200Y163583D01*
X89242Y163292D01*
X89200Y163042D01*
X89033Y162792D01*
X88783Y162583D01*
X88492Y162500D01*
X88158Y162583D01*
X87867Y162833D01*
X87700Y163208D01*
X87658Y163625D01*
X87742Y164167D01*
X87867Y164458D01*
X88075Y164750D01*
X88367Y164958D01*
X88658Y165000D01*
X88950Y164917D01*
X89158Y164708D01*
G01X90842Y162792D02*
X91133Y162583D01*
X91467Y162500D01*
X91800Y162583D01*
X92092Y162833D01*
X92300Y163208D01*
X92383Y163583D01*
Y164042D01*
X92300Y164417D01*
X92092Y164750D01*
X91842Y164917D01*
X91550Y165000D01*
X91217Y164917D01*
X90967Y164750D01*
X90800Y164500D01*
X90717Y164167D01*
X90800Y163875D01*
X91008Y163583D01*
X91258Y163417D01*
X91550Y163375D01*
X91883Y163458D01*
X92133Y163667D01*
X92383Y164042D01*
G01X93733Y163000D02*
X93983Y162708D01*
X94317Y162542D01*
X94692Y162500D01*
X95025Y162542D01*
X95358Y162750D01*
X95567Y163000D01*
X95608Y163250D01*
X95525Y163542D01*
X95233Y163750D01*
X94942Y163833D01*
X94567D01*
G01X94942D02*
X95192Y163958D01*
X95400Y164167D01*
X95483Y164417D01*
X95400Y164667D01*
X95192Y164875D01*
X94817Y165000D01*
X94442Y164958D01*
X94067Y164792D01*
G01X94137Y174661D02*
Y178661D01*
X86737D01*
G01X84617Y170500D02*
Y173000D01*
X85658D01*
X85992Y172875D01*
X86200Y172708D01*
X86283Y172375D01*
X86200Y172042D01*
X85950Y171833D01*
X85658Y171708D01*
X84617D01*
G01X85658D02*
X86283Y170500D01*
G01X87758Y171542D02*
X88050Y171833D01*
X88300Y172000D01*
X88633Y172083D01*
X88925Y172000D01*
X89133Y171833D01*
X89300Y171583D01*
X89342Y171292D01*
X89300Y171042D01*
X89133Y170792D01*
X88883Y170583D01*
X88592Y170500D01*
X88258Y170583D01*
X87967Y170833D01*
X87800Y171208D01*
X87758Y171625D01*
X87842Y172167D01*
X87967Y172458D01*
X88175Y172750D01*
X88467Y172958D01*
X88758Y173000D01*
X89050Y172917D01*
X89258Y172708D01*
G01X90942Y170792D02*
X91233Y170583D01*
X91567Y170500D01*
X91900Y170583D01*
X92192Y170833D01*
X92400Y171208D01*
X92483Y171583D01*
Y172042D01*
X92400Y172417D01*
X92192Y172750D01*
X91942Y172917D01*
X91650Y173000D01*
X91317Y172917D01*
X91067Y172750D01*
X90900Y172500D01*
X90817Y172167D01*
X90900Y171875D01*
X91108Y171583D01*
X91358Y171417D01*
X91650Y171375D01*
X91983Y171458D01*
X92233Y171667D01*
X92483Y172042D01*
G01X93833Y170875D02*
X94083Y170667D01*
X94375Y170542D01*
X94750Y170500D01*
X95125Y170583D01*
X95417Y170750D01*
X95625Y171042D01*
X95667Y171375D01*
X95583Y171708D01*
X95375Y171917D01*
X95083Y172083D01*
X94792Y172125D01*
X94500Y172083D01*
X94125Y171917D01*
X94250Y173000D01*
X95375D01*
G01X86837Y193161D02*
Y189161D01*
X94237D01*
G01X84454Y166661D02*
Y169161D01*
X85495D01*
X85829Y169036D01*
X86037Y168869D01*
X86120Y168536D01*
X86037Y168203D01*
X85787Y167994D01*
X85495Y167869D01*
X84454D01*
G01X85495D02*
X86120Y166661D01*
G01X87595Y167703D02*
X87887Y167994D01*
X88137Y168161D01*
X88470Y168244D01*
X88762Y168161D01*
X88970Y167994D01*
X89137Y167744D01*
X89179Y167453D01*
X89137Y167203D01*
X88970Y166953D01*
X88720Y166744D01*
X88429Y166661D01*
X88095Y166744D01*
X87804Y166994D01*
X87637Y167369D01*
X87595Y167786D01*
X87679Y168328D01*
X87804Y168619D01*
X88012Y168911D01*
X88304Y169119D01*
X88595Y169161D01*
X88887Y169078D01*
X89095Y168869D01*
G01X90779Y166953D02*
X91070Y166744D01*
X91404Y166661D01*
X91737Y166744D01*
X92029Y166994D01*
X92237Y167369D01*
X92320Y167744D01*
Y168203D01*
X92237Y168578D01*
X92029Y168911D01*
X91779Y169078D01*
X91487Y169161D01*
X91154Y169078D01*
X90904Y168911D01*
X90737Y168661D01*
X90654Y168328D01*
X90737Y168036D01*
X90945Y167744D01*
X91195Y167578D01*
X91487Y167536D01*
X91820Y167619D01*
X92070Y167828D01*
X92320Y168203D01*
G01X94587Y169161D02*
X94254Y169078D01*
X94004Y168869D01*
X93837Y168619D01*
X93712Y168286D01*
X93670Y167911D01*
X93712Y167536D01*
X93837Y167203D01*
X94004Y166953D01*
X94254Y166744D01*
X94587Y166661D01*
X94920Y166744D01*
X95170Y166953D01*
X95337Y167203D01*
X95462Y167536D01*
X95504Y167911D01*
X95462Y168286D01*
X95337Y168619D01*
X95170Y168869D01*
X94920Y169078D01*
X94587Y169161D01*
G01X94137Y179161D02*
Y183161D01*
X86737D01*
G01X74737Y197861D02*
Y184461D01*
G01D02*
X86137D01*
G01D02*
Y197861D01*
G01D02*
X74737D01*
G01X92237Y223261D02*
X73037D01*
Y212061D01*
X92237D01*
Y223261D01*
X91837D01*
G01X94500Y255017D02*
X92000D01*
Y256058D01*
X92125Y256392D01*
X92292Y256600D01*
X92625Y256683D01*
X92958Y256600D01*
X93167Y256350D01*
X93292Y256058D01*
Y255017D01*
G01Y256058D02*
X94500Y256683D01*
G01X93458Y258158D02*
X93167Y258450D01*
X93000Y258700D01*
X92917Y259033D01*
X93000Y259325D01*
X93167Y259533D01*
X93417Y259700D01*
X93708Y259742D01*
X93958Y259700D01*
X94208Y259533D01*
X94417Y259283D01*
X94500Y258992D01*
X94417Y258658D01*
X94167Y258367D01*
X93792Y258200D01*
X93375Y258158D01*
X92833Y258242D01*
X92542Y258367D01*
X92250Y258575D01*
X92042Y258867D01*
X92000Y259158D01*
X92083Y259450D01*
X92292Y259658D01*
G01X94500Y262050D02*
X94458Y262342D01*
X94333Y262675D01*
X94125Y262883D01*
X93833Y262967D01*
X93542Y262883D01*
X93292Y262633D01*
X93167Y262258D01*
Y261842D01*
X93083Y261592D01*
X92875Y261383D01*
X92583Y261300D01*
X92292Y261425D01*
X92083Y261717D01*
X92000Y262050D01*
X92083Y262383D01*
X92292Y262675D01*
X92583Y262800D01*
X92875Y262717D01*
X93083Y262508D01*
X93167Y262258D01*
Y261842D01*
X93292Y261467D01*
X93542Y261217D01*
X93833Y261133D01*
X94125Y261217D01*
X94333Y261425D01*
X94458Y261758D01*
X94500Y262050D01*
G01Y265150D02*
X92000D01*
X92500Y264650D01*
G01X94500D02*
Y265650D01*
G01X89437Y253961D02*
X97437D01*
Y236361D01*
X89437D01*
Y253961D01*
G01X82237Y244161D02*
X87737D01*
G01D02*
Y236161D01*
G01D02*
X82237D01*
G01X96000Y224850D02*
X95958Y224517D01*
X95792Y224225D01*
X95542Y223975D01*
X95250Y223808D01*
X94917Y223725D01*
X94583D01*
X94250Y223808D01*
X93958Y223975D01*
X93708Y224225D01*
X93542Y224517D01*
X93500Y224850D01*
X93542Y225183D01*
X93708Y225475D01*
X93958Y225725D01*
X94250Y225892D01*
X94583Y225975D01*
X94917D01*
X95250Y225892D01*
X95542Y225725D01*
X95792Y225475D01*
X95958Y225183D01*
X96000Y224850D01*
G01X95333Y225183D02*
X96000Y225683D01*
G01Y227950D02*
X93500D01*
X94000Y227450D01*
G01X96000D02*
Y228450D01*
G01Y231550D02*
X93500D01*
X95292Y230008D01*
Y232092D01*
G01X96000Y234650D02*
X93500D01*
X95292Y233108D01*
Y235192D01*
G01X92137Y215661D02*
X90037Y217461D01*
X92137Y219661D01*
G01X86708Y280767D02*
X86583Y280517D01*
X86500Y280225D01*
Y279892D01*
X86625Y279517D01*
X86833Y279225D01*
X87083Y279017D01*
X87500Y278850D01*
X87875Y278808D01*
X88250Y278892D01*
X88500Y279017D01*
X88750Y279267D01*
X88917Y279558D01*
X89000Y279850D01*
Y280142D01*
X88917Y280433D01*
X88792Y280683D01*
X88625Y280892D01*
G01X88500Y282033D02*
X88792Y282283D01*
X88958Y282617D01*
X89000Y282992D01*
X88958Y283325D01*
X88750Y283658D01*
X88500Y283867D01*
X88250Y283908D01*
X87958Y283825D01*
X87750Y283533D01*
X87667Y283242D01*
Y282867D01*
G01Y283242D02*
X87542Y283492D01*
X87333Y283700D01*
X87083Y283783D01*
X86833Y283700D01*
X86625Y283492D01*
X86500Y283117D01*
X86542Y282742D01*
X86708Y282367D01*
G01X88625Y285133D02*
X88833Y285383D01*
X88958Y285675D01*
X89000Y286050D01*
X88917Y286425D01*
X88750Y286717D01*
X88458Y286925D01*
X88125Y286967D01*
X87792Y286883D01*
X87583Y286675D01*
X87417Y286383D01*
X87375Y286092D01*
X87417Y285800D01*
X87583Y285425D01*
X86500Y285550D01*
Y286675D01*
G01X89000Y289067D02*
X88458Y289150D01*
X88000Y289275D01*
X87583Y289442D01*
X87125Y289650D01*
X86500Y289983D01*
Y288317D01*
G01X89708Y292767D02*
X89583Y292517D01*
X89500Y292225D01*
Y291892D01*
X89625Y291517D01*
X89833Y291225D01*
X90083Y291017D01*
X90500Y290850D01*
X90875Y290808D01*
X91250Y290892D01*
X91500Y291017D01*
X91750Y291267D01*
X91917Y291558D01*
X92000Y291850D01*
Y292142D01*
X91917Y292433D01*
X91792Y292683D01*
X91625Y292892D01*
G01X91500Y294033D02*
X91792Y294283D01*
X91958Y294617D01*
X92000Y294992D01*
X91958Y295325D01*
X91750Y295658D01*
X91500Y295867D01*
X91250Y295908D01*
X90958Y295825D01*
X90750Y295533D01*
X90667Y295242D01*
Y294867D01*
G01Y295242D02*
X90542Y295492D01*
X90333Y295700D01*
X90083Y295783D01*
X89833Y295700D01*
X89625Y295492D01*
X89500Y295117D01*
X89542Y294742D01*
X89708Y294367D01*
G01X91625Y297133D02*
X91833Y297383D01*
X91958Y297675D01*
X92000Y298050D01*
X91917Y298425D01*
X91750Y298717D01*
X91458Y298925D01*
X91125Y298967D01*
X90792Y298883D01*
X90583Y298675D01*
X90417Y298383D01*
X90375Y298092D01*
X90417Y297800D01*
X90583Y297425D01*
X89500Y297550D01*
Y298675D01*
G01X91708Y300442D02*
X91917Y300733D01*
X92000Y301067D01*
X91917Y301400D01*
X91667Y301692D01*
X91292Y301900D01*
X90917Y301983D01*
X90458D01*
X90083Y301900D01*
X89750Y301692D01*
X89583Y301442D01*
X89500Y301150D01*
X89583Y300817D01*
X89750Y300567D01*
X90000Y300400D01*
X90333Y300317D01*
X90625Y300400D01*
X90917Y300608D01*
X91083Y300858D01*
X91125Y301150D01*
X91042Y301483D01*
X90833Y301733D01*
X90458Y301983D01*
G01X100299Y329492D02*
Y331992D01*
G01X102049D02*
Y329492D01*
G01Y330742D02*
X100299D01*
G01X103357Y329492D02*
Y331992D01*
X104191D01*
X104524Y331867D01*
X104774Y331700D01*
X104982Y331450D01*
X105149Y331159D01*
X105191Y330742D01*
X105149Y330325D01*
X104982Y330034D01*
X104774Y329784D01*
X104524Y329617D01*
X104191Y329492D01*
X103357D01*
G01X106457D02*
Y331992D01*
X107291D01*
X107624Y331867D01*
X107874Y331700D01*
X108082Y331450D01*
X108249Y331159D01*
X108291Y330742D01*
X108249Y330325D01*
X108082Y330034D01*
X107874Y329784D01*
X107624Y329617D01*
X107291Y329492D01*
X106457D01*
G01X109599Y329825D02*
X109932Y329617D01*
X110307Y329492D01*
X110641D01*
X110974Y329617D01*
X111224Y329825D01*
X111349Y330117D01*
X111266Y330409D01*
X111057Y330659D01*
X110682Y330825D01*
X110182Y330909D01*
X109891Y331075D01*
X109766Y331367D01*
X109849Y331659D01*
X110057Y331867D01*
X110349Y331992D01*
X110641D01*
X110932Y331909D01*
X111182Y331700D01*
G01X112532Y329492D02*
X113574Y331992D01*
X114616Y329492D01*
G01X114241Y330367D02*
X112907D01*
G01X115799Y329825D02*
X116132Y329617D01*
X116507Y329492D01*
X116841D01*
X117174Y329617D01*
X117424Y329825D01*
X117549Y330117D01*
X117466Y330409D01*
X117257Y330659D01*
X116882Y330825D01*
X116382Y330909D01*
X116091Y331075D01*
X115966Y331367D01*
X116049Y331659D01*
X116257Y331867D01*
X116549Y331992D01*
X116841D01*
X117132Y331909D01*
X117382Y331700D01*
G01X118982Y331575D02*
X119232Y331825D01*
X119524Y331950D01*
X119857Y331992D01*
X120274Y331909D01*
X120566Y331700D01*
X120649Y331450D01*
X120607Y331200D01*
X120441Y330992D01*
X119607Y330575D01*
X119232Y330284D01*
X118982Y329867D01*
X118899Y329492D01*
X120649D01*
G01X123374D02*
Y331992D01*
X121832Y330200D01*
X123916D01*
G01X83500Y495517D02*
X81000D01*
Y496558D01*
X81125Y496892D01*
X81292Y497100D01*
X81625Y497183D01*
X81958Y497100D01*
X82167Y496850D01*
X82292Y496558D01*
Y495517D01*
G01Y496558D02*
X83500Y497183D01*
G01X81417Y498658D02*
X81167Y498908D01*
X81042Y499200D01*
X81000Y499533D01*
X81083Y499950D01*
X81292Y500242D01*
X81542Y500325D01*
X81792Y500283D01*
X82000Y500117D01*
X82417Y499283D01*
X82708Y498908D01*
X83125Y498658D01*
X83500Y498575D01*
Y500325D01*
G01Y502467D02*
X82958Y502550D01*
X82500Y502675D01*
X82083Y502842D01*
X81625Y503050D01*
X81000Y503383D01*
Y501717D01*
G01X83500Y505567D02*
X82958Y505650D01*
X82500Y505775D01*
X82083Y505942D01*
X81625Y506150D01*
X81000Y506483D01*
Y504817D01*
G01X78500Y495517D02*
X76000D01*
Y496558D01*
X76125Y496892D01*
X76292Y497100D01*
X76625Y497183D01*
X76958Y497100D01*
X77167Y496850D01*
X77292Y496558D01*
Y495517D01*
G01Y496558D02*
X78500Y497183D01*
G01X76417Y498658D02*
X76167Y498908D01*
X76042Y499200D01*
X76000Y499533D01*
X76083Y499950D01*
X76292Y500242D01*
X76542Y500325D01*
X76792Y500283D01*
X77000Y500117D01*
X77417Y499283D01*
X77708Y498908D01*
X78125Y498658D01*
X78500Y498575D01*
Y500325D01*
G01Y502467D02*
X77958Y502550D01*
X77500Y502675D01*
X77083Y502842D01*
X76625Y503050D01*
X76000Y503383D01*
Y501717D01*
G01X78000Y504733D02*
X78292Y504983D01*
X78458Y505317D01*
X78500Y505692D01*
X78458Y506025D01*
X78250Y506358D01*
X78000Y506567D01*
X77750Y506608D01*
X77458Y506525D01*
X77250Y506233D01*
X77167Y505942D01*
Y505567D01*
G01Y505942D02*
X77042Y506192D01*
X76833Y506400D01*
X76583Y506483D01*
X76333Y506400D01*
X76125Y506192D01*
X76000Y505817D01*
X76042Y505442D01*
X76208Y505067D01*
G01X94124Y674248D02*
X99174D01*
Y772948D01*
X123824D01*
Y588548D01*
X99174D01*
Y647248D01*
X94124D01*
Y674248D01*
G01X82454Y614417D02*
Y616917D01*
X83495D01*
X83829Y616792D01*
X84037Y616625D01*
X84120Y616292D01*
X84037Y615959D01*
X83787Y615750D01*
X83495Y615625D01*
X82454D01*
G01X83495D02*
X84120Y614417D01*
G01X86887D02*
Y616917D01*
X85345Y615125D01*
X87429D01*
G01X89487Y614417D02*
Y616917D01*
X88987Y616417D01*
G01Y614417D02*
X89987D01*
G01X93087D02*
Y616917D01*
X91545Y615125D01*
X93629D01*
G01X94137Y631917D02*
Y635917D01*
X86737D01*
G01X82517Y610500D02*
Y613000D01*
X83558D01*
X83892Y612875D01*
X84100Y612708D01*
X84183Y612375D01*
X84100Y612042D01*
X83850Y611833D01*
X83558Y611708D01*
X82517D01*
G01X83558D02*
X84183Y610500D01*
G01X86950D02*
Y613000D01*
X85408Y611208D01*
X87492D01*
G01X89550Y610500D02*
Y613000D01*
X89050Y612500D01*
G01Y610500D02*
X90050D01*
G01X92567D02*
X92650Y611042D01*
X92775Y611500D01*
X92942Y611917D01*
X93150Y612375D01*
X93483Y613000D01*
X91817D01*
G01X83196Y631631D02*
Y627631D01*
X90596D01*
G01X82617Y618000D02*
Y620500D01*
X83658D01*
X83992Y620375D01*
X84200Y620208D01*
X84283Y619875D01*
X84200Y619542D01*
X83950Y619333D01*
X83658Y619208D01*
X82617D01*
G01X83658D02*
X84283Y618000D01*
G01X87050D02*
Y620500D01*
X85508Y618708D01*
X87592D01*
G01X89650Y618000D02*
Y620500D01*
X89150Y620000D01*
G01Y618000D02*
X90150D01*
G01X92042Y618292D02*
X92333Y618083D01*
X92667Y618000D01*
X93000Y618083D01*
X93292Y618333D01*
X93500Y618708D01*
X93583Y619083D01*
Y619542D01*
X93500Y619917D01*
X93292Y620250D01*
X93042Y620417D01*
X92750Y620500D01*
X92417Y620417D01*
X92167Y620250D01*
X92000Y620000D01*
X91917Y619667D01*
X92000Y619375D01*
X92208Y619083D01*
X92458Y618917D01*
X92750Y618875D01*
X93083Y618958D01*
X93333Y619167D01*
X93583Y619542D01*
G01X86837Y645917D02*
Y641917D01*
X94237D01*
G01X74900Y625000D02*
X74567Y625042D01*
X74275Y625208D01*
X74025Y625458D01*
X73858Y625750D01*
X73775Y626083D01*
Y626417D01*
X73858Y626750D01*
X74025Y627042D01*
X74275Y627292D01*
X74567Y627458D01*
X74900Y627500D01*
X75233Y627458D01*
X75525Y627292D01*
X75775Y627042D01*
X75942Y626750D01*
X76025Y626417D01*
Y626083D01*
X75942Y625750D01*
X75775Y625458D01*
X75525Y625208D01*
X75233Y625042D01*
X74900Y625000D01*
G01X75233Y625667D02*
X75733Y625000D01*
G01X77917D02*
X78000Y625542D01*
X78125Y626000D01*
X78292Y626417D01*
X78500Y626875D01*
X78833Y627500D01*
X77167D01*
G01X80183Y625500D02*
X80433Y625208D01*
X80767Y625042D01*
X81142Y625000D01*
X81475Y625042D01*
X81808Y625250D01*
X82017Y625500D01*
X82058Y625750D01*
X81975Y626042D01*
X81683Y626250D01*
X81392Y626333D01*
X81017D01*
G01X81392D02*
X81642Y626458D01*
X81850Y626667D01*
X81933Y626917D01*
X81850Y627167D01*
X81642Y627375D01*
X81267Y627500D01*
X80892Y627458D01*
X80517Y627292D01*
G01X86137Y637217D02*
Y650617D01*
G01X74737Y637217D02*
X86137D01*
G01X74737Y650617D02*
Y637217D01*
G01X89437Y706717D02*
X97437D01*
Y689117D01*
X89437D01*
Y706717D01*
G01X86137Y650617D02*
X74737D01*
G01X87737Y688917D02*
X82237D01*
G01X87737Y696917D02*
Y688917D01*
G01X96000Y677900D02*
X95958Y677567D01*
X95792Y677275D01*
X95542Y677025D01*
X95250Y676858D01*
X94917Y676775D01*
X94583D01*
X94250Y676858D01*
X93958Y677025D01*
X93708Y677275D01*
X93542Y677567D01*
X93500Y677900D01*
X93542Y678233D01*
X93708Y678525D01*
X93958Y678775D01*
X94250Y678942D01*
X94583Y679025D01*
X94917D01*
X95250Y678942D01*
X95542Y678775D01*
X95792Y678525D01*
X95958Y678233D01*
X96000Y677900D01*
G01X95333Y678233D02*
X96000Y678733D01*
G01Y680917D02*
X95458Y681000D01*
X95000Y681125D01*
X94583Y681292D01*
X94125Y681500D01*
X93500Y681833D01*
Y680167D01*
G01X93917Y683308D02*
X93667Y683558D01*
X93542Y683850D01*
X93500Y684183D01*
X93583Y684600D01*
X93792Y684892D01*
X94042Y684975D01*
X94292Y684933D01*
X94500Y684767D01*
X94917Y683933D01*
X95208Y683558D01*
X95625Y683308D01*
X96000Y683225D01*
Y684975D01*
G01X92137Y668417D02*
X90037Y670217D01*
X92137Y672417D01*
G01X92237Y676017D02*
X73037D01*
Y664817D01*
X92237D01*
Y676017D01*
X91837D01*
G01X94000Y708017D02*
X91500D01*
Y709058D01*
X91625Y709392D01*
X91792Y709600D01*
X92125Y709683D01*
X92458Y709600D01*
X92667Y709350D01*
X92792Y709058D01*
Y708017D01*
G01Y709058D02*
X94000Y709683D01*
G01Y712450D02*
X91500D01*
X93292Y710908D01*
Y712992D01*
G01X91500Y715050D02*
X91583Y714717D01*
X91792Y714467D01*
X92042Y714300D01*
X92375Y714175D01*
X92750Y714133D01*
X93125Y714175D01*
X93458Y714300D01*
X93708Y714467D01*
X93917Y714717D01*
X94000Y715050D01*
X93917Y715383D01*
X93708Y715633D01*
X93458Y715800D01*
X93125Y715925D01*
X92750Y715967D01*
X92375Y715925D01*
X92042Y715800D01*
X91792Y715633D01*
X91583Y715383D01*
X91500Y715050D01*
G01X93625Y717233D02*
X93833Y717483D01*
X93958Y717775D01*
X94000Y718150D01*
X93917Y718525D01*
X93750Y718817D01*
X93458Y719025D01*
X93125Y719067D01*
X92792Y718983D01*
X92583Y718775D01*
X92417Y718483D01*
X92375Y718192D01*
X92417Y717900D01*
X92583Y717525D01*
X91500Y717650D01*
Y718775D01*
G01X87208Y733767D02*
X87083Y733517D01*
X87000Y733225D01*
Y732892D01*
X87125Y732517D01*
X87333Y732225D01*
X87583Y732017D01*
X88000Y731850D01*
X88375Y731808D01*
X88750Y731892D01*
X89000Y732017D01*
X89250Y732267D01*
X89417Y732558D01*
X89500Y732850D01*
Y733142D01*
X89417Y733433D01*
X89292Y733683D01*
X89125Y733892D01*
G01X87417Y735158D02*
X87167Y735408D01*
X87042Y735700D01*
X87000Y736033D01*
X87083Y736450D01*
X87292Y736742D01*
X87542Y736825D01*
X87792Y736783D01*
X88000Y736617D01*
X88417Y735783D01*
X88708Y735408D01*
X89125Y735158D01*
X89500Y735075D01*
Y736825D01*
G01X87000Y739050D02*
X87083Y738717D01*
X87292Y738467D01*
X87542Y738300D01*
X87875Y738175D01*
X88250Y738133D01*
X88625Y738175D01*
X88958Y738300D01*
X89208Y738467D01*
X89417Y738717D01*
X89500Y739050D01*
X89417Y739383D01*
X89208Y739633D01*
X88958Y739800D01*
X88625Y739925D01*
X88250Y739967D01*
X87875Y739925D01*
X87542Y739800D01*
X87292Y739633D01*
X87083Y739383D01*
X87000Y739050D01*
G01X87417Y741358D02*
X87167Y741608D01*
X87042Y741900D01*
X87000Y742233D01*
X87083Y742650D01*
X87292Y742942D01*
X87542Y743025D01*
X87792Y742983D01*
X88000Y742817D01*
X88417Y741983D01*
X88708Y741608D01*
X89125Y741358D01*
X89500Y741275D01*
Y743025D01*
G01X82237Y696917D02*
X87737D01*
G01X98775Y781500D02*
Y784000D01*
G01X100525D02*
Y781500D01*
G01Y782750D02*
X98775D01*
G01X101833Y781500D02*
Y784000D01*
X102667D01*
X103000Y783875D01*
X103250Y783708D01*
X103458Y783458D01*
X103625Y783167D01*
X103667Y782750D01*
X103625Y782333D01*
X103458Y782042D01*
X103250Y781792D01*
X103000Y781625D01*
X102667Y781500D01*
X101833D01*
G01X104933D02*
Y784000D01*
X105767D01*
X106100Y783875D01*
X106350Y783708D01*
X106558Y783458D01*
X106725Y783167D01*
X106767Y782750D01*
X106725Y782333D01*
X106558Y782042D01*
X106350Y781792D01*
X106100Y781625D01*
X105767Y781500D01*
X104933D01*
G01X108075Y781833D02*
X108408Y781625D01*
X108783Y781500D01*
X109117D01*
X109450Y781625D01*
X109700Y781833D01*
X109825Y782125D01*
X109742Y782417D01*
X109533Y782667D01*
X109158Y782833D01*
X108658Y782917D01*
X108367Y783083D01*
X108242Y783375D01*
X108325Y783667D01*
X108533Y783875D01*
X108825Y784000D01*
X109117D01*
X109408Y783917D01*
X109658Y783708D01*
G01X111008Y781500D02*
X112050Y784000D01*
X113092Y781500D01*
G01X112717Y782375D02*
X111383D01*
G01X114275Y781833D02*
X114608Y781625D01*
X114983Y781500D01*
X115317D01*
X115650Y781625D01*
X115900Y781833D01*
X116025Y782125D01*
X115942Y782417D01*
X115733Y782667D01*
X115358Y782833D01*
X114858Y782917D01*
X114567Y783083D01*
X114442Y783375D01*
X114525Y783667D01*
X114733Y783875D01*
X115025Y784000D01*
X115317D01*
X115608Y783917D01*
X115858Y783708D01*
G01X118250Y781500D02*
Y784000D01*
X117750Y783500D01*
G01Y781500D02*
X118750D01*
G01X120558Y783583D02*
X120808Y783833D01*
X121100Y783958D01*
X121433Y784000D01*
X121850Y783917D01*
X122142Y783708D01*
X122225Y783458D01*
X122183Y783208D01*
X122017Y783000D01*
X121183Y782583D01*
X120808Y782292D01*
X120558Y781875D01*
X120475Y781500D01*
X122225D01*
G01X89708Y746767D02*
X89583Y746517D01*
X89500Y746225D01*
Y745892D01*
X89625Y745517D01*
X89833Y745225D01*
X90083Y745017D01*
X90500Y744850D01*
X90875Y744808D01*
X91250Y744892D01*
X91500Y745017D01*
X91750Y745267D01*
X91917Y745558D01*
X92000Y745850D01*
Y746142D01*
X91917Y746433D01*
X91792Y746683D01*
X91625Y746892D01*
G01X89917Y748158D02*
X89667Y748408D01*
X89542Y748700D01*
X89500Y749033D01*
X89583Y749450D01*
X89792Y749742D01*
X90042Y749825D01*
X90292Y749783D01*
X90500Y749617D01*
X90917Y748783D01*
X91208Y748408D01*
X91625Y748158D01*
X92000Y748075D01*
Y749825D01*
G01X89500Y752050D02*
X89583Y751717D01*
X89792Y751467D01*
X90042Y751300D01*
X90375Y751175D01*
X90750Y751133D01*
X91125Y751175D01*
X91458Y751300D01*
X91708Y751467D01*
X91917Y751717D01*
X92000Y752050D01*
X91917Y752383D01*
X91708Y752633D01*
X91458Y752800D01*
X91125Y752925D01*
X90750Y752967D01*
X90375Y752925D01*
X90042Y752800D01*
X89792Y752633D01*
X89583Y752383D01*
X89500Y752050D01*
G01X91500Y754233D02*
X91792Y754483D01*
X91958Y754817D01*
X92000Y755192D01*
X91958Y755525D01*
X91750Y755858D01*
X91500Y756067D01*
X91250Y756108D01*
X90958Y756025D01*
X90750Y755733D01*
X90667Y755442D01*
Y755067D01*
G01Y755442D02*
X90542Y755692D01*
X90333Y755900D01*
X90083Y755983D01*
X89833Y755900D01*
X89625Y755692D01*
X89500Y755317D01*
X89542Y754942D01*
X89708Y754567D01*
G01X81424Y818709D02*
X78924D01*
Y820293D01*
G01X80132Y819709D02*
Y818709D01*
G01X78924Y821768D02*
X81424D01*
Y823434D01*
G01Y826534D02*
Y824868D01*
X78924D01*
Y826534D01*
G01X80132Y825868D02*
Y824868D01*
G01X81424Y827884D02*
X78924D01*
Y828718D01*
X79049Y829051D01*
X79216Y829301D01*
X79466Y829509D01*
X79757Y829676D01*
X80174Y829718D01*
X80591Y829676D01*
X80882Y829509D01*
X81132Y829301D01*
X81299Y829051D01*
X81424Y828718D01*
Y827884D01*
G01Y831901D02*
X78924D01*
X79424Y831401D01*
G01X81424D02*
Y832401D01*
G01X84967Y980000D02*
Y982500D01*
X86008D01*
X86342Y982375D01*
X86550Y982208D01*
X86633Y981875D01*
X86550Y981542D01*
X86300Y981333D01*
X86008Y981208D01*
X84967D01*
G01X86008D02*
X86633Y980000D01*
G01X88900D02*
Y982500D01*
X88400Y982000D01*
G01Y980000D02*
X89400D01*
G01X91208Y982083D02*
X91458Y982333D01*
X91750Y982458D01*
X92083Y982500D01*
X92500Y982417D01*
X92792Y982208D01*
X92875Y981958D01*
X92833Y981708D01*
X92667Y981500D01*
X91833Y981083D01*
X91458Y980792D01*
X91208Y980375D01*
X91125Y980000D01*
X92875D01*
G01X95100D02*
Y982500D01*
X94600Y982000D01*
G01Y980000D02*
X95600D01*
G01X97492Y980292D02*
X97783Y980083D01*
X98117Y980000D01*
X98450Y980083D01*
X98742Y980333D01*
X98950Y980708D01*
X99033Y981083D01*
Y981542D01*
X98950Y981917D01*
X98742Y982250D01*
X98492Y982417D01*
X98200Y982500D01*
X97867Y982417D01*
X97617Y982250D01*
X97450Y982000D01*
X97367Y981667D01*
X97450Y981375D01*
X97658Y981083D01*
X97908Y980917D01*
X98200Y980875D01*
X98533Y980958D01*
X98783Y981167D01*
X99033Y981542D01*
G01X106263Y983725D02*
Y987725D01*
X98863D01*
G01X113967Y954500D02*
Y957000D01*
X115008D01*
X115342Y956875D01*
X115550Y956708D01*
X115633Y956375D01*
X115550Y956042D01*
X115300Y955833D01*
X115008Y955708D01*
X113967D01*
G01X115008D02*
X115633Y954500D01*
G01X117900D02*
Y957000D01*
X117400Y956500D01*
G01Y954500D02*
X118400D01*
G01X120208Y956583D02*
X120458Y956833D01*
X120750Y956958D01*
X121083Y957000D01*
X121500Y956917D01*
X121792Y956708D01*
X121875Y956458D01*
X121833Y956208D01*
X121667Y956000D01*
X120833Y955583D01*
X120458Y955292D01*
X120208Y954875D01*
X120125Y954500D01*
X121875D01*
G01X124100D02*
Y957000D01*
X123600Y956500D01*
G01Y954500D02*
X124600D01*
G01X127700D02*
Y957000D01*
X126158Y955208D01*
X128242D01*
G01X128494Y969575D02*
X120694D01*
G01X115094Y962575D02*
X123794D01*
G01X115094Y969575D02*
Y962575D01*
G01X121494Y969575D02*
X115094D01*
G01X101267Y962792D02*
X101017Y962917D01*
X100725Y963000D01*
X100392D01*
X100017Y962875D01*
X99725Y962667D01*
X99517Y962417D01*
X99350Y962000D01*
X99308Y961625D01*
X99392Y961250D01*
X99517Y961000D01*
X99767Y960750D01*
X100058Y960583D01*
X100350Y960500D01*
X100642D01*
X100933Y960583D01*
X101183Y960708D01*
X101392Y960875D01*
G01X102533D02*
X102783Y960667D01*
X103075Y960542D01*
X103450Y960500D01*
X103825Y960583D01*
X104117Y960750D01*
X104325Y961042D01*
X104367Y961375D01*
X104283Y961708D01*
X104075Y961917D01*
X103783Y962083D01*
X103492Y962125D01*
X103200Y962083D01*
X102825Y961917D01*
X102950Y963000D01*
X104075D01*
G01X105842Y960792D02*
X106133Y960583D01*
X106467Y960500D01*
X106800Y960583D01*
X107092Y960833D01*
X107300Y961208D01*
X107383Y961583D01*
Y962042D01*
X107300Y962417D01*
X107092Y962750D01*
X106842Y962917D01*
X106550Y963000D01*
X106217Y962917D01*
X105967Y962750D01*
X105800Y962500D01*
X105717Y962167D01*
X105800Y961875D01*
X106008Y961583D01*
X106258Y961417D01*
X106550Y961375D01*
X106883Y961458D01*
X107133Y961667D01*
X107383Y962042D01*
G01X109650Y960500D02*
X109942Y960542D01*
X110275Y960667D01*
X110483Y960875D01*
X110567Y961167D01*
X110483Y961458D01*
X110233Y961708D01*
X109858Y961833D01*
X109442D01*
X109192Y961917D01*
X108983Y962125D01*
X108900Y962417D01*
X109025Y962708D01*
X109317Y962917D01*
X109650Y963000D01*
X109983Y962917D01*
X110275Y962708D01*
X110400Y962417D01*
X110317Y962125D01*
X110108Y961917D01*
X109858Y961833D01*
X109442D01*
X109067Y961708D01*
X108817Y961458D01*
X108733Y961167D01*
X108817Y960875D01*
X109025Y960667D01*
X109358Y960542D01*
X109650Y960500D01*
G01X101267Y958792D02*
X101017Y958917D01*
X100725Y959000D01*
X100392D01*
X100017Y958875D01*
X99725Y958667D01*
X99517Y958417D01*
X99350Y958000D01*
X99308Y957625D01*
X99392Y957250D01*
X99517Y957000D01*
X99767Y956750D01*
X100058Y956583D01*
X100350Y956500D01*
X100642D01*
X100933Y956583D01*
X101183Y956708D01*
X101392Y956875D01*
G01X102533D02*
X102783Y956667D01*
X103075Y956542D01*
X103450Y956500D01*
X103825Y956583D01*
X104117Y956750D01*
X104325Y957042D01*
X104367Y957375D01*
X104283Y957708D01*
X104075Y957917D01*
X103783Y958083D01*
X103492Y958125D01*
X103200Y958083D01*
X102825Y957917D01*
X102950Y959000D01*
X104075D01*
G01X105842Y956792D02*
X106133Y956583D01*
X106467Y956500D01*
X106800Y956583D01*
X107092Y956833D01*
X107300Y957208D01*
X107383Y957583D01*
Y958042D01*
X107300Y958417D01*
X107092Y958750D01*
X106842Y958917D01*
X106550Y959000D01*
X106217Y958917D01*
X105967Y958750D01*
X105800Y958500D01*
X105717Y958167D01*
X105800Y957875D01*
X106008Y957583D01*
X106258Y957417D01*
X106550Y957375D01*
X106883Y957458D01*
X107133Y957667D01*
X107383Y958042D01*
G01X109567Y956500D02*
X109650Y957042D01*
X109775Y957500D01*
X109942Y957917D01*
X110150Y958375D01*
X110483Y959000D01*
X108817D01*
G01X78800Y949472D02*
X76300D01*
Y950513D01*
X76425Y950847D01*
X76592Y951055D01*
X76925Y951138D01*
X77258Y951055D01*
X77467Y950805D01*
X77592Y950513D01*
Y949472D01*
G01Y950513D02*
X78800Y951138D01*
G01Y953405D02*
X76300D01*
X76800Y952905D01*
G01X78800D02*
Y953905D01*
G01X78508Y955797D02*
X78717Y956088D01*
X78800Y956422D01*
X78717Y956755D01*
X78467Y957047D01*
X78092Y957255D01*
X77717Y957338D01*
X77258D01*
X76883Y957255D01*
X76550Y957047D01*
X76383Y956797D01*
X76300Y956505D01*
X76383Y956172D01*
X76550Y955922D01*
X76800Y955755D01*
X77133Y955672D01*
X77425Y955755D01*
X77717Y955963D01*
X77883Y956213D01*
X77925Y956505D01*
X77842Y956838D01*
X77633Y957088D01*
X77258Y957338D01*
G01X77758Y958813D02*
X77467Y959105D01*
X77300Y959355D01*
X77217Y959688D01*
X77300Y959980D01*
X77467Y960188D01*
X77717Y960355D01*
X78008Y960397D01*
X78258Y960355D01*
X78508Y960188D01*
X78717Y959938D01*
X78800Y959647D01*
X78717Y959313D01*
X78467Y959022D01*
X78092Y958855D01*
X77675Y958813D01*
X77133Y958897D01*
X76842Y959022D01*
X76550Y959230D01*
X76342Y959522D01*
X76300Y959813D01*
X76383Y960105D01*
X76592Y960313D01*
G01X99164Y1011001D02*
Y1013501D01*
X100205D01*
X100539Y1013376D01*
X100747Y1013209D01*
X100830Y1012876D01*
X100747Y1012543D01*
X100497Y1012334D01*
X100205Y1012209D01*
X99164D01*
G01X100205D02*
X100830Y1011001D01*
G01X103097D02*
Y1013501D01*
X102597Y1013001D01*
G01Y1011001D02*
X103597D01*
G01X105405Y1013084D02*
X105655Y1013334D01*
X105947Y1013459D01*
X106280Y1013501D01*
X106697Y1013418D01*
X106989Y1013209D01*
X107072Y1012959D01*
X107030Y1012709D01*
X106864Y1012501D01*
X106030Y1012084D01*
X105655Y1011793D01*
X105405Y1011376D01*
X105322Y1011001D01*
X107072D01*
G01X109297D02*
Y1013501D01*
X108797Y1013001D01*
G01Y1011001D02*
X109797D01*
G01X111605Y1013084D02*
X111855Y1013334D01*
X112147Y1013459D01*
X112480Y1013501D01*
X112897Y1013418D01*
X113189Y1013209D01*
X113272Y1012959D01*
X113230Y1012709D01*
X113064Y1012501D01*
X112230Y1012084D01*
X111855Y1011793D01*
X111605Y1011376D01*
X111522Y1011001D01*
X113272D01*
G01X122397Y993001D02*
Y997001D01*
X114997D01*
G01X99162Y1015067D02*
Y1017567D01*
X100203D01*
X100537Y1017442D01*
X100745Y1017275D01*
X100828Y1016942D01*
X100745Y1016609D01*
X100495Y1016400D01*
X100203Y1016275D01*
X99162D01*
G01X100203D02*
X100828Y1015067D01*
G01X103095D02*
Y1017567D01*
X102595Y1017067D01*
G01Y1015067D02*
X103595D01*
G01X105403Y1017150D02*
X105653Y1017400D01*
X105945Y1017525D01*
X106278Y1017567D01*
X106695Y1017484D01*
X106987Y1017275D01*
X107070Y1017025D01*
X107028Y1016775D01*
X106862Y1016567D01*
X106028Y1016150D01*
X105653Y1015859D01*
X105403Y1015442D01*
X105320Y1015067D01*
X107070D01*
G01X109295D02*
Y1017567D01*
X108795Y1017067D01*
G01Y1015067D02*
X109795D01*
G01X111478Y1015442D02*
X111728Y1015234D01*
X112020Y1015109D01*
X112395Y1015067D01*
X112770Y1015150D01*
X113062Y1015317D01*
X113270Y1015609D01*
X113312Y1015942D01*
X113228Y1016275D01*
X113020Y1016484D01*
X112728Y1016650D01*
X112437Y1016692D01*
X112145Y1016650D01*
X111770Y1016484D01*
X111895Y1017567D01*
X113020D01*
G01X114995Y1001067D02*
Y997067D01*
X122395D01*
G01X77755Y1008070D02*
Y1010570D01*
X78796D01*
X79130Y1010445D01*
X79338Y1010278D01*
X79421Y1009945D01*
X79338Y1009612D01*
X79088Y1009403D01*
X78796Y1009278D01*
X77755D01*
G01X78796D02*
X79421Y1008070D01*
G01X81688D02*
Y1010570D01*
X81188Y1010070D01*
G01Y1008070D02*
X82188D01*
G01X83996Y1010153D02*
X84246Y1010403D01*
X84538Y1010528D01*
X84871Y1010570D01*
X85288Y1010487D01*
X85580Y1010278D01*
X85663Y1010028D01*
X85621Y1009778D01*
X85455Y1009570D01*
X84621Y1009153D01*
X84246Y1008862D01*
X83996Y1008445D01*
X83913Y1008070D01*
X85663D01*
G01X87888D02*
Y1010570D01*
X87388Y1010070D01*
G01Y1008070D02*
X88388D01*
G01X90988D02*
X91280Y1008112D01*
X91613Y1008237D01*
X91821Y1008445D01*
X91905Y1008737D01*
X91821Y1009028D01*
X91571Y1009278D01*
X91196Y1009403D01*
X90780D01*
X90530Y1009487D01*
X90321Y1009695D01*
X90238Y1009987D01*
X90363Y1010278D01*
X90655Y1010487D01*
X90988Y1010570D01*
X91321Y1010487D01*
X91613Y1010278D01*
X91738Y1009987D01*
X91655Y1009695D01*
X91446Y1009487D01*
X91196Y1009403D01*
X90780D01*
X90405Y1009278D01*
X90155Y1009028D01*
X90071Y1008737D01*
X90155Y1008445D01*
X90363Y1008237D01*
X90696Y1008112D01*
X90988Y1008070D01*
G01X107563Y1001325D02*
Y1005325D01*
X100163D01*
G01X91849Y991708D02*
X89349D01*
Y992749D01*
X89474Y993083D01*
X89641Y993291D01*
X89974Y993374D01*
X90307Y993291D01*
X90516Y993041D01*
X90641Y992749D01*
Y991708D01*
G01Y992749D02*
X91849Y993374D01*
G01Y995641D02*
X89349D01*
X89849Y995141D01*
G01X91849D02*
Y996141D01*
G01X89766Y997949D02*
X89516Y998199D01*
X89391Y998491D01*
X89349Y998824D01*
X89432Y999241D01*
X89641Y999533D01*
X89891Y999616D01*
X90141Y999574D01*
X90349Y999408D01*
X90766Y998574D01*
X91057Y998199D01*
X91474Y997949D01*
X91849Y997866D01*
Y999616D01*
G01X89766Y1001049D02*
X89516Y1001299D01*
X89391Y1001591D01*
X89349Y1001924D01*
X89432Y1002341D01*
X89641Y1002633D01*
X89891Y1002716D01*
X90141Y1002674D01*
X90349Y1002508D01*
X90766Y1001674D01*
X91057Y1001299D01*
X91474Y1001049D01*
X91849Y1000966D01*
Y1002716D01*
G01X89766Y1004149D02*
X89516Y1004399D01*
X89391Y1004691D01*
X89349Y1005024D01*
X89432Y1005441D01*
X89641Y1005733D01*
X89891Y1005816D01*
X90141Y1005774D01*
X90349Y1005608D01*
X90766Y1004774D01*
X91057Y1004399D01*
X91474Y1004149D01*
X91849Y1004066D01*
Y1005816D01*
G01X106363Y993525D02*
X110363D01*
Y1000925D01*
G01X95986Y991763D02*
X93486D01*
Y992804D01*
X93611Y993138D01*
X93778Y993346D01*
X94111Y993429D01*
X94444Y993346D01*
X94653Y993096D01*
X94778Y992804D01*
Y991763D01*
G01Y992804D02*
X95986Y993429D01*
G01Y995696D02*
X93486D01*
X93986Y995196D01*
G01X95986D02*
Y996196D01*
G01X93903Y998004D02*
X93653Y998254D01*
X93528Y998546D01*
X93486Y998879D01*
X93569Y999296D01*
X93778Y999588D01*
X94028Y999671D01*
X94278Y999629D01*
X94486Y999463D01*
X94903Y998629D01*
X95194Y998254D01*
X95611Y998004D01*
X95986Y997921D01*
Y999671D01*
G01X93903Y1001104D02*
X93653Y1001354D01*
X93528Y1001646D01*
X93486Y1001979D01*
X93569Y1002396D01*
X93778Y1002688D01*
X94028Y1002771D01*
X94278Y1002729D01*
X94486Y1002563D01*
X94903Y1001729D01*
X95194Y1001354D01*
X95611Y1001104D01*
X95986Y1001021D01*
Y1002771D01*
G01X95486Y1004079D02*
X95778Y1004329D01*
X95944Y1004663D01*
X95986Y1005038D01*
X95944Y1005371D01*
X95736Y1005704D01*
X95486Y1005913D01*
X95236Y1005954D01*
X94944Y1005871D01*
X94736Y1005579D01*
X94653Y1005288D01*
Y1004913D01*
G01Y1005288D02*
X94528Y1005538D01*
X94319Y1005746D01*
X94069Y1005829D01*
X93819Y1005746D01*
X93611Y1005538D01*
X93486Y1005163D01*
X93528Y1004788D01*
X93694Y1004413D01*
G01X110500Y993580D02*
X114500D01*
Y1000980D01*
G01X114967Y1017500D02*
Y1020000D01*
X116008D01*
X116342Y1019875D01*
X116550Y1019708D01*
X116633Y1019375D01*
X116550Y1019042D01*
X116300Y1018833D01*
X116008Y1018708D01*
X114967D01*
G01X116008D02*
X116633Y1017500D01*
G01X118900D02*
Y1020000D01*
X118400Y1019500D01*
G01Y1017500D02*
X119400D01*
G01X121208Y1019583D02*
X121458Y1019833D01*
X121750Y1019958D01*
X122083Y1020000D01*
X122500Y1019917D01*
X122792Y1019708D01*
X122875Y1019458D01*
X122833Y1019208D01*
X122667Y1019000D01*
X121833Y1018583D01*
X121458Y1018292D01*
X121208Y1017875D01*
X121125Y1017500D01*
X122875D01*
G01X125100Y1020000D02*
X124767Y1019917D01*
X124517Y1019708D01*
X124350Y1019458D01*
X124225Y1019125D01*
X124183Y1018750D01*
X124225Y1018375D01*
X124350Y1018042D01*
X124517Y1017792D01*
X124767Y1017583D01*
X125100Y1017500D01*
X125433Y1017583D01*
X125683Y1017792D01*
X125850Y1018042D01*
X125975Y1018375D01*
X126017Y1018750D01*
X125975Y1019125D01*
X125850Y1019458D01*
X125683Y1019708D01*
X125433Y1019917D01*
X125100Y1020000D01*
G01X128200Y1017500D02*
X128492Y1017542D01*
X128825Y1017667D01*
X129033Y1017875D01*
X129117Y1018167D01*
X129033Y1018458D01*
X128783Y1018708D01*
X128408Y1018833D01*
X127992D01*
X127742Y1018917D01*
X127533Y1019125D01*
X127450Y1019417D01*
X127575Y1019708D01*
X127867Y1019917D01*
X128200Y1020000D01*
X128533Y1019917D01*
X128825Y1019708D01*
X128950Y1019417D01*
X128867Y1019125D01*
X128658Y1018917D01*
X128408Y1018833D01*
X127992D01*
X127617Y1018708D01*
X127367Y1018458D01*
X127283Y1018167D01*
X127367Y1017875D01*
X127575Y1017667D01*
X127908Y1017542D01*
X128200Y1017500D01*
G01X114967Y1009000D02*
Y1011500D01*
X116008D01*
X116342Y1011375D01*
X116550Y1011208D01*
X116633Y1010875D01*
X116550Y1010542D01*
X116300Y1010333D01*
X116008Y1010208D01*
X114967D01*
G01X116008D02*
X116633Y1009000D01*
G01X118900D02*
Y1011500D01*
X118400Y1011000D01*
G01Y1009000D02*
X119400D01*
G01X121208Y1011083D02*
X121458Y1011333D01*
X121750Y1011458D01*
X122083Y1011500D01*
X122500Y1011417D01*
X122792Y1011208D01*
X122875Y1010958D01*
X122833Y1010708D01*
X122667Y1010500D01*
X121833Y1010083D01*
X121458Y1009792D01*
X121208Y1009375D01*
X121125Y1009000D01*
X122875D01*
G01X125100D02*
Y1011500D01*
X124600Y1011000D01*
G01Y1009000D02*
X125600D01*
G01X127283Y1009500D02*
X127533Y1009208D01*
X127867Y1009042D01*
X128242Y1009000D01*
X128575Y1009042D01*
X128908Y1009250D01*
X129117Y1009500D01*
X129158Y1009750D01*
X129075Y1010042D01*
X128783Y1010250D01*
X128492Y1010333D01*
X128117D01*
G01X128492D02*
X128742Y1010458D01*
X128950Y1010667D01*
X129033Y1010917D01*
X128950Y1011167D01*
X128742Y1011375D01*
X128367Y1011500D01*
X127992Y1011458D01*
X127617Y1011292D01*
G01X116267Y1015792D02*
X116017Y1015917D01*
X115725Y1016000D01*
X115392D01*
X115017Y1015875D01*
X114725Y1015667D01*
X114517Y1015417D01*
X114350Y1015000D01*
X114308Y1014625D01*
X114392Y1014250D01*
X114517Y1014000D01*
X114767Y1013750D01*
X115058Y1013583D01*
X115350Y1013500D01*
X115642D01*
X115933Y1013583D01*
X116183Y1013708D01*
X116392Y1013875D01*
G01X117658Y1014542D02*
X117950Y1014833D01*
X118200Y1015000D01*
X118533Y1015083D01*
X118825Y1015000D01*
X119033Y1014833D01*
X119200Y1014583D01*
X119242Y1014292D01*
X119200Y1014042D01*
X119033Y1013792D01*
X118783Y1013583D01*
X118492Y1013500D01*
X118158Y1013583D01*
X117867Y1013833D01*
X117700Y1014208D01*
X117658Y1014625D01*
X117742Y1015167D01*
X117867Y1015458D01*
X118075Y1015750D01*
X118367Y1015958D01*
X118658Y1016000D01*
X118950Y1015917D01*
X119158Y1015708D01*
G01X121550Y1016000D02*
X121217Y1015917D01*
X120967Y1015708D01*
X120800Y1015458D01*
X120675Y1015125D01*
X120633Y1014750D01*
X120675Y1014375D01*
X120800Y1014042D01*
X120967Y1013792D01*
X121217Y1013583D01*
X121550Y1013500D01*
X121883Y1013583D01*
X122133Y1013792D01*
X122300Y1014042D01*
X122425Y1014375D01*
X122467Y1014750D01*
X122425Y1015125D01*
X122300Y1015458D01*
X122133Y1015708D01*
X121883Y1015917D01*
X121550Y1016000D01*
G01X123733Y1014000D02*
X123983Y1013708D01*
X124317Y1013542D01*
X124692Y1013500D01*
X125025Y1013542D01*
X125358Y1013750D01*
X125567Y1014000D01*
X125608Y1014250D01*
X125525Y1014542D01*
X125233Y1014750D01*
X124942Y1014833D01*
X124567D01*
G01X124942D02*
X125192Y1014958D01*
X125400Y1015167D01*
X125483Y1015417D01*
X125400Y1015667D01*
X125192Y1015875D01*
X124817Y1016000D01*
X124442Y1015958D01*
X124067Y1015792D01*
G01X94124Y1127004D02*
X99174D01*
Y1225704D01*
X123824D01*
Y1041304D01*
X99174D01*
Y1100004D01*
X94124D01*
Y1127004D01*
G01X83117Y1072000D02*
Y1074500D01*
X84158D01*
X84492Y1074375D01*
X84700Y1074208D01*
X84783Y1073875D01*
X84700Y1073542D01*
X84450Y1073333D01*
X84158Y1073208D01*
X83117D01*
G01X84158D02*
X84783Y1072000D01*
G01X86342Y1072292D02*
X86633Y1072083D01*
X86967Y1072000D01*
X87300Y1072083D01*
X87592Y1072333D01*
X87800Y1072708D01*
X87883Y1073083D01*
Y1073542D01*
X87800Y1073917D01*
X87592Y1074250D01*
X87342Y1074417D01*
X87050Y1074500D01*
X86717Y1074417D01*
X86467Y1074250D01*
X86300Y1074000D01*
X86217Y1073667D01*
X86300Y1073375D01*
X86508Y1073083D01*
X86758Y1072917D01*
X87050Y1072875D01*
X87383Y1072958D01*
X87633Y1073167D01*
X87883Y1073542D01*
G01X89358Y1073042D02*
X89650Y1073333D01*
X89900Y1073500D01*
X90233Y1073583D01*
X90525Y1073500D01*
X90733Y1073333D01*
X90900Y1073083D01*
X90942Y1072792D01*
X90900Y1072542D01*
X90733Y1072292D01*
X90483Y1072083D01*
X90192Y1072000D01*
X89858Y1072083D01*
X89567Y1072333D01*
X89400Y1072708D01*
X89358Y1073125D01*
X89442Y1073667D01*
X89567Y1073958D01*
X89775Y1074250D01*
X90067Y1074458D01*
X90358Y1074500D01*
X90650Y1074417D01*
X90858Y1074208D01*
G01X92458Y1073042D02*
X92750Y1073333D01*
X93000Y1073500D01*
X93333Y1073583D01*
X93625Y1073500D01*
X93833Y1073333D01*
X94000Y1073083D01*
X94042Y1072792D01*
X94000Y1072542D01*
X93833Y1072292D01*
X93583Y1072083D01*
X93292Y1072000D01*
X92958Y1072083D01*
X92667Y1072333D01*
X92500Y1072708D01*
X92458Y1073125D01*
X92542Y1073667D01*
X92667Y1073958D01*
X92875Y1074250D01*
X93167Y1074458D01*
X93458Y1074500D01*
X93750Y1074417D01*
X93958Y1074208D01*
G01X83117Y1068000D02*
Y1070500D01*
X84158D01*
X84492Y1070375D01*
X84700Y1070208D01*
X84783Y1069875D01*
X84700Y1069542D01*
X84450Y1069333D01*
X84158Y1069208D01*
X83117D01*
G01X84158D02*
X84783Y1068000D01*
G01X86342Y1068292D02*
X86633Y1068083D01*
X86967Y1068000D01*
X87300Y1068083D01*
X87592Y1068333D01*
X87800Y1068708D01*
X87883Y1069083D01*
Y1069542D01*
X87800Y1069917D01*
X87592Y1070250D01*
X87342Y1070417D01*
X87050Y1070500D01*
X86717Y1070417D01*
X86467Y1070250D01*
X86300Y1070000D01*
X86217Y1069667D01*
X86300Y1069375D01*
X86508Y1069083D01*
X86758Y1068917D01*
X87050Y1068875D01*
X87383Y1068958D01*
X87633Y1069167D01*
X87883Y1069542D01*
G01X89358Y1069042D02*
X89650Y1069333D01*
X89900Y1069500D01*
X90233Y1069583D01*
X90525Y1069500D01*
X90733Y1069333D01*
X90900Y1069083D01*
X90942Y1068792D01*
X90900Y1068542D01*
X90733Y1068292D01*
X90483Y1068083D01*
X90192Y1068000D01*
X89858Y1068083D01*
X89567Y1068333D01*
X89400Y1068708D01*
X89358Y1069125D01*
X89442Y1069667D01*
X89567Y1069958D01*
X89775Y1070250D01*
X90067Y1070458D01*
X90358Y1070500D01*
X90650Y1070417D01*
X90858Y1070208D01*
G01X93250Y1068000D02*
X93542Y1068042D01*
X93875Y1068167D01*
X94083Y1068375D01*
X94167Y1068667D01*
X94083Y1068958D01*
X93833Y1069208D01*
X93458Y1069333D01*
X93042D01*
X92792Y1069417D01*
X92583Y1069625D01*
X92500Y1069917D01*
X92625Y1070208D01*
X92917Y1070417D01*
X93250Y1070500D01*
X93583Y1070417D01*
X93875Y1070208D01*
X94000Y1069917D01*
X93917Y1069625D01*
X93708Y1069417D01*
X93458Y1069333D01*
X93042D01*
X92667Y1069208D01*
X92417Y1068958D01*
X92333Y1068667D01*
X92417Y1068375D01*
X92625Y1068167D01*
X92958Y1068042D01*
X93250Y1068000D01*
G01X94237Y1080173D02*
Y1084173D01*
X86837D01*
G01X83117Y1076000D02*
Y1078500D01*
X84158D01*
X84492Y1078375D01*
X84700Y1078208D01*
X84783Y1077875D01*
X84700Y1077542D01*
X84450Y1077333D01*
X84158Y1077208D01*
X83117D01*
G01X84158D02*
X84783Y1076000D01*
G01X86342Y1076292D02*
X86633Y1076083D01*
X86967Y1076000D01*
X87300Y1076083D01*
X87592Y1076333D01*
X87800Y1076708D01*
X87883Y1077083D01*
Y1077542D01*
X87800Y1077917D01*
X87592Y1078250D01*
X87342Y1078417D01*
X87050Y1078500D01*
X86717Y1078417D01*
X86467Y1078250D01*
X86300Y1078000D01*
X86217Y1077667D01*
X86300Y1077375D01*
X86508Y1077083D01*
X86758Y1076917D01*
X87050Y1076875D01*
X87383Y1076958D01*
X87633Y1077167D01*
X87883Y1077542D01*
G01X90067Y1076000D02*
X90150Y1076542D01*
X90275Y1077000D01*
X90442Y1077417D01*
X90650Y1077875D01*
X90983Y1078500D01*
X89317D01*
G01X93250D02*
X92917Y1078417D01*
X92667Y1078208D01*
X92500Y1077958D01*
X92375Y1077625D01*
X92333Y1077250D01*
X92375Y1076875D01*
X92500Y1076542D01*
X92667Y1076292D01*
X92917Y1076083D01*
X93250Y1076000D01*
X93583Y1076083D01*
X93833Y1076292D01*
X94000Y1076542D01*
X94125Y1076875D01*
X94167Y1077250D01*
X94125Y1077625D01*
X94000Y1077958D01*
X93833Y1078208D01*
X93583Y1078417D01*
X93250Y1078500D01*
G01X94237Y1084673D02*
Y1088673D01*
X86837D01*
G01Y1098673D02*
Y1094673D01*
X94237D01*
G01X86137Y1103373D02*
X74737D01*
G01X86137Y1089973D02*
Y1103373D01*
G01X74737Y1089973D02*
X86137D01*
G01X74737Y1103373D02*
Y1089973D01*
G01X97433Y1130050D02*
X97391Y1129717D01*
X97225Y1129425D01*
X96975Y1129175D01*
X96683Y1129008D01*
X96350Y1128925D01*
X96016D01*
X95683Y1129008D01*
X95391Y1129175D01*
X95141Y1129425D01*
X94975Y1129717D01*
X94933Y1130050D01*
X94975Y1130383D01*
X95141Y1130675D01*
X95391Y1130925D01*
X95683Y1131092D01*
X96016Y1131175D01*
X96350D01*
X96683Y1131092D01*
X96975Y1130925D01*
X97225Y1130675D01*
X97391Y1130383D01*
X97433Y1130050D01*
G01X96766Y1130383D02*
X97433Y1130883D01*
G01X95350Y1132358D02*
X95100Y1132608D01*
X94975Y1132900D01*
X94933Y1133233D01*
X95016Y1133650D01*
X95225Y1133942D01*
X95475Y1134025D01*
X95725Y1133983D01*
X95933Y1133817D01*
X96350Y1132983D01*
X96641Y1132608D01*
X97058Y1132358D01*
X97433Y1132275D01*
Y1134025D01*
G01Y1136250D02*
X94933D01*
X95433Y1135750D01*
G01X97433D02*
Y1136750D01*
G01X97058Y1138433D02*
X97266Y1138683D01*
X97391Y1138975D01*
X97433Y1139350D01*
X97350Y1139725D01*
X97183Y1140017D01*
X96891Y1140225D01*
X96558Y1140267D01*
X96225Y1140183D01*
X96016Y1139975D01*
X95850Y1139683D01*
X95808Y1139392D01*
X95850Y1139100D01*
X96016Y1138725D01*
X94933Y1138850D01*
Y1139975D01*
G01X92137Y1121173D02*
X90037Y1122973D01*
X92137Y1125173D01*
G01X92237Y1128773D02*
X73037D01*
Y1117573D01*
X92237D01*
Y1128773D01*
X91837D01*
G01X97000Y1161517D02*
X94500D01*
Y1162558D01*
X94625Y1162892D01*
X94792Y1163100D01*
X95125Y1163183D01*
X95458Y1163100D01*
X95667Y1162850D01*
X95792Y1162558D01*
Y1161517D01*
G01Y1162558D02*
X97000Y1163183D01*
G01X96708Y1164742D02*
X96917Y1165033D01*
X97000Y1165367D01*
X96917Y1165700D01*
X96667Y1165992D01*
X96292Y1166200D01*
X95917Y1166283D01*
X95458D01*
X95083Y1166200D01*
X94750Y1165992D01*
X94583Y1165742D01*
X94500Y1165450D01*
X94583Y1165117D01*
X94750Y1164867D01*
X95000Y1164700D01*
X95333Y1164617D01*
X95625Y1164700D01*
X95917Y1164908D01*
X96083Y1165158D01*
X96125Y1165450D01*
X96042Y1165783D01*
X95833Y1166033D01*
X95458Y1166283D01*
G01X96625Y1167633D02*
X96833Y1167883D01*
X96958Y1168175D01*
X97000Y1168550D01*
X96917Y1168925D01*
X96750Y1169217D01*
X96458Y1169425D01*
X96125Y1169467D01*
X95792Y1169383D01*
X95583Y1169175D01*
X95417Y1168883D01*
X95375Y1168592D01*
X95417Y1168300D01*
X95583Y1167925D01*
X94500Y1168050D01*
Y1169175D01*
G01X97000Y1171567D02*
X96458Y1171650D01*
X96000Y1171775D01*
X95583Y1171942D01*
X95125Y1172150D01*
X94500Y1172483D01*
Y1170817D01*
G01X89437Y1159473D02*
X97437D01*
Y1141873D01*
X89437D01*
Y1159473D01*
G01X87737Y1141673D02*
X82237D01*
G01X87737Y1149673D02*
Y1141673D01*
G01X82237Y1149673D02*
X87737D01*
G01X87208Y1186267D02*
X87083Y1186017D01*
X87000Y1185725D01*
Y1185392D01*
X87125Y1185017D01*
X87333Y1184725D01*
X87583Y1184517D01*
X88000Y1184350D01*
X88375Y1184308D01*
X88750Y1184392D01*
X89000Y1184517D01*
X89250Y1184767D01*
X89417Y1185058D01*
X89500Y1185350D01*
Y1185642D01*
X89417Y1185933D01*
X89292Y1186183D01*
X89125Y1186392D01*
G01Y1187533D02*
X89333Y1187783D01*
X89458Y1188075D01*
X89500Y1188450D01*
X89417Y1188825D01*
X89250Y1189117D01*
X88958Y1189325D01*
X88625Y1189367D01*
X88292Y1189283D01*
X88083Y1189075D01*
X87917Y1188783D01*
X87875Y1188492D01*
X87917Y1188200D01*
X88083Y1187825D01*
X87000Y1187950D01*
Y1189075D01*
G01X89500Y1191550D02*
X87000D01*
X87500Y1191050D01*
G01X89500D02*
Y1192050D01*
G01Y1195150D02*
X87000D01*
X88792Y1193608D01*
Y1195692D01*
G01X89708Y1198767D02*
X89583Y1198517D01*
X89500Y1198225D01*
Y1197892D01*
X89625Y1197517D01*
X89833Y1197225D01*
X90083Y1197017D01*
X90500Y1196850D01*
X90875Y1196808D01*
X91250Y1196892D01*
X91500Y1197017D01*
X91750Y1197267D01*
X91917Y1197558D01*
X92000Y1197850D01*
Y1198142D01*
X91917Y1198433D01*
X91792Y1198683D01*
X91625Y1198892D01*
G01Y1200033D02*
X91833Y1200283D01*
X91958Y1200575D01*
X92000Y1200950D01*
X91917Y1201325D01*
X91750Y1201617D01*
X91458Y1201825D01*
X91125Y1201867D01*
X90792Y1201783D01*
X90583Y1201575D01*
X90417Y1201283D01*
X90375Y1200992D01*
X90417Y1200700D01*
X90583Y1200325D01*
X89500Y1200450D01*
Y1201575D01*
G01X92000Y1204050D02*
X89500D01*
X90000Y1203550D01*
G01X92000D02*
Y1204550D01*
G01X91625Y1206233D02*
X91833Y1206483D01*
X91958Y1206775D01*
X92000Y1207150D01*
X91917Y1207525D01*
X91750Y1207817D01*
X91458Y1208025D01*
X91125Y1208067D01*
X90792Y1207983D01*
X90583Y1207775D01*
X90417Y1207483D01*
X90375Y1207192D01*
X90417Y1206900D01*
X90583Y1206525D01*
X89500Y1206650D01*
Y1207775D01*
G01X101849Y1234004D02*
Y1236504D01*
G01X103599D02*
Y1234004D01*
G01Y1235254D02*
X101849D01*
G01X104907Y1234004D02*
Y1236504D01*
X105741D01*
X106074Y1236379D01*
X106324Y1236212D01*
X106532Y1235962D01*
X106699Y1235671D01*
X106741Y1235254D01*
X106699Y1234837D01*
X106532Y1234546D01*
X106324Y1234296D01*
X106074Y1234129D01*
X105741Y1234004D01*
X104907D01*
G01X108007D02*
Y1236504D01*
X108841D01*
X109174Y1236379D01*
X109424Y1236212D01*
X109632Y1235962D01*
X109799Y1235671D01*
X109841Y1235254D01*
X109799Y1234837D01*
X109632Y1234546D01*
X109424Y1234296D01*
X109174Y1234129D01*
X108841Y1234004D01*
X108007D01*
G01X111149Y1234337D02*
X111482Y1234129D01*
X111857Y1234004D01*
X112191D01*
X112524Y1234129D01*
X112774Y1234337D01*
X112899Y1234629D01*
X112816Y1234921D01*
X112607Y1235171D01*
X112232Y1235337D01*
X111732Y1235421D01*
X111441Y1235587D01*
X111316Y1235879D01*
X111399Y1236171D01*
X111607Y1236379D01*
X111899Y1236504D01*
X112191D01*
X112482Y1236421D01*
X112732Y1236212D01*
G01X114082Y1234004D02*
X115124Y1236504D01*
X116166Y1234004D01*
G01X115791Y1234879D02*
X114457D01*
G01X117349Y1234337D02*
X117682Y1234129D01*
X118057Y1234004D01*
X118391D01*
X118724Y1234129D01*
X118974Y1234337D01*
X119099Y1234629D01*
X119016Y1234921D01*
X118807Y1235171D01*
X118432Y1235337D01*
X117932Y1235421D01*
X117641Y1235587D01*
X117516Y1235879D01*
X117599Y1236171D01*
X117807Y1236379D01*
X118099Y1236504D01*
X118391D01*
X118682Y1236421D01*
X118932Y1236212D01*
G01X121324Y1236504D02*
X120991Y1236421D01*
X120741Y1236212D01*
X120574Y1235962D01*
X120449Y1235629D01*
X120407Y1235254D01*
X120449Y1234879D01*
X120574Y1234546D01*
X120741Y1234296D01*
X120991Y1234087D01*
X121324Y1234004D01*
X121657Y1234087D01*
X121907Y1234296D01*
X122074Y1234546D01*
X122199Y1234879D01*
X122241Y1235254D01*
X122199Y1235629D01*
X122074Y1235962D01*
X121907Y1236212D01*
X121657Y1236421D01*
X121324Y1236504D01*
G01X81685Y1271273D02*
X79185D01*
Y1272314D01*
X79310Y1272648D01*
X79477Y1272856D01*
X79810Y1272939D01*
X80143Y1272856D01*
X80352Y1272606D01*
X80477Y1272314D01*
Y1271273D01*
G01Y1272314D02*
X81685Y1272939D01*
G01X79185Y1274373D02*
X81685D01*
Y1276039D01*
G01Y1279139D02*
Y1277473D01*
X79185D01*
Y1279139D01*
G01X80393Y1278473D02*
Y1277473D01*
G01X81685Y1280489D02*
X79185D01*
Y1281323D01*
X79310Y1281656D01*
X79477Y1281906D01*
X79727Y1282114D01*
X80018Y1282281D01*
X80435Y1282323D01*
X80852Y1282281D01*
X81143Y1282114D01*
X81393Y1281906D01*
X81560Y1281656D01*
X81685Y1281323D01*
Y1280489D01*
G01X79602Y1283714D02*
X79352Y1283964D01*
X79227Y1284256D01*
X79185Y1284589D01*
X79268Y1285006D01*
X79477Y1285298D01*
X79727Y1285381D01*
X79977Y1285339D01*
X80185Y1285173D01*
X80602Y1284339D01*
X80893Y1283964D01*
X81310Y1283714D01*
X81685Y1283631D01*
Y1285381D01*
G01X81310Y1286689D02*
X81518Y1286939D01*
X81643Y1287231D01*
X81685Y1287606D01*
X81602Y1287981D01*
X81435Y1288273D01*
X81143Y1288481D01*
X80810Y1288523D01*
X80477Y1288439D01*
X80268Y1288231D01*
X80102Y1287939D01*
X80060Y1287648D01*
X80102Y1287356D01*
X80268Y1286981D01*
X79185Y1287106D01*
Y1288231D01*
G01X131267Y165292D02*
X131017Y165417D01*
X130725Y165500D01*
X130392D01*
X130017Y165375D01*
X129725Y165167D01*
X129517Y164917D01*
X129350Y164500D01*
X129308Y164125D01*
X129392Y163750D01*
X129517Y163500D01*
X129767Y163250D01*
X130058Y163083D01*
X130350Y163000D01*
X130642D01*
X130933Y163083D01*
X131183Y163208D01*
X131392Y163375D01*
G01X132533Y163500D02*
X132783Y163208D01*
X133117Y163042D01*
X133492Y163000D01*
X133825Y163042D01*
X134158Y163250D01*
X134367Y163500D01*
X134408Y163750D01*
X134325Y164042D01*
X134033Y164250D01*
X133742Y164333D01*
X133367D01*
G01X133742D02*
X133992Y164458D01*
X134200Y164667D01*
X134283Y164917D01*
X134200Y165167D01*
X133992Y165375D01*
X133617Y165500D01*
X133242Y165458D01*
X132867Y165292D01*
G01X135633Y163375D02*
X135883Y163167D01*
X136175Y163042D01*
X136550Y163000D01*
X136925Y163083D01*
X137217Y163250D01*
X137425Y163542D01*
X137467Y163875D01*
X137383Y164208D01*
X137175Y164417D01*
X136883Y164583D01*
X136592Y164625D01*
X136300Y164583D01*
X135925Y164417D01*
X136050Y165500D01*
X137175D01*
G01X139650Y163000D02*
Y165500D01*
X139150Y165000D01*
G01Y163000D02*
X140150D01*
G01X166666Y209561D02*
Y212061D01*
X167707D01*
X168041Y211936D01*
X168249Y211769D01*
X168332Y211436D01*
X168249Y211103D01*
X167999Y210894D01*
X167707Y210769D01*
X166666D01*
G01X167707D02*
X168332Y209561D01*
G01X170516D02*
X170599Y210103D01*
X170724Y210561D01*
X170891Y210978D01*
X171099Y211436D01*
X171432Y212061D01*
X169766D01*
G01X172907Y211644D02*
X173157Y211894D01*
X173449Y212019D01*
X173782Y212061D01*
X174199Y211978D01*
X174491Y211769D01*
X174574Y211519D01*
X174532Y211269D01*
X174366Y211061D01*
X173532Y210644D01*
X173157Y210353D01*
X172907Y209936D01*
X172824Y209561D01*
X174574D01*
G01X176799Y212061D02*
X176466Y211978D01*
X176216Y211769D01*
X176049Y211519D01*
X175924Y211186D01*
X175882Y210811D01*
X175924Y210436D01*
X176049Y210103D01*
X176216Y209853D01*
X176466Y209644D01*
X176799Y209561D01*
X177132Y209644D01*
X177382Y209853D01*
X177549Y210103D01*
X177674Y210436D01*
X177716Y210811D01*
X177674Y211186D01*
X177549Y211519D01*
X177382Y211769D01*
X177132Y211978D01*
X176799Y212061D01*
G01X131267Y169292D02*
X131017Y169417D01*
X130725Y169500D01*
X130392D01*
X130017Y169375D01*
X129725Y169167D01*
X129517Y168917D01*
X129350Y168500D01*
X129308Y168125D01*
X129392Y167750D01*
X129517Y167500D01*
X129767Y167250D01*
X130058Y167083D01*
X130350Y167000D01*
X130642D01*
X130933Y167083D01*
X131183Y167208D01*
X131392Y167375D01*
G01X132533Y167500D02*
X132783Y167208D01*
X133117Y167042D01*
X133492Y167000D01*
X133825Y167042D01*
X134158Y167250D01*
X134367Y167500D01*
X134408Y167750D01*
X134325Y168042D01*
X134033Y168250D01*
X133742Y168333D01*
X133367D01*
G01X133742D02*
X133992Y168458D01*
X134200Y168667D01*
X134283Y168917D01*
X134200Y169167D01*
X133992Y169375D01*
X133617Y169500D01*
X133242Y169458D01*
X132867Y169292D01*
G01X135633Y167375D02*
X135883Y167167D01*
X136175Y167042D01*
X136550Y167000D01*
X136925Y167083D01*
X137217Y167250D01*
X137425Y167542D01*
X137467Y167875D01*
X137383Y168208D01*
X137175Y168417D01*
X136883Y168583D01*
X136592Y168625D01*
X136300Y168583D01*
X135925Y168417D01*
X136050Y169500D01*
X137175D01*
G01X139650D02*
X139317Y169417D01*
X139067Y169208D01*
X138900Y168958D01*
X138775Y168625D01*
X138733Y168250D01*
X138775Y167875D01*
X138900Y167542D01*
X139067Y167292D01*
X139317Y167083D01*
X139650Y167000D01*
X139983Y167083D01*
X140233Y167292D01*
X140400Y167542D01*
X140525Y167875D01*
X140567Y168250D01*
X140525Y168625D01*
X140400Y168958D01*
X140233Y169208D01*
X139983Y169417D01*
X139650Y169500D01*
G01X135454Y232761D02*
Y235261D01*
X136495D01*
X136829Y235136D01*
X137037Y234969D01*
X137120Y234636D01*
X137037Y234303D01*
X136787Y234094D01*
X136495Y233969D01*
X135454D01*
G01X136495D02*
X137120Y232761D01*
G01X138595Y233803D02*
X138887Y234094D01*
X139137Y234261D01*
X139470Y234344D01*
X139762Y234261D01*
X139970Y234094D01*
X140137Y233844D01*
X140179Y233553D01*
X140137Y233303D01*
X139970Y233053D01*
X139720Y232844D01*
X139429Y232761D01*
X139095Y232844D01*
X138804Y233094D01*
X138637Y233469D01*
X138595Y233886D01*
X138679Y234428D01*
X138804Y234719D01*
X139012Y235011D01*
X139304Y235219D01*
X139595Y235261D01*
X139887Y235178D01*
X140095Y234969D01*
G01X142487Y232761D02*
X142779Y232803D01*
X143112Y232928D01*
X143320Y233136D01*
X143404Y233428D01*
X143320Y233719D01*
X143070Y233969D01*
X142695Y234094D01*
X142279D01*
X142029Y234178D01*
X141820Y234386D01*
X141737Y234678D01*
X141862Y234969D01*
X142154Y235178D01*
X142487Y235261D01*
X142820Y235178D01*
X143112Y234969D01*
X143237Y234678D01*
X143154Y234386D01*
X142945Y234178D01*
X142695Y234094D01*
X142279D01*
X141904Y233969D01*
X141654Y233719D01*
X141570Y233428D01*
X141654Y233136D01*
X141862Y232928D01*
X142195Y232803D01*
X142487Y232761D01*
G01X144795Y234844D02*
X145045Y235094D01*
X145337Y235219D01*
X145670Y235261D01*
X146087Y235178D01*
X146379Y234969D01*
X146462Y234719D01*
X146420Y234469D01*
X146254Y234261D01*
X145420Y233844D01*
X145045Y233553D01*
X144795Y233136D01*
X144712Y232761D01*
X146462D01*
G01X144637Y242761D02*
Y246761D01*
X137237D01*
G01X170000Y222850D02*
X169958Y222517D01*
X169792Y222225D01*
X169542Y221975D01*
X169250Y221808D01*
X168917Y221725D01*
X168583D01*
X168250Y221808D01*
X167958Y221975D01*
X167708Y222225D01*
X167542Y222517D01*
X167500Y222850D01*
X167542Y223183D01*
X167708Y223475D01*
X167958Y223725D01*
X168250Y223892D01*
X168583Y223975D01*
X168917D01*
X169250Y223892D01*
X169542Y223725D01*
X169792Y223475D01*
X169958Y223183D01*
X170000Y222850D01*
G01X169333Y223183D02*
X170000Y223683D01*
G01Y225950D02*
X167500D01*
X168000Y225450D01*
G01X170000D02*
Y226450D01*
G01X169625Y228133D02*
X169833Y228383D01*
X169958Y228675D01*
X170000Y229050D01*
X169917Y229425D01*
X169750Y229717D01*
X169458Y229925D01*
X169125Y229967D01*
X168792Y229883D01*
X168583Y229675D01*
X168417Y229383D01*
X168375Y229092D01*
X168417Y228800D01*
X168583Y228425D01*
X167500Y228550D01*
Y229675D01*
G01X167917Y231358D02*
X167667Y231608D01*
X167542Y231900D01*
X167500Y232233D01*
X167583Y232650D01*
X167792Y232942D01*
X168042Y233025D01*
X168292Y232983D01*
X168500Y232817D01*
X168917Y231983D01*
X169208Y231608D01*
X169625Y231358D01*
X170000Y231275D01*
Y233025D01*
G01X142017Y250000D02*
Y252500D01*
X143058D01*
X143392Y252375D01*
X143600Y252208D01*
X143683Y251875D01*
X143600Y251542D01*
X143350Y251333D01*
X143058Y251208D01*
X142017D01*
G01X143058D02*
X143683Y250000D01*
G01X145158Y251042D02*
X145450Y251333D01*
X145700Y251500D01*
X146033Y251583D01*
X146325Y251500D01*
X146533Y251333D01*
X146700Y251083D01*
X146742Y250792D01*
X146700Y250542D01*
X146533Y250292D01*
X146283Y250083D01*
X145992Y250000D01*
X145658Y250083D01*
X145367Y250333D01*
X145200Y250708D01*
X145158Y251125D01*
X145242Y251667D01*
X145367Y251958D01*
X145575Y252250D01*
X145867Y252458D01*
X146158Y252500D01*
X146450Y252417D01*
X146658Y252208D01*
G01X149050Y250000D02*
X149342Y250042D01*
X149675Y250167D01*
X149883Y250375D01*
X149967Y250667D01*
X149883Y250958D01*
X149633Y251208D01*
X149258Y251333D01*
X148842D01*
X148592Y251417D01*
X148383Y251625D01*
X148300Y251917D01*
X148425Y252208D01*
X148717Y252417D01*
X149050Y252500D01*
X149383Y252417D01*
X149675Y252208D01*
X149800Y251917D01*
X149717Y251625D01*
X149508Y251417D01*
X149258Y251333D01*
X148842D01*
X148467Y251208D01*
X148217Y250958D01*
X148133Y250667D01*
X148217Y250375D01*
X148425Y250167D01*
X148758Y250042D01*
X149050Y250000D01*
G01X151358Y251042D02*
X151650Y251333D01*
X151900Y251500D01*
X152233Y251583D01*
X152525Y251500D01*
X152733Y251333D01*
X152900Y251083D01*
X152942Y250792D01*
X152900Y250542D01*
X152733Y250292D01*
X152483Y250083D01*
X152192Y250000D01*
X151858Y250083D01*
X151567Y250333D01*
X151400Y250708D01*
X151358Y251125D01*
X151442Y251667D01*
X151567Y251958D01*
X151775Y252250D01*
X152067Y252458D01*
X152358Y252500D01*
X152650Y252417D01*
X152858Y252208D01*
G01X137204Y230953D02*
X136954Y231078D01*
X136662Y231161D01*
X136329D01*
X135954Y231036D01*
X135662Y230828D01*
X135454Y230578D01*
X135287Y230161D01*
X135245Y229786D01*
X135329Y229411D01*
X135454Y229161D01*
X135704Y228911D01*
X135995Y228744D01*
X136287Y228661D01*
X136579D01*
X136870Y228744D01*
X137120Y228869D01*
X137329Y229036D01*
G01X138470Y229161D02*
X138720Y228869D01*
X139054Y228703D01*
X139429Y228661D01*
X139762Y228703D01*
X140095Y228911D01*
X140304Y229161D01*
X140345Y229411D01*
X140262Y229703D01*
X139970Y229911D01*
X139679Y229994D01*
X139304D01*
G01X139679D02*
X139929Y230119D01*
X140137Y230328D01*
X140220Y230578D01*
X140137Y230828D01*
X139929Y231036D01*
X139554Y231161D01*
X139179Y231119D01*
X138804Y230953D01*
G01X141570Y229036D02*
X141820Y228828D01*
X142112Y228703D01*
X142487Y228661D01*
X142862Y228744D01*
X143154Y228911D01*
X143362Y229203D01*
X143404Y229536D01*
X143320Y229869D01*
X143112Y230078D01*
X142820Y230244D01*
X142529Y230286D01*
X142237Y230244D01*
X141862Y230078D01*
X141987Y231161D01*
X143112D01*
G01X145587Y228661D02*
X145879Y228703D01*
X146212Y228828D01*
X146420Y229036D01*
X146504Y229328D01*
X146420Y229619D01*
X146170Y229869D01*
X145795Y229994D01*
X145379D01*
X145129Y230078D01*
X144920Y230286D01*
X144837Y230578D01*
X144962Y230869D01*
X145254Y231078D01*
X145587Y231161D01*
X145920Y231078D01*
X146212Y230869D01*
X146337Y230578D01*
X146254Y230286D01*
X146045Y230078D01*
X145795Y229994D01*
X145379D01*
X145004Y229869D01*
X144754Y229619D01*
X144670Y229328D01*
X144754Y229036D01*
X144962Y228828D01*
X145295Y228703D01*
X145587Y228661D01*
G01X168416Y215953D02*
X168166Y216078D01*
X167874Y216161D01*
X167541D01*
X167166Y216036D01*
X166874Y215828D01*
X166666Y215578D01*
X166499Y215161D01*
X166457Y214786D01*
X166541Y214411D01*
X166666Y214161D01*
X166916Y213911D01*
X167207Y213744D01*
X167499Y213661D01*
X167791D01*
X168082Y213744D01*
X168332Y213869D01*
X168541Y214036D01*
G01X169682Y214161D02*
X169932Y213869D01*
X170266Y213703D01*
X170641Y213661D01*
X170974Y213703D01*
X171307Y213911D01*
X171516Y214161D01*
X171557Y214411D01*
X171474Y214703D01*
X171182Y214911D01*
X170891Y214994D01*
X170516D01*
G01X170891D02*
X171141Y215119D01*
X171349Y215328D01*
X171432Y215578D01*
X171349Y215828D01*
X171141Y216036D01*
X170766Y216161D01*
X170391Y216119D01*
X170016Y215953D01*
G01X173616Y213661D02*
X173699Y214203D01*
X173824Y214661D01*
X173991Y215078D01*
X174199Y215536D01*
X174532Y216161D01*
X172866D01*
G01X177299Y213661D02*
Y216161D01*
X175757Y214369D01*
X177841D01*
G01X133500Y264300D02*
X136000D01*
G01X133500Y263342D02*
Y265258D01*
G01X136000Y266567D02*
X133500D01*
Y267567D01*
X133625Y267900D01*
X133917Y268150D01*
X134250Y268233D01*
X134583Y268150D01*
X134833Y267942D01*
X134958Y267567D01*
Y266567D01*
G01X136000Y270500D02*
X133500D01*
X134000Y270000D01*
G01X136000D02*
Y271000D01*
G01X133917Y272808D02*
X133667Y273058D01*
X133542Y273350D01*
X133500Y273683D01*
X133583Y274100D01*
X133792Y274392D01*
X134042Y274475D01*
X134292Y274433D01*
X134500Y274267D01*
X134917Y273433D01*
X135208Y273058D01*
X135625Y272808D01*
X136000Y272725D01*
Y274475D01*
G01X133917Y275908D02*
X133667Y276158D01*
X133542Y276450D01*
X133500Y276783D01*
X133583Y277200D01*
X133792Y277492D01*
X134042Y277575D01*
X134292Y277533D01*
X134500Y277367D01*
X134917Y276533D01*
X135208Y276158D01*
X135625Y275908D01*
X136000Y275825D01*
Y277575D01*
G01X165506Y448464D02*
X166173Y448964D01*
X166673Y449797D01*
X167006Y450964D01*
X166673Y451964D01*
X166006Y452631D01*
X164840Y453131D01*
X160340D01*
Y443131D01*
X165840D01*
X167006Y443798D01*
X167673Y444798D01*
X168006Y445964D01*
X167673Y447131D01*
X166673Y448131D01*
X165506Y448464D01*
X160340D01*
G01X176773Y443131D02*
Y453131D01*
X170606Y445964D01*
X178940D01*
G01X185373Y443131D02*
X186540Y443298D01*
X187873Y443798D01*
X188706Y444631D01*
X189040Y445798D01*
X188706Y446964D01*
X187706Y447964D01*
X186206Y448464D01*
X184540D01*
X183540Y448798D01*
X182706Y449631D01*
X182373Y450798D01*
X182873Y451964D01*
X184039Y452798D01*
X185373Y453131D01*
X186706Y452798D01*
X187873Y451964D01*
X188373Y450798D01*
X188040Y449631D01*
X187206Y448798D01*
X186206Y448464D01*
X184540D01*
X183040Y447964D01*
X182040Y446964D01*
X181706Y445798D01*
X182040Y444631D01*
X182873Y443798D01*
X184206Y443298D01*
X185373Y443131D01*
G01X195973Y442798D02*
X195640Y442964D01*
Y443298D01*
X195973Y443464D01*
X196306Y443298D01*
Y442964D01*
X195973Y442798D01*
G01X206573Y453131D02*
X205239Y452798D01*
X204240Y451964D01*
X203573Y450964D01*
X203073Y449631D01*
X202906Y448131D01*
X203073Y446631D01*
X203573Y445298D01*
X204240Y444297D01*
X205239Y443464D01*
X206573Y443131D01*
X207906Y443464D01*
X208906Y444297D01*
X209573Y445298D01*
X210073Y446631D01*
X210240Y448131D01*
X210073Y449631D01*
X209573Y450964D01*
X208906Y451964D01*
X207906Y452798D01*
X206573Y453131D01*
G01X217173Y443131D02*
Y453131D01*
X215173Y451131D01*
G01Y443131D02*
X219173D01*
G01X227773D02*
Y453131D01*
X225773Y451131D01*
G01Y443131D02*
X229773D01*
G01X238373D02*
Y453131D01*
X236373Y451131D01*
G01Y443131D02*
X240373D01*
G01X245806Y451464D02*
X246806Y452464D01*
X247973Y452964D01*
X249306Y453131D01*
X250973Y452798D01*
X252140Y451964D01*
X252473Y450964D01*
X252306Y449964D01*
X251640Y449131D01*
X248306Y447464D01*
X246806Y446298D01*
X245806Y444631D01*
X245473Y443131D01*
X252473D01*
G01X259573Y442798D02*
X259240Y442964D01*
Y443298D01*
X259573Y443464D01*
X259906Y443298D01*
Y442964D01*
X259573Y442798D01*
G01X270173Y453131D02*
X268839Y452798D01*
X267840Y451964D01*
X267173Y450964D01*
X266673Y449631D01*
X266506Y448131D01*
X266673Y446631D01*
X267173Y445298D01*
X267840Y444297D01*
X268839Y443464D01*
X270173Y443131D01*
X271506Y443464D01*
X272506Y444297D01*
X273173Y445298D01*
X273673Y446631D01*
X273840Y448131D01*
X273673Y449631D01*
X273173Y450964D01*
X272506Y451964D01*
X271506Y452798D01*
X270173Y453131D01*
G01X280773D02*
X279439Y452798D01*
X278440Y451964D01*
X277773Y450964D01*
X277273Y449631D01*
X277106Y448131D01*
X277273Y446631D01*
X277773Y445298D01*
X278440Y444297D01*
X279439Y443464D01*
X280773Y443131D01*
X282106Y443464D01*
X283106Y444297D01*
X283773Y445298D01*
X284273Y446631D01*
X284440Y448131D01*
X284273Y449631D01*
X283773Y450964D01*
X283106Y451964D01*
X282106Y452798D01*
X280773Y453131D01*
G01X291373Y443131D02*
Y453131D01*
X289373Y451131D01*
G01Y443131D02*
X293373D01*
G01X301973D02*
Y453131D01*
X299973Y451131D01*
G01Y443131D02*
X303973D01*
G01X160340Y426131D02*
Y436131D01*
X164673Y427798D01*
X169006Y436131D01*
Y426131D01*
G01X171106D02*
X175273Y436131D01*
X179440Y426131D01*
G01X177940Y429631D02*
X172606D01*
G01X182206Y426131D02*
Y436131D01*
X185540D01*
X186873Y435631D01*
X187873Y434964D01*
X188706Y433964D01*
X189373Y432797D01*
X189540Y431131D01*
X189373Y429464D01*
X188706Y428298D01*
X187873Y427297D01*
X186873Y426631D01*
X185540Y426131D01*
X182206D01*
G01X199806D02*
X193140D01*
Y436131D01*
X199806D01*
G01X197140Y431298D02*
X193140D01*
G01X215673Y436131D02*
X219673D01*
G01X217673D02*
Y426131D01*
G01X215673D02*
X219673D01*
G01X224440D02*
Y436131D01*
X232106Y426131D01*
Y436131D01*
G01X249473D02*
Y426131D01*
G01X245640Y436131D02*
X253306D01*
G01X255906Y426131D02*
X260073Y436131D01*
X264240Y426131D01*
G01X262740Y429631D02*
X257406D01*
G01X268673Y436131D02*
X272673D01*
G01X270673D02*
Y426131D01*
G01X268673D02*
X272673D01*
G01X276273Y436131D02*
X278606Y426131D01*
X281273Y436131D01*
X283940Y426131D01*
X286273Y436131D01*
G01X287706Y426131D02*
X291873Y436131D01*
X296040Y426131D01*
G01X294540Y429631D02*
X289206D01*
G01X298640Y426131D02*
Y436131D01*
X306306Y426131D01*
Y436131D01*
G01X143006Y480464D02*
X143673Y480964D01*
X144173Y481797D01*
X144506Y482964D01*
X144173Y483964D01*
X143506Y484631D01*
X142340Y485131D01*
X137840D01*
Y475131D01*
X143340D01*
X144506Y475798D01*
X145173Y476798D01*
X145506Y477964D01*
X145173Y479131D01*
X144173Y480131D01*
X143006Y480464D01*
X137840D01*
G01X149940Y475131D02*
Y481797D01*
G01Y480464D02*
X150773Y481131D01*
X151606Y481631D01*
X152773Y481797D01*
X153606Y481631D01*
X154606Y481131D01*
G01X159373Y472131D02*
X160373Y471798D01*
X161706Y472131D01*
X162540Y472798D01*
X163206Y473631D01*
X164206Y476297D01*
X166373Y481797D01*
G01X161040D02*
X164206Y476297D01*
G01X176140Y480964D02*
X174973Y481631D01*
X173973Y481797D01*
X172640Y481464D01*
X171640Y480798D01*
X170973Y479631D01*
X170806Y478464D01*
X170973Y477298D01*
X171640Y476297D01*
X172640Y475464D01*
X173973Y475131D01*
X175140Y475464D01*
X176140Y476131D01*
G01X181573Y479631D02*
X186906D01*
X186406Y480798D01*
X185573Y481464D01*
X184406Y481797D01*
X183240Y481631D01*
X182240Y481131D01*
X181573Y479964D01*
X181240Y478964D01*
Y477964D01*
X181573Y476964D01*
X182406Y475964D01*
X183406Y475298D01*
X184573Y475131D01*
X185740Y475464D01*
X186906Y476464D01*
G01X208940Y484298D02*
X207940Y484798D01*
X206773Y485131D01*
X205440D01*
X203939Y484631D01*
X202773Y483798D01*
X201940Y482798D01*
X201273Y481131D01*
X201106Y479631D01*
X201440Y478131D01*
X201940Y477131D01*
X202940Y476131D01*
X204106Y475464D01*
X205273Y475131D01*
X206440D01*
X207606Y475464D01*
X208606Y475964D01*
X209440Y476631D01*
G01X218873Y475131D02*
Y481797D01*
G01Y480631D02*
X218206Y481298D01*
X217206Y481631D01*
X216040Y481797D01*
X214873Y481464D01*
X213873Y480798D01*
X213206Y479798D01*
X212873Y478464D01*
X213206Y477131D01*
X213873Y476131D01*
X214873Y475464D01*
X216040Y475131D01*
X217206Y475298D01*
X218206Y475798D01*
X218873Y476464D01*
G01X223640Y475131D02*
Y481797D01*
G01Y480131D02*
X224306Y480964D01*
X225306Y481631D01*
X226640Y481797D01*
X227806Y481631D01*
X228806Y480964D01*
X229306Y479798D01*
Y475131D01*
G01X233573Y472131D02*
X234573Y471798D01*
X235906Y472131D01*
X236740Y472798D01*
X237406Y473631D01*
X238406Y476297D01*
X240573Y481797D01*
G01X235240D02*
X238406Y476297D01*
G01X247673Y475131D02*
X246673Y475298D01*
X245673Y475964D01*
X245006Y477131D01*
X244673Y478464D01*
X245006Y479798D01*
X245673Y480964D01*
X246673Y481631D01*
X247673Y481797D01*
X248673Y481631D01*
X249673Y480964D01*
X250340Y479798D01*
X250506Y478464D01*
X250340Y477131D01*
X249673Y475964D01*
X248673Y475298D01*
X247673Y475131D01*
G01X255440D02*
Y481797D01*
G01Y480131D02*
X256106Y480964D01*
X257106Y481631D01*
X258440Y481797D01*
X259606Y481631D01*
X260606Y480964D01*
X261106Y479798D01*
Y475131D01*
G01X276306D02*
Y485131D01*
X282640D01*
G01X280306Y480298D02*
X276306D01*
G01X290073Y474798D02*
X289740Y474964D01*
Y475298D01*
X290073Y475464D01*
X290406Y475298D01*
Y474964D01*
X290073Y474798D01*
G01X297006Y475131D02*
Y485131D01*
X300340D01*
X301673Y484631D01*
X302673Y483964D01*
X303506Y482964D01*
X304173Y481797D01*
X304340Y480131D01*
X304173Y478464D01*
X303506Y477298D01*
X302673Y476297D01*
X301673Y475631D01*
X300340Y475131D01*
X297006D01*
G01X307940D02*
Y485131D01*
X311940D01*
X313273Y484631D01*
X314273Y483464D01*
X314606Y482131D01*
X314273Y480798D01*
X313440Y479798D01*
X311940Y479297D01*
X307940D01*
G01X323206Y480464D02*
X323873Y480964D01*
X324373Y481797D01*
X324706Y482964D01*
X324373Y483964D01*
X323706Y484631D01*
X322540Y485131D01*
X318040D01*
Y475131D01*
X323540D01*
X324706Y475798D01*
X325373Y476798D01*
X325706Y477964D01*
X325373Y479131D01*
X324373Y480131D01*
X323206Y480464D01*
X318040D01*
G01X162832Y491642D02*
X162499Y491684D01*
X162207Y491850D01*
X161957Y492100D01*
X161790Y492392D01*
X161707Y492725D01*
Y493059D01*
X161790Y493392D01*
X161957Y493684D01*
X162207Y493934D01*
X162499Y494100D01*
X162832Y494142D01*
X163165Y494100D01*
X163457Y493934D01*
X163707Y493684D01*
X163874Y493392D01*
X163957Y493059D01*
Y492725D01*
X163874Y492392D01*
X163707Y492100D01*
X163457Y491850D01*
X163165Y491684D01*
X162832Y491642D01*
G01X163165Y492309D02*
X163665Y491642D01*
G01X165140Y493725D02*
X165390Y493975D01*
X165682Y494100D01*
X166015Y494142D01*
X166432Y494059D01*
X166724Y493850D01*
X166807Y493600D01*
X166765Y493350D01*
X166599Y493142D01*
X165765Y492725D01*
X165390Y492434D01*
X165140Y492017D01*
X165057Y491642D01*
X166807D01*
G01X168949D02*
X169032Y492184D01*
X169157Y492642D01*
X169324Y493059D01*
X169532Y493517D01*
X169865Y494142D01*
X168199D01*
G01X171340Y492684D02*
X171632Y492975D01*
X171882Y493142D01*
X172215Y493225D01*
X172507Y493142D01*
X172715Y492975D01*
X172882Y492725D01*
X172924Y492434D01*
X172882Y492184D01*
X172715Y491934D01*
X172465Y491725D01*
X172174Y491642D01*
X171840Y491725D01*
X171549Y491975D01*
X171382Y492350D01*
X171340Y492767D01*
X171424Y493309D01*
X171549Y493600D01*
X171757Y493892D01*
X172049Y494100D01*
X172340Y494142D01*
X172632Y494059D01*
X172840Y493850D01*
G01X161482Y496142D02*
X174482D01*
G01X161482Y510142D02*
Y496142D01*
G01X164628Y522874D02*
Y525374D01*
X165669D01*
X166003Y525249D01*
X166211Y525082D01*
X166294Y524749D01*
X166211Y524416D01*
X165961Y524207D01*
X165669Y524082D01*
X164628D01*
G01X165669D02*
X166294Y522874D01*
G01X167644Y523249D02*
X167894Y523041D01*
X168186Y522916D01*
X168561Y522874D01*
X168936Y522957D01*
X169228Y523124D01*
X169436Y523416D01*
X169478Y523749D01*
X169394Y524082D01*
X169186Y524291D01*
X168894Y524457D01*
X168603Y524499D01*
X168311Y524457D01*
X167936Y524291D01*
X168061Y525374D01*
X169186D01*
G01X171661D02*
X171328Y525291D01*
X171078Y525082D01*
X170911Y524832D01*
X170786Y524499D01*
X170744Y524124D01*
X170786Y523749D01*
X170911Y523416D01*
X171078Y523166D01*
X171328Y522957D01*
X171661Y522874D01*
X171994Y522957D01*
X172244Y523166D01*
X172411Y523416D01*
X172536Y523749D01*
X172578Y524124D01*
X172536Y524499D01*
X172411Y524832D01*
X172244Y525082D01*
X171994Y525291D01*
X171661Y525374D01*
G01X175261Y522874D02*
Y525374D01*
X173719Y523582D01*
X175803D01*
G01X173811Y510874D02*
Y514874D01*
X166411D01*
G01X174482Y510142D02*
X161482D01*
G01X165987Y550352D02*
X165737Y550477D01*
X165445Y550560D01*
X165112D01*
X164737Y550435D01*
X164445Y550227D01*
X164237Y549977D01*
X164070Y549560D01*
X164028Y549185D01*
X164112Y548810D01*
X164237Y548560D01*
X164487Y548310D01*
X164778Y548143D01*
X165070Y548060D01*
X165362D01*
X165653Y548143D01*
X165903Y548268D01*
X166112Y548435D01*
G01X167378Y549102D02*
X167670Y549393D01*
X167920Y549560D01*
X168253Y549643D01*
X168545Y549560D01*
X168753Y549393D01*
X168920Y549143D01*
X168962Y548852D01*
X168920Y548602D01*
X168753Y548352D01*
X168503Y548143D01*
X168212Y548060D01*
X167878Y548143D01*
X167587Y548393D01*
X167420Y548768D01*
X167378Y549185D01*
X167462Y549727D01*
X167587Y550018D01*
X167795Y550310D01*
X168087Y550518D01*
X168378Y550560D01*
X168670Y550477D01*
X168878Y550268D01*
G01X171270Y548060D02*
Y550560D01*
X170770Y550060D01*
G01Y548060D02*
X171770D01*
G01X174870D02*
Y550560D01*
X173328Y548768D01*
X175412D01*
G01X164864Y599001D02*
Y601501D01*
X165905D01*
X166239Y601376D01*
X166447Y601209D01*
X166530Y600876D01*
X166447Y600543D01*
X166197Y600334D01*
X165905Y600209D01*
X164864D01*
G01X165905D02*
X166530Y599001D01*
G01X168797D02*
Y601501D01*
X168297Y601001D01*
G01Y599001D02*
X169297D01*
G01X171105Y601084D02*
X171355Y601334D01*
X171647Y601459D01*
X171980Y601501D01*
X172397Y601418D01*
X172689Y601209D01*
X172772Y600959D01*
X172730Y600709D01*
X172564Y600501D01*
X171730Y600084D01*
X171355Y599793D01*
X171105Y599376D01*
X171022Y599001D01*
X172772D01*
G01X174080Y599501D02*
X174330Y599209D01*
X174664Y599043D01*
X175039Y599001D01*
X175372Y599043D01*
X175705Y599251D01*
X175914Y599501D01*
X175955Y599751D01*
X175872Y600043D01*
X175580Y600251D01*
X175289Y600334D01*
X174914D01*
G01X175289D02*
X175539Y600459D01*
X175747Y600668D01*
X175830Y600918D01*
X175747Y601168D01*
X175539Y601376D01*
X175164Y601501D01*
X174789Y601459D01*
X174414Y601293D01*
G01X177305Y601084D02*
X177555Y601334D01*
X177847Y601459D01*
X178180Y601501D01*
X178597Y601418D01*
X178889Y601209D01*
X178972Y600959D01*
X178930Y600709D01*
X178764Y600501D01*
X177930Y600084D01*
X177555Y599793D01*
X177305Y599376D01*
X177222Y599001D01*
X178972D01*
G01X148940Y598293D02*
Y600793D01*
X149981D01*
X150315Y600668D01*
X150523Y600501D01*
X150606Y600168D01*
X150523Y599835D01*
X150273Y599626D01*
X149981Y599501D01*
X148940D01*
G01X149981D02*
X150606Y598293D01*
G01X152873D02*
Y600793D01*
X152373Y600293D01*
G01Y598293D02*
X153373D01*
G01X155181Y600376D02*
X155431Y600626D01*
X155723Y600751D01*
X156056Y600793D01*
X156473Y600710D01*
X156765Y600501D01*
X156848Y600251D01*
X156806Y600001D01*
X156640Y599793D01*
X155806Y599376D01*
X155431Y599085D01*
X155181Y598668D01*
X155098Y598293D01*
X156848D01*
G01X158156Y598793D02*
X158406Y598501D01*
X158740Y598335D01*
X159115Y598293D01*
X159448Y598335D01*
X159781Y598543D01*
X159990Y598793D01*
X160031Y599043D01*
X159948Y599335D01*
X159656Y599543D01*
X159365Y599626D01*
X158990D01*
G01X159365D02*
X159615Y599751D01*
X159823Y599960D01*
X159906Y600210D01*
X159823Y600460D01*
X159615Y600668D01*
X159240Y600793D01*
X158865Y600751D01*
X158490Y600585D01*
G01X162090Y598293D02*
X162173Y598835D01*
X162298Y599293D01*
X162465Y599710D01*
X162673Y600168D01*
X163006Y600793D01*
X161340D01*
G01X174263Y589025D02*
Y593025D01*
X166863D01*
G01X149967Y572500D02*
Y575000D01*
X151008D01*
X151342Y574875D01*
X151550Y574708D01*
X151633Y574375D01*
X151550Y574042D01*
X151300Y573833D01*
X151008Y573708D01*
X149967D01*
G01X151008D02*
X151633Y572500D01*
G01X153900D02*
Y575000D01*
X153400Y574500D01*
G01Y572500D02*
X154400D01*
G01X156208Y574583D02*
X156458Y574833D01*
X156750Y574958D01*
X157083Y575000D01*
X157500Y574917D01*
X157792Y574708D01*
X157875Y574458D01*
X157833Y574208D01*
X157667Y574000D01*
X156833Y573583D01*
X156458Y573292D01*
X156208Y572875D01*
X156125Y572500D01*
X157875D01*
G01X159183Y573000D02*
X159433Y572708D01*
X159767Y572542D01*
X160142Y572500D01*
X160475Y572542D01*
X160808Y572750D01*
X161017Y573000D01*
X161058Y573250D01*
X160975Y573542D01*
X160683Y573750D01*
X160392Y573833D01*
X160017D01*
G01X160392D02*
X160642Y573958D01*
X160850Y574167D01*
X160933Y574417D01*
X160850Y574667D01*
X160642Y574875D01*
X160267Y575000D01*
X159892Y574958D01*
X159517Y574792D01*
G01X163200Y572500D02*
X163492Y572542D01*
X163825Y572667D01*
X164033Y572875D01*
X164117Y573167D01*
X164033Y573458D01*
X163783Y573708D01*
X163408Y573833D01*
X162992D01*
X162742Y573917D01*
X162533Y574125D01*
X162450Y574417D01*
X162575Y574708D01*
X162867Y574917D01*
X163200Y575000D01*
X163533Y574917D01*
X163825Y574708D01*
X163950Y574417D01*
X163867Y574125D01*
X163658Y573917D01*
X163408Y573833D01*
X162992D01*
X162617Y573708D01*
X162367Y573458D01*
X162283Y573167D01*
X162367Y572875D01*
X162575Y572667D01*
X162908Y572542D01*
X163200Y572500D01*
G01X172963Y571725D02*
Y575725D01*
X165563D01*
G01X158536Y582485D02*
X156036D01*
Y583526D01*
X156161Y583860D01*
X156328Y584068D01*
X156661Y584151D01*
X156994Y584068D01*
X157203Y583818D01*
X157328Y583526D01*
Y582485D01*
G01Y583526D02*
X158536Y584151D01*
G01Y586418D02*
X156036D01*
X156536Y585918D01*
G01X158536D02*
Y586918D01*
G01X156453Y588726D02*
X156203Y588976D01*
X156078Y589268D01*
X156036Y589601D01*
X156119Y590018D01*
X156328Y590310D01*
X156578Y590393D01*
X156828Y590351D01*
X157036Y590185D01*
X157453Y589351D01*
X157744Y588976D01*
X158161Y588726D01*
X158536Y588643D01*
Y590393D01*
G01Y593118D02*
X156036D01*
X157828Y591576D01*
Y593660D01*
G01X156036Y595718D02*
X156119Y595385D01*
X156328Y595135D01*
X156578Y594968D01*
X156911Y594843D01*
X157286Y594801D01*
X157661Y594843D01*
X157994Y594968D01*
X158244Y595135D01*
X158453Y595385D01*
X158536Y595718D01*
X158453Y596051D01*
X158244Y596301D01*
X157994Y596468D01*
X157661Y596593D01*
X157286Y596635D01*
X156911Y596593D01*
X156578Y596468D01*
X156328Y596301D01*
X156119Y596051D01*
X156036Y595718D01*
G01X162673Y582540D02*
X160173D01*
Y583581D01*
X160298Y583915D01*
X160465Y584123D01*
X160798Y584206D01*
X161131Y584123D01*
X161340Y583873D01*
X161465Y583581D01*
Y582540D01*
G01Y583581D02*
X162673Y584206D01*
G01Y586473D02*
X160173D01*
X160673Y585973D01*
G01X162673D02*
Y586973D01*
G01X160590Y588781D02*
X160340Y589031D01*
X160215Y589323D01*
X160173Y589656D01*
X160256Y590073D01*
X160465Y590365D01*
X160715Y590448D01*
X160965Y590406D01*
X161173Y590240D01*
X161590Y589406D01*
X161881Y589031D01*
X162298Y588781D01*
X162673Y588698D01*
Y590448D01*
G01Y593173D02*
X160173D01*
X161965Y591631D01*
Y593715D01*
G01X160590Y594981D02*
X160340Y595231D01*
X160215Y595523D01*
X160173Y595856D01*
X160256Y596273D01*
X160465Y596565D01*
X160715Y596648D01*
X160965Y596606D01*
X161173Y596440D01*
X161590Y595606D01*
X161881Y595231D01*
X162298Y594981D01*
X162673Y594898D01*
Y596648D01*
G01X153938Y565230D02*
X153688Y565355D01*
X153396Y565438D01*
X153063D01*
X152688Y565313D01*
X152396Y565105D01*
X152188Y564855D01*
X152021Y564438D01*
X151979Y564063D01*
X152063Y563688D01*
X152188Y563438D01*
X152438Y563188D01*
X152729Y563021D01*
X153021Y562938D01*
X153313D01*
X153604Y563021D01*
X153854Y563146D01*
X154063Y563313D01*
G01X155329Y563980D02*
X155621Y564271D01*
X155871Y564438D01*
X156204Y564521D01*
X156496Y564438D01*
X156704Y564271D01*
X156871Y564021D01*
X156913Y563730D01*
X156871Y563480D01*
X156704Y563230D01*
X156454Y563021D01*
X156163Y562938D01*
X155829Y563021D01*
X155538Y563271D01*
X155371Y563646D01*
X155329Y564063D01*
X155413Y564605D01*
X155538Y564896D01*
X155746Y565188D01*
X156038Y565396D01*
X156329Y565438D01*
X156621Y565355D01*
X156829Y565146D01*
G01X159221Y562938D02*
Y565438D01*
X158721Y564938D01*
G01Y562938D02*
X159721D01*
G01X161404Y563313D02*
X161654Y563105D01*
X161946Y562980D01*
X162321Y562938D01*
X162696Y563021D01*
X162988Y563188D01*
X163196Y563480D01*
X163238Y563813D01*
X163154Y564146D01*
X162946Y564355D01*
X162654Y564521D01*
X162363Y564563D01*
X162071Y564521D01*
X161696Y564355D01*
X161821Y565438D01*
X162946D01*
G01X164862Y603067D02*
Y605567D01*
X165903D01*
X166237Y605442D01*
X166445Y605275D01*
X166528Y604942D01*
X166445Y604609D01*
X166195Y604400D01*
X165903Y604275D01*
X164862D01*
G01X165903D02*
X166528Y603067D01*
G01X168795D02*
Y605567D01*
X168295Y605067D01*
G01Y603067D02*
X169295D01*
G01X171103Y605150D02*
X171353Y605400D01*
X171645Y605525D01*
X171978Y605567D01*
X172395Y605484D01*
X172687Y605275D01*
X172770Y605025D01*
X172728Y604775D01*
X172562Y604567D01*
X171728Y604150D01*
X171353Y603859D01*
X171103Y603442D01*
X171020Y603067D01*
X172770D01*
G01X174078Y603567D02*
X174328Y603275D01*
X174662Y603109D01*
X175037Y603067D01*
X175370Y603109D01*
X175703Y603317D01*
X175912Y603567D01*
X175953Y603817D01*
X175870Y604109D01*
X175578Y604317D01*
X175287Y604400D01*
X174912D01*
G01X175287D02*
X175537Y604525D01*
X175745Y604734D01*
X175828Y604984D01*
X175745Y605234D01*
X175537Y605442D01*
X175162Y605567D01*
X174787Y605525D01*
X174412Y605359D01*
G01X178595Y603067D02*
Y605567D01*
X177053Y603775D01*
X179137D01*
G01X130076Y617940D02*
X129826Y618065D01*
X129534Y618148D01*
X129201D01*
X128826Y618023D01*
X128534Y617815D01*
X128326Y617565D01*
X128159Y617148D01*
X128117Y616773D01*
X128201Y616398D01*
X128326Y616148D01*
X128576Y615898D01*
X128867Y615731D01*
X129159Y615648D01*
X129451D01*
X129742Y615731D01*
X129992Y615856D01*
X130201Y616023D01*
G01X132259Y615648D02*
Y618148D01*
X131759Y617648D01*
G01Y615648D02*
X132759D01*
G01X134651Y615940D02*
X134942Y615731D01*
X135276Y615648D01*
X135609Y615731D01*
X135901Y615981D01*
X136109Y616356D01*
X136192Y616731D01*
Y617190D01*
X136109Y617565D01*
X135901Y617898D01*
X135651Y618065D01*
X135359Y618148D01*
X135026Y618065D01*
X134776Y617898D01*
X134609Y617648D01*
X134526Y617315D01*
X134609Y617023D01*
X134817Y616731D01*
X135067Y616565D01*
X135359Y616523D01*
X135692Y616606D01*
X135942Y616815D01*
X136192Y617190D01*
G01X137542Y616023D02*
X137792Y615815D01*
X138084Y615690D01*
X138459Y615648D01*
X138834Y615731D01*
X139126Y615898D01*
X139334Y616190D01*
X139376Y616523D01*
X139292Y616856D01*
X139084Y617065D01*
X138792Y617231D01*
X138501Y617273D01*
X138209Y617231D01*
X137834Y617065D01*
X137959Y618148D01*
X139084D01*
G01X130267Y621792D02*
X130017Y621917D01*
X129725Y622000D01*
X129392D01*
X129017Y621875D01*
X128725Y621667D01*
X128517Y621417D01*
X128350Y621000D01*
X128308Y620625D01*
X128392Y620250D01*
X128517Y620000D01*
X128767Y619750D01*
X129058Y619583D01*
X129350Y619500D01*
X129642D01*
X129933Y619583D01*
X130183Y619708D01*
X130392Y619875D01*
G01X132450Y619500D02*
Y622000D01*
X131950Y621500D01*
G01Y619500D02*
X132950D01*
G01X134842Y619792D02*
X135133Y619583D01*
X135467Y619500D01*
X135800Y619583D01*
X136092Y619833D01*
X136300Y620208D01*
X136383Y620583D01*
Y621042D01*
X136300Y621417D01*
X136092Y621750D01*
X135842Y621917D01*
X135550Y622000D01*
X135217Y621917D01*
X134967Y621750D01*
X134800Y621500D01*
X134717Y621167D01*
X134800Y620875D01*
X135008Y620583D01*
X135258Y620417D01*
X135550Y620375D01*
X135883Y620458D01*
X136133Y620667D01*
X136383Y621042D01*
G01X139150Y619500D02*
Y622000D01*
X137608Y620208D01*
X139692D01*
G01X134954Y686017D02*
Y688517D01*
X135995D01*
X136329Y688392D01*
X136537Y688225D01*
X136620Y687892D01*
X136537Y687559D01*
X136287Y687350D01*
X135995Y687225D01*
X134954D01*
G01X135995D02*
X136620Y686017D01*
G01X139387D02*
Y688517D01*
X137845Y686725D01*
X139929D01*
G01X141987Y688517D02*
X141654Y688434D01*
X141404Y688225D01*
X141237Y687975D01*
X141112Y687642D01*
X141070Y687267D01*
X141112Y686892D01*
X141237Y686559D01*
X141404Y686309D01*
X141654Y686100D01*
X141987Y686017D01*
X142320Y686100D01*
X142570Y686309D01*
X142737Y686559D01*
X142862Y686892D01*
X142904Y687267D01*
X142862Y687642D01*
X142737Y687975D01*
X142570Y688225D01*
X142320Y688434D01*
X141987Y688517D01*
G01X144295Y687059D02*
X144587Y687350D01*
X144837Y687517D01*
X145170Y687600D01*
X145462Y687517D01*
X145670Y687350D01*
X145837Y687100D01*
X145879Y686809D01*
X145837Y686559D01*
X145670Y686309D01*
X145420Y686100D01*
X145129Y686017D01*
X144795Y686100D01*
X144504Y686350D01*
X144337Y686725D01*
X144295Y687142D01*
X144379Y687684D01*
X144504Y687975D01*
X144712Y688267D01*
X145004Y688475D01*
X145295Y688517D01*
X145587Y688434D01*
X145795Y688225D01*
G01X144637Y695517D02*
Y699517D01*
X137237D01*
G01X170000Y675900D02*
X169958Y675567D01*
X169792Y675275D01*
X169542Y675025D01*
X169250Y674858D01*
X168917Y674775D01*
X168583D01*
X168250Y674858D01*
X167958Y675025D01*
X167708Y675275D01*
X167542Y675567D01*
X167500Y675900D01*
X167542Y676233D01*
X167708Y676525D01*
X167958Y676775D01*
X168250Y676942D01*
X168583Y677025D01*
X168917D01*
X169250Y676942D01*
X169542Y676775D01*
X169792Y676525D01*
X169958Y676233D01*
X170000Y675900D01*
G01X169333Y676233D02*
X170000Y676733D01*
G01Y679000D02*
X169958Y679292D01*
X169833Y679625D01*
X169625Y679833D01*
X169333Y679917D01*
X169042Y679833D01*
X168792Y679583D01*
X168667Y679208D01*
Y678792D01*
X168583Y678542D01*
X168375Y678333D01*
X168083Y678250D01*
X167792Y678375D01*
X167583Y678667D01*
X167500Y679000D01*
X167583Y679333D01*
X167792Y679625D01*
X168083Y679750D01*
X168375Y679667D01*
X168583Y679458D01*
X168667Y679208D01*
Y678792D01*
X168792Y678417D01*
X169042Y678167D01*
X169333Y678083D01*
X169625Y678167D01*
X169833Y678375D01*
X169958Y678708D01*
X170000Y679000D01*
G01X167500Y682100D02*
X167583Y681767D01*
X167792Y681517D01*
X168042Y681350D01*
X168375Y681225D01*
X168750Y681183D01*
X169125Y681225D01*
X169458Y681350D01*
X169708Y681517D01*
X169917Y681767D01*
X170000Y682100D01*
X169917Y682433D01*
X169708Y682683D01*
X169458Y682850D01*
X169125Y682975D01*
X168750Y683017D01*
X168375Y682975D01*
X168042Y682850D01*
X167792Y682683D01*
X167583Y682433D01*
X167500Y682100D01*
G01X136704Y684209D02*
X136454Y684334D01*
X136162Y684417D01*
X135829D01*
X135454Y684292D01*
X135162Y684084D01*
X134954Y683834D01*
X134787Y683417D01*
X134745Y683042D01*
X134829Y682667D01*
X134954Y682417D01*
X135204Y682167D01*
X135495Y682000D01*
X135787Y681917D01*
X136079D01*
X136370Y682000D01*
X136620Y682125D01*
X136829Y682292D01*
G01X138887Y681917D02*
Y684417D01*
X138387Y683917D01*
G01Y681917D02*
X139387D01*
G01X141279Y682209D02*
X141570Y682000D01*
X141904Y681917D01*
X142237Y682000D01*
X142529Y682250D01*
X142737Y682625D01*
X142820Y683000D01*
Y683459D01*
X142737Y683834D01*
X142529Y684167D01*
X142279Y684334D01*
X141987Y684417D01*
X141654Y684334D01*
X141404Y684167D01*
X141237Y683917D01*
X141154Y683584D01*
X141237Y683292D01*
X141445Y683000D01*
X141695Y682834D01*
X141987Y682792D01*
X142320Y682875D01*
X142570Y683084D01*
X142820Y683459D01*
G01X145087Y681917D02*
X145379Y681959D01*
X145712Y682084D01*
X145920Y682292D01*
X146004Y682584D01*
X145920Y682875D01*
X145670Y683125D01*
X145295Y683250D01*
X144879D01*
X144629Y683334D01*
X144420Y683542D01*
X144337Y683834D01*
X144462Y684125D01*
X144754Y684334D01*
X145087Y684417D01*
X145420Y684334D01*
X145712Y684125D01*
X145837Y683834D01*
X145754Y683542D01*
X145545Y683334D01*
X145295Y683250D01*
X144879D01*
X144504Y683125D01*
X144254Y682875D01*
X144170Y682584D01*
X144254Y682292D01*
X144462Y682084D01*
X144795Y681959D01*
X145087Y681917D01*
G01X136246Y740409D02*
X133746D01*
Y741450D01*
X133871Y741784D01*
X134038Y741992D01*
X134371Y742075D01*
X134704Y741992D01*
X134913Y741742D01*
X135038Y741450D01*
Y740409D01*
G01Y741450D02*
X136246Y742075D01*
G01Y744842D02*
X133746D01*
X135538Y743300D01*
Y745384D01*
G01X135871Y746525D02*
X136079Y746775D01*
X136204Y747067D01*
X136246Y747442D01*
X136163Y747817D01*
X135996Y748109D01*
X135704Y748317D01*
X135371Y748359D01*
X135038Y748275D01*
X134829Y748067D01*
X134663Y747775D01*
X134621Y747484D01*
X134663Y747192D01*
X134829Y746817D01*
X133746Y746942D01*
Y748067D01*
G01X136246Y750459D02*
X135704Y750542D01*
X135246Y750667D01*
X134829Y750834D01*
X134371Y751042D01*
X133746Y751375D01*
Y749709D01*
G01X142372Y741924D02*
X138372D01*
Y734524D01*
G01X132117Y716100D02*
Y718600D01*
X133158D01*
X133492Y718475D01*
X133700Y718308D01*
X133783Y717975D01*
X133700Y717642D01*
X133450Y717433D01*
X133158Y717308D01*
X132117D01*
G01X133158D02*
X133783Y716100D01*
G01X136050D02*
Y718600D01*
X135550Y718100D01*
G01Y716100D02*
X136550D01*
G01X139650D02*
Y718600D01*
X138108Y716808D01*
X140192D01*
G01X142167Y716100D02*
X142250Y716642D01*
X142375Y717100D01*
X142542Y717517D01*
X142750Y717975D01*
X143083Y718600D01*
X141417D01*
G01X148303Y716355D02*
Y712355D01*
X155703D01*
G01X160326Y723691D02*
X160284Y723358D01*
X160118Y723066D01*
X159868Y722816D01*
X159576Y722649D01*
X159243Y722566D01*
X158909D01*
X158576Y722649D01*
X158284Y722816D01*
X158034Y723066D01*
X157868Y723358D01*
X157826Y723691D01*
X157868Y724024D01*
X158034Y724316D01*
X158284Y724566D01*
X158576Y724733D01*
X158909Y724816D01*
X159243D01*
X159576Y724733D01*
X159868Y724566D01*
X160118Y724316D01*
X160284Y724024D01*
X160326Y723691D01*
G01X159659Y724024D02*
X160326Y724524D01*
G01X158243Y725999D02*
X157993Y726249D01*
X157868Y726541D01*
X157826Y726874D01*
X157909Y727291D01*
X158118Y727583D01*
X158368Y727666D01*
X158618Y727624D01*
X158826Y727458D01*
X159243Y726624D01*
X159534Y726249D01*
X159951Y725999D01*
X160326Y725916D01*
Y727666D01*
G01X159284Y729099D02*
X158993Y729391D01*
X158826Y729641D01*
X158743Y729974D01*
X158826Y730266D01*
X158993Y730474D01*
X159243Y730641D01*
X159534Y730683D01*
X159784Y730641D01*
X160034Y730474D01*
X160243Y730224D01*
X160326Y729933D01*
X160243Y729599D01*
X159993Y729308D01*
X159618Y729141D01*
X159201Y729099D01*
X158659Y729183D01*
X158368Y729308D01*
X158076Y729516D01*
X157868Y729808D01*
X157826Y730099D01*
X157909Y730391D01*
X158118Y730599D01*
G01X160326Y733491D02*
X157826D01*
X159618Y731949D01*
Y734033D01*
G01X143326Y735841D02*
Y721841D01*
G01X156326Y735841D02*
X143326D01*
G01X156326Y721841D02*
Y735841D01*
G01X143326Y721841D02*
X156326D01*
G01X160330Y738611D02*
X160288Y738278D01*
X160122Y737986D01*
X159872Y737736D01*
X159580Y737569D01*
X159247Y737486D01*
X158913D01*
X158580Y737569D01*
X158288Y737736D01*
X158038Y737986D01*
X157872Y738278D01*
X157830Y738611D01*
X157872Y738944D01*
X158038Y739236D01*
X158288Y739486D01*
X158580Y739653D01*
X158913Y739736D01*
X159247D01*
X159580Y739653D01*
X159872Y739486D01*
X160122Y739236D01*
X160288Y738944D01*
X160330Y738611D01*
G01X159663Y738944D02*
X160330Y739444D01*
G01X158247Y740919D02*
X157997Y741169D01*
X157872Y741461D01*
X157830Y741794D01*
X157913Y742211D01*
X158122Y742503D01*
X158372Y742586D01*
X158622Y742544D01*
X158830Y742378D01*
X159247Y741544D01*
X159538Y741169D01*
X159955Y740919D01*
X160330Y740836D01*
Y742586D01*
G01X158247Y744019D02*
X157997Y744269D01*
X157872Y744561D01*
X157830Y744894D01*
X157913Y745311D01*
X158122Y745603D01*
X158372Y745686D01*
X158622Y745644D01*
X158830Y745478D01*
X159247Y744644D01*
X159538Y744269D01*
X159955Y744019D01*
X160330Y743936D01*
Y745686D01*
G01Y748411D02*
X157830D01*
X159622Y746869D01*
Y748953D01*
G01X143330Y750761D02*
Y736761D01*
G01X156330D02*
Y750761D01*
G01X143330Y736761D02*
X156330D01*
G01X133437Y723267D02*
X135937D01*
G01X133437Y722309D02*
Y724225D01*
G01X135937Y725534D02*
X133437D01*
Y726534D01*
X133562Y726867D01*
X133854Y727117D01*
X134187Y727200D01*
X134520Y727117D01*
X134770Y726909D01*
X134895Y726534D01*
Y725534D01*
G01Y728675D02*
X134604Y728967D01*
X134437Y729217D01*
X134354Y729550D01*
X134437Y729842D01*
X134604Y730050D01*
X134854Y730217D01*
X135145Y730259D01*
X135395Y730217D01*
X135645Y730050D01*
X135854Y729800D01*
X135937Y729509D01*
X135854Y729175D01*
X135604Y728884D01*
X135229Y728717D01*
X134812Y728675D01*
X134270Y728759D01*
X133979Y728884D01*
X133687Y729092D01*
X133479Y729384D01*
X133437Y729675D01*
X133520Y729967D01*
X133729Y730175D01*
G01X133854Y731775D02*
X133604Y732025D01*
X133479Y732317D01*
X133437Y732650D01*
X133520Y733067D01*
X133729Y733359D01*
X133979Y733442D01*
X134229Y733400D01*
X134437Y733234D01*
X134854Y732400D01*
X135145Y732025D01*
X135562Y731775D01*
X135937Y731692D01*
Y733442D01*
G01X129017Y712000D02*
Y714500D01*
X130058D01*
X130392Y714375D01*
X130600Y714208D01*
X130683Y713875D01*
X130600Y713542D01*
X130350Y713333D01*
X130058Y713208D01*
X129017D01*
G01X130058D02*
X130683Y712000D01*
G01X133450D02*
Y714500D01*
X131908Y712708D01*
X133992D01*
G01X136050Y712000D02*
Y714500D01*
X135550Y714000D01*
G01Y712000D02*
X136550D01*
G01X139150Y714500D02*
X138817Y714417D01*
X138567Y714208D01*
X138400Y713958D01*
X138275Y713625D01*
X138233Y713250D01*
X138275Y712875D01*
X138400Y712542D01*
X138567Y712292D01*
X138817Y712083D01*
X139150Y712000D01*
X139483Y712083D01*
X139733Y712292D01*
X139900Y712542D01*
X140025Y712875D01*
X140067Y713250D01*
X140025Y713625D01*
X139900Y713958D01*
X139733Y714208D01*
X139483Y714417D01*
X139150Y714500D01*
G01X156330Y750761D02*
X143330D01*
G01X128494Y962575D02*
X123294D01*
G01X128494D02*
Y969575D01*
G01X132500Y949967D02*
X130000D01*
Y951008D01*
X130125Y951342D01*
X130292Y951550D01*
X130625Y951633D01*
X130958Y951550D01*
X131167Y951300D01*
X131292Y951008D01*
Y949967D01*
G01Y951008D02*
X132500Y951633D01*
G01Y953900D02*
X130000D01*
X130500Y953400D01*
G01X132500D02*
Y954400D01*
G01X130417Y956208D02*
X130167Y956458D01*
X130042Y956750D01*
X130000Y957083D01*
X130083Y957500D01*
X130292Y957792D01*
X130542Y957875D01*
X130792Y957833D01*
X131000Y957667D01*
X131417Y956833D01*
X131708Y956458D01*
X132125Y956208D01*
X132500Y956125D01*
Y957875D01*
G01X130000Y960100D02*
X130083Y959767D01*
X130292Y959517D01*
X130542Y959350D01*
X130875Y959225D01*
X131250Y959183D01*
X131625Y959225D01*
X131958Y959350D01*
X132208Y959517D01*
X132417Y959767D01*
X132500Y960100D01*
X132417Y960433D01*
X132208Y960683D01*
X131958Y960850D01*
X131625Y960975D01*
X131250Y961017D01*
X130875Y960975D01*
X130542Y960850D01*
X130292Y960683D01*
X130083Y960433D01*
X130000Y960100D01*
G01X132208Y962492D02*
X132417Y962783D01*
X132500Y963117D01*
X132417Y963450D01*
X132167Y963742D01*
X131792Y963950D01*
X131417Y964033D01*
X130958D01*
X130583Y963950D01*
X130250Y963742D01*
X130083Y963492D01*
X130000Y963200D01*
X130083Y962867D01*
X130250Y962617D01*
X130500Y962450D01*
X130833Y962367D01*
X131125Y962450D01*
X131417Y962658D01*
X131583Y962908D01*
X131625Y963200D01*
X131542Y963533D01*
X131333Y963783D01*
X130958Y964033D01*
G01X147495Y968027D02*
X147245Y968152D01*
X146953Y968235D01*
X146620D01*
X146245Y968110D01*
X145953Y967902D01*
X145745Y967652D01*
X145578Y967235D01*
X145536Y966860D01*
X145620Y966485D01*
X145745Y966235D01*
X145995Y965985D01*
X146286Y965818D01*
X146578Y965735D01*
X146870D01*
X147161Y965818D01*
X147411Y965943D01*
X147620Y966110D01*
G01X148886Y966777D02*
X149178Y967068D01*
X149428Y967235D01*
X149761Y967318D01*
X150053Y967235D01*
X150261Y967068D01*
X150428Y966818D01*
X150470Y966527D01*
X150428Y966277D01*
X150261Y966027D01*
X150011Y965818D01*
X149720Y965735D01*
X149386Y965818D01*
X149095Y966068D01*
X148928Y966443D01*
X148886Y966860D01*
X148970Y967402D01*
X149095Y967693D01*
X149303Y967985D01*
X149595Y968193D01*
X149886Y968235D01*
X150178Y968152D01*
X150386Y967943D01*
G01X152778Y968235D02*
X152445Y968152D01*
X152195Y967943D01*
X152028Y967693D01*
X151903Y967360D01*
X151861Y966985D01*
X151903Y966610D01*
X152028Y966277D01*
X152195Y966027D01*
X152445Y965818D01*
X152778Y965735D01*
X153111Y965818D01*
X153361Y966027D01*
X153528Y966277D01*
X153653Y966610D01*
X153695Y966985D01*
X153653Y967360D01*
X153528Y967693D01*
X153361Y967943D01*
X153111Y968152D01*
X152778Y968235D01*
G01X155795Y965735D02*
X155878Y966277D01*
X156003Y966735D01*
X156170Y967152D01*
X156378Y967610D01*
X156711Y968235D01*
X155045D01*
G01X147523Y973054D02*
X147273Y973179D01*
X146981Y973262D01*
X146648D01*
X146273Y973137D01*
X145981Y972929D01*
X145773Y972679D01*
X145606Y972262D01*
X145564Y971887D01*
X145648Y971512D01*
X145773Y971262D01*
X146023Y971012D01*
X146314Y970845D01*
X146606Y970762D01*
X146898D01*
X147189Y970845D01*
X147439Y970970D01*
X147648Y971137D01*
G01X148914Y971804D02*
X149206Y972095D01*
X149456Y972262D01*
X149789Y972345D01*
X150081Y972262D01*
X150289Y972095D01*
X150456Y971845D01*
X150498Y971554D01*
X150456Y971304D01*
X150289Y971054D01*
X150039Y970845D01*
X149748Y970762D01*
X149414Y970845D01*
X149123Y971095D01*
X148956Y971470D01*
X148914Y971887D01*
X148998Y972429D01*
X149123Y972720D01*
X149331Y973012D01*
X149623Y973220D01*
X149914Y973262D01*
X150206Y973179D01*
X150414Y972970D01*
G01X152806Y973262D02*
X152473Y973179D01*
X152223Y972970D01*
X152056Y972720D01*
X151931Y972387D01*
X151889Y972012D01*
X151931Y971637D01*
X152056Y971304D01*
X152223Y971054D01*
X152473Y970845D01*
X152806Y970762D01*
X153139Y970845D01*
X153389Y971054D01*
X153556Y971304D01*
X153681Y971637D01*
X153723Y972012D01*
X153681Y972387D01*
X153556Y972720D01*
X153389Y972970D01*
X153139Y973179D01*
X152806Y973262D01*
G01X154989Y971137D02*
X155239Y970929D01*
X155531Y970804D01*
X155906Y970762D01*
X156281Y970845D01*
X156573Y971012D01*
X156781Y971304D01*
X156823Y971637D01*
X156739Y971970D01*
X156531Y972179D01*
X156239Y972345D01*
X155948Y972387D01*
X155656Y972345D01*
X155281Y972179D01*
X155406Y973262D01*
X156531D01*
G01X134500Y1014467D02*
X132000D01*
Y1015508D01*
X132125Y1015842D01*
X132292Y1016050D01*
X132625Y1016133D01*
X132958Y1016050D01*
X133167Y1015800D01*
X133292Y1015508D01*
Y1014467D01*
G01Y1015508D02*
X134500Y1016133D01*
G01Y1018400D02*
X132000D01*
X132500Y1017900D01*
G01X134500D02*
Y1018900D01*
G01X132417Y1020708D02*
X132167Y1020958D01*
X132042Y1021250D01*
X132000Y1021583D01*
X132083Y1022000D01*
X132292Y1022292D01*
X132542Y1022375D01*
X132792Y1022333D01*
X133000Y1022167D01*
X133417Y1021333D01*
X133708Y1020958D01*
X134125Y1020708D01*
X134500Y1020625D01*
Y1022375D01*
G01X132000Y1024600D02*
X132083Y1024267D01*
X132292Y1024017D01*
X132542Y1023850D01*
X132875Y1023725D01*
X133250Y1023683D01*
X133625Y1023725D01*
X133958Y1023850D01*
X134208Y1024017D01*
X134417Y1024267D01*
X134500Y1024600D01*
X134417Y1024933D01*
X134208Y1025183D01*
X133958Y1025350D01*
X133625Y1025475D01*
X133250Y1025517D01*
X132875Y1025475D01*
X132542Y1025350D01*
X132292Y1025183D01*
X132083Y1024933D01*
X132000Y1024600D01*
G01X134125Y1026783D02*
X134333Y1027033D01*
X134458Y1027325D01*
X134500Y1027700D01*
X134417Y1028075D01*
X134250Y1028367D01*
X133958Y1028575D01*
X133625Y1028617D01*
X133292Y1028533D01*
X133083Y1028325D01*
X132917Y1028033D01*
X132875Y1027742D01*
X132917Y1027450D01*
X133083Y1027075D01*
X132000Y1027200D01*
Y1028325D01*
G01X135063Y1011425D02*
X131063D01*
Y1004025D01*
G01X136845Y1009651D02*
Y1012151D01*
X137886D01*
X138220Y1012026D01*
X138428Y1011859D01*
X138511Y1011526D01*
X138428Y1011193D01*
X138178Y1010984D01*
X137886Y1010859D01*
X136845D01*
G01X137886D02*
X138511Y1009651D01*
G01X140778D02*
Y1012151D01*
X140278Y1011651D01*
G01Y1009651D02*
X141278D01*
G01X143086Y1011734D02*
X143336Y1011984D01*
X143628Y1012109D01*
X143961Y1012151D01*
X144378Y1012068D01*
X144670Y1011859D01*
X144753Y1011609D01*
X144711Y1011359D01*
X144545Y1011151D01*
X143711Y1010734D01*
X143336Y1010443D01*
X143086Y1010026D01*
X143003Y1009651D01*
X144753D01*
G01X146978Y1012151D02*
X146645Y1012068D01*
X146395Y1011859D01*
X146228Y1011609D01*
X146103Y1011276D01*
X146061Y1010901D01*
X146103Y1010526D01*
X146228Y1010193D01*
X146395Y1009943D01*
X146645Y1009734D01*
X146978Y1009651D01*
X147311Y1009734D01*
X147561Y1009943D01*
X147728Y1010193D01*
X147853Y1010526D01*
X147895Y1010901D01*
X147853Y1011276D01*
X147728Y1011609D01*
X147561Y1011859D01*
X147311Y1012068D01*
X146978Y1012151D01*
G01X149995Y1009651D02*
X150078Y1010193D01*
X150203Y1010651D01*
X150370Y1011068D01*
X150578Y1011526D01*
X150911Y1012151D01*
X149245D01*
G01X142563Y1003625D02*
Y1007625D01*
X135163D01*
G01X130763Y999725D02*
Y1003725D01*
X123363D01*
G01X139479Y990492D02*
Y992992D01*
X140520D01*
X140854Y992867D01*
X141062Y992700D01*
X141145Y992367D01*
X141062Y992034D01*
X140812Y991825D01*
X140520Y991700D01*
X139479D01*
G01X140520D02*
X141145Y990492D01*
G01X143412D02*
Y992992D01*
X142912Y992492D01*
G01Y990492D02*
X143912D01*
G01X145720Y992575D02*
X145970Y992825D01*
X146262Y992950D01*
X146595Y992992D01*
X147012Y992909D01*
X147304Y992700D01*
X147387Y992450D01*
X147345Y992200D01*
X147179Y991992D01*
X146345Y991575D01*
X145970Y991284D01*
X145720Y990867D01*
X145637Y990492D01*
X147387D01*
G01X149612D02*
Y992992D01*
X149112Y992492D01*
G01Y990492D02*
X150112D01*
G01X152712Y992992D02*
X152379Y992909D01*
X152129Y992700D01*
X151962Y992450D01*
X151837Y992117D01*
X151795Y991742D01*
X151837Y991367D01*
X151962Y991034D01*
X152129Y990784D01*
X152379Y990575D01*
X152712Y990492D01*
X153045Y990575D01*
X153295Y990784D01*
X153462Y991034D01*
X153587Y991367D01*
X153629Y991742D01*
X153587Y992117D01*
X153462Y992450D01*
X153295Y992700D01*
X153045Y992909D01*
X152712Y992992D01*
G01X142522Y995250D02*
Y999250D01*
X135122D01*
G01X129855Y990723D02*
Y994723D01*
X122455D01*
G01X151143Y1006621D02*
Y1004121D01*
G01X150185Y1006621D02*
X152101D01*
G01X153410Y1004121D02*
Y1006621D01*
X154410D01*
X154743Y1006496D01*
X154993Y1006204D01*
X155076Y1005871D01*
X154993Y1005538D01*
X154785Y1005288D01*
X154410Y1005163D01*
X153410D01*
G01X156551Y1006204D02*
X156801Y1006454D01*
X157093Y1006579D01*
X157426Y1006621D01*
X157843Y1006538D01*
X158135Y1006329D01*
X158218Y1006079D01*
X158176Y1005829D01*
X158010Y1005621D01*
X157176Y1005204D01*
X156801Y1004913D01*
X156551Y1004496D01*
X156468Y1004121D01*
X158218D01*
G01X159526Y1004496D02*
X159776Y1004288D01*
X160068Y1004163D01*
X160443Y1004121D01*
X160818Y1004204D01*
X161110Y1004371D01*
X161318Y1004663D01*
X161360Y1004996D01*
X161276Y1005329D01*
X161068Y1005538D01*
X160776Y1005704D01*
X160485Y1005746D01*
X160193Y1005704D01*
X159818Y1005538D01*
X159943Y1006621D01*
X161068D01*
G01X162751Y1005163D02*
X163043Y1005454D01*
X163293Y1005621D01*
X163626Y1005704D01*
X163918Y1005621D01*
X164126Y1005454D01*
X164293Y1005204D01*
X164335Y1004913D01*
X164293Y1004663D01*
X164126Y1004413D01*
X163876Y1004204D01*
X163585Y1004121D01*
X163251Y1004204D01*
X162960Y1004454D01*
X162793Y1004829D01*
X162751Y1005246D01*
X162835Y1005788D01*
X162960Y1006079D01*
X163168Y1006371D01*
X163460Y1006579D01*
X163751Y1006621D01*
X164043Y1006538D01*
X164251Y1006329D01*
G01X132470Y1070437D02*
X132220Y1070562D01*
X131928Y1070645D01*
X131595D01*
X131220Y1070520D01*
X130928Y1070312D01*
X130720Y1070062D01*
X130553Y1069645D01*
X130511Y1069270D01*
X130595Y1068895D01*
X130720Y1068645D01*
X130970Y1068395D01*
X131261Y1068228D01*
X131553Y1068145D01*
X131845D01*
X132136Y1068228D01*
X132386Y1068353D01*
X132595Y1068520D01*
G01X133736D02*
X133986Y1068312D01*
X134278Y1068187D01*
X134653Y1068145D01*
X135028Y1068228D01*
X135320Y1068395D01*
X135528Y1068687D01*
X135570Y1069020D01*
X135486Y1069353D01*
X135278Y1069562D01*
X134986Y1069728D01*
X134695Y1069770D01*
X134403Y1069728D01*
X134028Y1069562D01*
X134153Y1070645D01*
X135278D01*
G01X137753D02*
X137420Y1070562D01*
X137170Y1070353D01*
X137003Y1070103D01*
X136878Y1069770D01*
X136836Y1069395D01*
X136878Y1069020D01*
X137003Y1068687D01*
X137170Y1068437D01*
X137420Y1068228D01*
X137753Y1068145D01*
X138086Y1068228D01*
X138336Y1068437D01*
X138503Y1068687D01*
X138628Y1069020D01*
X138670Y1069395D01*
X138628Y1069770D01*
X138503Y1070103D01*
X138336Y1070353D01*
X138086Y1070562D01*
X137753Y1070645D01*
G01X140770Y1068145D02*
X140853Y1068687D01*
X140978Y1069145D01*
X141145Y1069562D01*
X141353Y1070020D01*
X141686Y1070645D01*
X140020D01*
G01X132161Y1074033D02*
X131911Y1074158D01*
X131619Y1074241D01*
X131286D01*
X130911Y1074116D01*
X130619Y1073908D01*
X130411Y1073658D01*
X130244Y1073241D01*
X130202Y1072866D01*
X130286Y1072491D01*
X130411Y1072241D01*
X130661Y1071991D01*
X130952Y1071824D01*
X131244Y1071741D01*
X131536D01*
X131827Y1071824D01*
X132077Y1071949D01*
X132286Y1072116D01*
G01X133427D02*
X133677Y1071908D01*
X133969Y1071783D01*
X134344Y1071741D01*
X134719Y1071824D01*
X135011Y1071991D01*
X135219Y1072283D01*
X135261Y1072616D01*
X135177Y1072949D01*
X134969Y1073158D01*
X134677Y1073324D01*
X134386Y1073366D01*
X134094Y1073324D01*
X133719Y1073158D01*
X133844Y1074241D01*
X134969D01*
G01X137444D02*
X137111Y1074158D01*
X136861Y1073949D01*
X136694Y1073699D01*
X136569Y1073366D01*
X136527Y1072991D01*
X136569Y1072616D01*
X136694Y1072283D01*
X136861Y1072033D01*
X137111Y1071824D01*
X137444Y1071741D01*
X137777Y1071824D01*
X138027Y1072033D01*
X138194Y1072283D01*
X138319Y1072616D01*
X138361Y1072991D01*
X138319Y1073366D01*
X138194Y1073699D01*
X138027Y1073949D01*
X137777Y1074158D01*
X137444Y1074241D01*
G01X139752Y1072783D02*
X140044Y1073074D01*
X140294Y1073241D01*
X140627Y1073324D01*
X140919Y1073241D01*
X141127Y1073074D01*
X141294Y1072824D01*
X141336Y1072533D01*
X141294Y1072283D01*
X141127Y1072033D01*
X140877Y1071824D01*
X140586Y1071741D01*
X140252Y1071824D01*
X139961Y1072074D01*
X139794Y1072449D01*
X139752Y1072866D01*
X139836Y1073408D01*
X139961Y1073699D01*
X140169Y1073991D01*
X140461Y1074199D01*
X140752Y1074241D01*
X141044Y1074158D01*
X141252Y1073949D01*
G01X164666Y1099873D02*
Y1102373D01*
X165707D01*
X166041Y1102248D01*
X166249Y1102081D01*
X166332Y1101748D01*
X166249Y1101415D01*
X165999Y1101206D01*
X165707Y1101081D01*
X164666D01*
G01X165707D02*
X166332Y1099873D01*
G01X168599D02*
Y1102373D01*
X168099Y1101873D01*
G01Y1099873D02*
X169099D01*
G01X170907Y1100915D02*
X171199Y1101206D01*
X171449Y1101373D01*
X171782Y1101456D01*
X172074Y1101373D01*
X172282Y1101206D01*
X172449Y1100956D01*
X172491Y1100665D01*
X172449Y1100415D01*
X172282Y1100165D01*
X172032Y1099956D01*
X171741Y1099873D01*
X171407Y1099956D01*
X171116Y1100206D01*
X170949Y1100581D01*
X170907Y1100998D01*
X170991Y1101540D01*
X171116Y1101831D01*
X171324Y1102123D01*
X171616Y1102331D01*
X171907Y1102373D01*
X172199Y1102290D01*
X172407Y1102081D01*
G01X174799Y1102373D02*
X174466Y1102290D01*
X174216Y1102081D01*
X174049Y1101831D01*
X173924Y1101498D01*
X173882Y1101123D01*
X173924Y1100748D01*
X174049Y1100415D01*
X174216Y1100165D01*
X174466Y1099956D01*
X174799Y1099873D01*
X175132Y1099956D01*
X175382Y1100165D01*
X175549Y1100415D01*
X175674Y1100748D01*
X175716Y1101123D01*
X175674Y1101498D01*
X175549Y1101831D01*
X175382Y1102081D01*
X175132Y1102290D01*
X174799Y1102373D01*
G01X165017Y1089167D02*
Y1091667D01*
X166058D01*
X166392Y1091542D01*
X166600Y1091375D01*
X166683Y1091042D01*
X166600Y1090709D01*
X166350Y1090500D01*
X166058Y1090375D01*
X165017D01*
G01X166058D02*
X166683Y1089167D01*
G01X168950D02*
Y1091667D01*
X168450Y1091167D01*
G01Y1089167D02*
X169450D01*
G01X171258Y1090209D02*
X171550Y1090500D01*
X171800Y1090667D01*
X172133Y1090750D01*
X172425Y1090667D01*
X172633Y1090500D01*
X172800Y1090250D01*
X172842Y1089959D01*
X172800Y1089709D01*
X172633Y1089459D01*
X172383Y1089250D01*
X172092Y1089167D01*
X171758Y1089250D01*
X171467Y1089500D01*
X171300Y1089875D01*
X171258Y1090292D01*
X171342Y1090834D01*
X171467Y1091125D01*
X171675Y1091417D01*
X171967Y1091625D01*
X172258Y1091667D01*
X172550Y1091584D01*
X172758Y1091375D01*
G01X174358Y1090209D02*
X174650Y1090500D01*
X174900Y1090667D01*
X175233Y1090750D01*
X175525Y1090667D01*
X175733Y1090500D01*
X175900Y1090250D01*
X175942Y1089959D01*
X175900Y1089709D01*
X175733Y1089459D01*
X175483Y1089250D01*
X175192Y1089167D01*
X174858Y1089250D01*
X174567Y1089500D01*
X174400Y1089875D01*
X174358Y1090292D01*
X174442Y1090834D01*
X174567Y1091125D01*
X174775Y1091417D01*
X175067Y1091625D01*
X175358Y1091667D01*
X175650Y1091584D01*
X175858Y1091375D01*
G01X159966Y1122073D02*
Y1124573D01*
X161007D01*
X161341Y1124448D01*
X161549Y1124281D01*
X161632Y1123948D01*
X161549Y1123615D01*
X161299Y1123406D01*
X161007Y1123281D01*
X159966D01*
G01X161007D02*
X161632Y1122073D01*
G01X163899D02*
Y1124573D01*
X163399Y1124073D01*
G01Y1122073D02*
X164399D01*
G01X166207Y1123115D02*
X166499Y1123406D01*
X166749Y1123573D01*
X167082Y1123656D01*
X167374Y1123573D01*
X167582Y1123406D01*
X167749Y1123156D01*
X167791Y1122865D01*
X167749Y1122615D01*
X167582Y1122365D01*
X167332Y1122156D01*
X167041Y1122073D01*
X166707Y1122156D01*
X166416Y1122406D01*
X166249Y1122781D01*
X166207Y1123198D01*
X166291Y1123740D01*
X166416Y1124031D01*
X166624Y1124323D01*
X166916Y1124531D01*
X167207Y1124573D01*
X167499Y1124490D01*
X167707Y1124281D01*
G01X170016Y1122073D02*
X170099Y1122615D01*
X170224Y1123073D01*
X170391Y1123490D01*
X170599Y1123948D01*
X170932Y1124573D01*
X169266D01*
G01X165017Y1092667D02*
Y1095167D01*
X166058D01*
X166392Y1095042D01*
X166600Y1094875D01*
X166683Y1094542D01*
X166600Y1094209D01*
X166350Y1094000D01*
X166058Y1093875D01*
X165017D01*
G01X166058D02*
X166683Y1092667D01*
G01X168950D02*
Y1095167D01*
X168450Y1094667D01*
G01Y1092667D02*
X169450D01*
G01X171258Y1093709D02*
X171550Y1094000D01*
X171800Y1094167D01*
X172133Y1094250D01*
X172425Y1094167D01*
X172633Y1094000D01*
X172800Y1093750D01*
X172842Y1093459D01*
X172800Y1093209D01*
X172633Y1092959D01*
X172383Y1092750D01*
X172092Y1092667D01*
X171758Y1092750D01*
X171467Y1093000D01*
X171300Y1093375D01*
X171258Y1093792D01*
X171342Y1094334D01*
X171467Y1094625D01*
X171675Y1094917D01*
X171967Y1095125D01*
X172258Y1095167D01*
X172550Y1095084D01*
X172758Y1094875D01*
G01X174442Y1092959D02*
X174733Y1092750D01*
X175067Y1092667D01*
X175400Y1092750D01*
X175692Y1093000D01*
X175900Y1093375D01*
X175983Y1093750D01*
Y1094209D01*
X175900Y1094584D01*
X175692Y1094917D01*
X175442Y1095084D01*
X175150Y1095167D01*
X174817Y1095084D01*
X174567Y1094917D01*
X174400Y1094667D01*
X174317Y1094334D01*
X174400Y1094042D01*
X174608Y1093750D01*
X174858Y1093584D01*
X175150Y1093542D01*
X175483Y1093625D01*
X175733Y1093834D01*
X175983Y1094209D01*
G01X163266Y1128465D02*
X163016Y1128590D01*
X162724Y1128673D01*
X162391D01*
X162016Y1128548D01*
X161724Y1128340D01*
X161516Y1128090D01*
X161349Y1127673D01*
X161307Y1127298D01*
X161391Y1126923D01*
X161516Y1126673D01*
X161766Y1126423D01*
X162057Y1126256D01*
X162349Y1126173D01*
X162641D01*
X162932Y1126256D01*
X163182Y1126381D01*
X163391Y1126548D01*
G01X164657Y1127215D02*
X164949Y1127506D01*
X165199Y1127673D01*
X165532Y1127756D01*
X165824Y1127673D01*
X166032Y1127506D01*
X166199Y1127256D01*
X166241Y1126965D01*
X166199Y1126715D01*
X166032Y1126465D01*
X165782Y1126256D01*
X165491Y1126173D01*
X165157Y1126256D01*
X164866Y1126506D01*
X164699Y1126881D01*
X164657Y1127298D01*
X164741Y1127840D01*
X164866Y1128131D01*
X165074Y1128423D01*
X165366Y1128631D01*
X165657Y1128673D01*
X165949Y1128590D01*
X166157Y1128381D01*
G01X167757Y1128256D02*
X168007Y1128506D01*
X168299Y1128631D01*
X168632Y1128673D01*
X169049Y1128590D01*
X169341Y1128381D01*
X169424Y1128131D01*
X169382Y1127881D01*
X169216Y1127673D01*
X168382Y1127256D01*
X168007Y1126965D01*
X167757Y1126548D01*
X167674Y1126173D01*
X169424D01*
G01X167966Y1106265D02*
X167716Y1106390D01*
X167424Y1106473D01*
X167091D01*
X166716Y1106348D01*
X166424Y1106140D01*
X166216Y1105890D01*
X166049Y1105473D01*
X166007Y1105098D01*
X166091Y1104723D01*
X166216Y1104473D01*
X166466Y1104223D01*
X166757Y1104056D01*
X167049Y1103973D01*
X167341D01*
X167632Y1104056D01*
X167882Y1104181D01*
X168091Y1104348D01*
G01X169357Y1105015D02*
X169649Y1105306D01*
X169899Y1105473D01*
X170232Y1105556D01*
X170524Y1105473D01*
X170732Y1105306D01*
X170899Y1105056D01*
X170941Y1104765D01*
X170899Y1104515D01*
X170732Y1104265D01*
X170482Y1104056D01*
X170191Y1103973D01*
X169857Y1104056D01*
X169566Y1104306D01*
X169399Y1104681D01*
X169357Y1105098D01*
X169441Y1105640D01*
X169566Y1105931D01*
X169774Y1106223D01*
X170066Y1106431D01*
X170357Y1106473D01*
X170649Y1106390D01*
X170857Y1106181D01*
G01X173249Y1103973D02*
Y1106473D01*
X172749Y1105973D01*
G01Y1103973D02*
X173749D01*
G01X125454Y1149273D02*
Y1151773D01*
X126495D01*
X126829Y1151648D01*
X127037Y1151481D01*
X127120Y1151148D01*
X127037Y1150815D01*
X126787Y1150606D01*
X126495Y1150481D01*
X125454D01*
G01X126495D02*
X127120Y1149273D01*
G01X128679Y1149565D02*
X128970Y1149356D01*
X129304Y1149273D01*
X129637Y1149356D01*
X129929Y1149606D01*
X130137Y1149981D01*
X130220Y1150356D01*
Y1150815D01*
X130137Y1151190D01*
X129929Y1151523D01*
X129679Y1151690D01*
X129387Y1151773D01*
X129054Y1151690D01*
X128804Y1151523D01*
X128637Y1151273D01*
X128554Y1150940D01*
X128637Y1150648D01*
X128845Y1150356D01*
X129095Y1150190D01*
X129387Y1150148D01*
X129720Y1150231D01*
X129970Y1150440D01*
X130220Y1150815D01*
G01X131570Y1149648D02*
X131820Y1149440D01*
X132112Y1149315D01*
X132487Y1149273D01*
X132862Y1149356D01*
X133154Y1149523D01*
X133362Y1149815D01*
X133404Y1150148D01*
X133320Y1150481D01*
X133112Y1150690D01*
X132820Y1150856D01*
X132529Y1150898D01*
X132237Y1150856D01*
X131862Y1150690D01*
X131987Y1151773D01*
X133112D01*
G01X135587Y1149273D02*
X135879Y1149315D01*
X136212Y1149440D01*
X136420Y1149648D01*
X136504Y1149940D01*
X136420Y1150231D01*
X136170Y1150481D01*
X135795Y1150606D01*
X135379D01*
X135129Y1150690D01*
X134920Y1150898D01*
X134837Y1151190D01*
X134962Y1151481D01*
X135254Y1151690D01*
X135587Y1151773D01*
X135920Y1151690D01*
X136212Y1151481D01*
X136337Y1151190D01*
X136254Y1150898D01*
X136045Y1150690D01*
X135795Y1150606D01*
X135379D01*
X135004Y1150481D01*
X134754Y1150231D01*
X134670Y1149940D01*
X134754Y1149648D01*
X134962Y1149440D01*
X135295Y1149315D01*
X135587Y1149273D01*
G01X144637Y1148273D02*
Y1152273D01*
X137237D01*
G01X148517Y1149000D02*
Y1151500D01*
X149558D01*
X149892Y1151375D01*
X150100Y1151208D01*
X150183Y1150875D01*
X150100Y1150542D01*
X149850Y1150333D01*
X149558Y1150208D01*
X148517D01*
G01X149558D02*
X150183Y1149000D01*
G01X151533Y1149375D02*
X151783Y1149167D01*
X152075Y1149042D01*
X152450Y1149000D01*
X152825Y1149083D01*
X153117Y1149250D01*
X153325Y1149542D01*
X153367Y1149875D01*
X153283Y1150208D01*
X153075Y1150417D01*
X152783Y1150583D01*
X152492Y1150625D01*
X152200Y1150583D01*
X151825Y1150417D01*
X151950Y1151500D01*
X153075D01*
G01X154633Y1149375D02*
X154883Y1149167D01*
X155175Y1149042D01*
X155550Y1149000D01*
X155925Y1149083D01*
X156217Y1149250D01*
X156425Y1149542D01*
X156467Y1149875D01*
X156383Y1150208D01*
X156175Y1150417D01*
X155883Y1150583D01*
X155592Y1150625D01*
X155300Y1150583D01*
X154925Y1150417D01*
X155050Y1151500D01*
X156175D01*
G01X159150Y1149000D02*
Y1151500D01*
X157608Y1149708D01*
X159692D01*
G01X148912Y1160233D02*
Y1156233D01*
X156312D01*
G01X160500Y1169350D02*
X160458Y1169017D01*
X160292Y1168725D01*
X160042Y1168475D01*
X159750Y1168308D01*
X159417Y1168225D01*
X159083D01*
X158750Y1168308D01*
X158458Y1168475D01*
X158208Y1168725D01*
X158042Y1169017D01*
X158000Y1169350D01*
X158042Y1169683D01*
X158208Y1169975D01*
X158458Y1170225D01*
X158750Y1170392D01*
X159083Y1170475D01*
X159417D01*
X159750Y1170392D01*
X160042Y1170225D01*
X160292Y1169975D01*
X160458Y1169683D01*
X160500Y1169350D01*
G01X159833Y1169683D02*
X160500Y1170183D01*
G01X158417Y1171658D02*
X158167Y1171908D01*
X158042Y1172200D01*
X158000Y1172533D01*
X158083Y1172950D01*
X158292Y1173242D01*
X158542Y1173325D01*
X158792Y1173283D01*
X159000Y1173117D01*
X159417Y1172283D01*
X159708Y1171908D01*
X160125Y1171658D01*
X160500Y1171575D01*
Y1173325D01*
G01Y1175550D02*
X160458Y1175842D01*
X160333Y1176175D01*
X160125Y1176383D01*
X159833Y1176467D01*
X159542Y1176383D01*
X159292Y1176133D01*
X159167Y1175758D01*
Y1175342D01*
X159083Y1175092D01*
X158875Y1174883D01*
X158583Y1174800D01*
X158292Y1174925D01*
X158083Y1175217D01*
X158000Y1175550D01*
X158083Y1175883D01*
X158292Y1176175D01*
X158583Y1176300D01*
X158875Y1176217D01*
X159083Y1176008D01*
X159167Y1175758D01*
Y1175342D01*
X159292Y1174967D01*
X159542Y1174717D01*
X159833Y1174633D01*
X160125Y1174717D01*
X160333Y1174925D01*
X160458Y1175258D01*
X160500Y1175550D01*
G01Y1178650D02*
X160458Y1178942D01*
X160333Y1179275D01*
X160125Y1179483D01*
X159833Y1179567D01*
X159542Y1179483D01*
X159292Y1179233D01*
X159167Y1178858D01*
Y1178442D01*
X159083Y1178192D01*
X158875Y1177983D01*
X158583Y1177900D01*
X158292Y1178025D01*
X158083Y1178317D01*
X158000Y1178650D01*
X158083Y1178983D01*
X158292Y1179275D01*
X158583Y1179400D01*
X158875Y1179317D01*
X159083Y1179108D01*
X159167Y1178858D01*
Y1178442D01*
X159292Y1178067D01*
X159542Y1177817D01*
X159833Y1177733D01*
X160125Y1177817D01*
X160333Y1178025D01*
X160458Y1178358D01*
X160500Y1178650D01*
G01X143341Y1181092D02*
Y1167092D01*
G01X156341D02*
Y1181092D01*
G01X143341Y1167092D02*
X156341D01*
G01X170000Y1138950D02*
X169958Y1138617D01*
X169792Y1138325D01*
X169542Y1138075D01*
X169250Y1137908D01*
X168917Y1137825D01*
X168583D01*
X168250Y1137908D01*
X167958Y1138075D01*
X167708Y1138325D01*
X167542Y1138617D01*
X167500Y1138950D01*
X167542Y1139283D01*
X167708Y1139575D01*
X167958Y1139825D01*
X168250Y1139992D01*
X168583Y1140075D01*
X168917D01*
X169250Y1139992D01*
X169542Y1139825D01*
X169792Y1139575D01*
X169958Y1139283D01*
X170000Y1138950D01*
G01X169333Y1139283D02*
X170000Y1139783D01*
G01Y1142050D02*
X169958Y1142342D01*
X169833Y1142675D01*
X169625Y1142883D01*
X169333Y1142967D01*
X169042Y1142883D01*
X168792Y1142633D01*
X168667Y1142258D01*
Y1141842D01*
X168583Y1141592D01*
X168375Y1141383D01*
X168083Y1141300D01*
X167792Y1141425D01*
X167583Y1141717D01*
X167500Y1142050D01*
X167583Y1142383D01*
X167792Y1142675D01*
X168083Y1142800D01*
X168375Y1142717D01*
X168583Y1142508D01*
X168667Y1142258D01*
Y1141842D01*
X168792Y1141467D01*
X169042Y1141217D01*
X169333Y1141133D01*
X169625Y1141217D01*
X169833Y1141425D01*
X169958Y1141758D01*
X170000Y1142050D01*
G01X134000Y1171300D02*
X136500D01*
G01X134000Y1170342D02*
Y1172258D01*
G01X136500Y1173567D02*
X134000D01*
Y1174567D01*
X134125Y1174900D01*
X134417Y1175150D01*
X134750Y1175233D01*
X135083Y1175150D01*
X135333Y1174942D01*
X135458Y1174567D01*
Y1173567D01*
G01X136500Y1177500D02*
X134000D01*
X134500Y1177000D01*
G01X136500D02*
Y1178000D01*
G01Y1180600D02*
X136458Y1180892D01*
X136333Y1181225D01*
X136125Y1181433D01*
X135833Y1181517D01*
X135542Y1181433D01*
X135292Y1181183D01*
X135167Y1180808D01*
Y1180392D01*
X135083Y1180142D01*
X134875Y1179933D01*
X134583Y1179850D01*
X134292Y1179975D01*
X134083Y1180267D01*
X134000Y1180600D01*
X134083Y1180933D01*
X134292Y1181225D01*
X134583Y1181350D01*
X134875Y1181267D01*
X135083Y1181058D01*
X135167Y1180808D01*
Y1180392D01*
X135292Y1180017D01*
X135542Y1179767D01*
X135833Y1179683D01*
X136125Y1179767D01*
X136333Y1179975D01*
X136458Y1180308D01*
X136500Y1180600D01*
G01X134417Y1182908D02*
X134167Y1183158D01*
X134042Y1183450D01*
X134000Y1183783D01*
X134083Y1184200D01*
X134292Y1184492D01*
X134542Y1184575D01*
X134792Y1184533D01*
X135000Y1184367D01*
X135417Y1183533D01*
X135708Y1183158D01*
X136125Y1182908D01*
X136500Y1182825D01*
Y1184575D01*
G01X130517Y1165000D02*
Y1167500D01*
X131558D01*
X131892Y1167375D01*
X132100Y1167208D01*
X132183Y1166875D01*
X132100Y1166542D01*
X131850Y1166333D01*
X131558Y1166208D01*
X130517D01*
G01X131558D02*
X132183Y1165000D01*
G01X133742Y1165292D02*
X134033Y1165083D01*
X134367Y1165000D01*
X134700Y1165083D01*
X134992Y1165333D01*
X135200Y1165708D01*
X135283Y1166083D01*
Y1166542D01*
X135200Y1166917D01*
X134992Y1167250D01*
X134742Y1167417D01*
X134450Y1167500D01*
X134117Y1167417D01*
X133867Y1167250D01*
X133700Y1167000D01*
X133617Y1166667D01*
X133700Y1166375D01*
X133908Y1166083D01*
X134158Y1165917D01*
X134450Y1165875D01*
X134783Y1165958D01*
X135033Y1166167D01*
X135283Y1166542D01*
G01X136758Y1166042D02*
X137050Y1166333D01*
X137300Y1166500D01*
X137633Y1166583D01*
X137925Y1166500D01*
X138133Y1166333D01*
X138300Y1166083D01*
X138342Y1165792D01*
X138300Y1165542D01*
X138133Y1165292D01*
X137883Y1165083D01*
X137592Y1165000D01*
X137258Y1165083D01*
X136967Y1165333D01*
X136800Y1165708D01*
X136758Y1166125D01*
X136842Y1166667D01*
X136967Y1166958D01*
X137175Y1167250D01*
X137467Y1167458D01*
X137758Y1167500D01*
X138050Y1167417D01*
X138258Y1167208D01*
G01X139858Y1167083D02*
X140108Y1167333D01*
X140400Y1167458D01*
X140733Y1167500D01*
X141150Y1167417D01*
X141442Y1167208D01*
X141525Y1166958D01*
X141483Y1166708D01*
X141317Y1166500D01*
X140483Y1166083D01*
X140108Y1165792D01*
X139858Y1165375D01*
X139775Y1165000D01*
X141525D01*
G01X127204Y1147465D02*
X126954Y1147590D01*
X126662Y1147673D01*
X126329D01*
X125954Y1147548D01*
X125662Y1147340D01*
X125454Y1147090D01*
X125287Y1146673D01*
X125245Y1146298D01*
X125329Y1145923D01*
X125454Y1145673D01*
X125704Y1145423D01*
X125995Y1145256D01*
X126287Y1145173D01*
X126579D01*
X126870Y1145256D01*
X127120Y1145381D01*
X127329Y1145548D01*
G01X128470D02*
X128720Y1145340D01*
X129012Y1145215D01*
X129387Y1145173D01*
X129762Y1145256D01*
X130054Y1145423D01*
X130262Y1145715D01*
X130304Y1146048D01*
X130220Y1146381D01*
X130012Y1146590D01*
X129720Y1146756D01*
X129429Y1146798D01*
X129137Y1146756D01*
X128762Y1146590D01*
X128887Y1147673D01*
X130012D01*
G01X132487Y1145173D02*
Y1147673D01*
X131987Y1147173D01*
G01Y1145173D02*
X132987D01*
G01X134670Y1145673D02*
X134920Y1145381D01*
X135254Y1145215D01*
X135629Y1145173D01*
X135962Y1145215D01*
X136295Y1145423D01*
X136504Y1145673D01*
X136545Y1145923D01*
X136462Y1146215D01*
X136170Y1146423D01*
X135879Y1146506D01*
X135504D01*
G01X135879D02*
X136129Y1146631D01*
X136337Y1146840D01*
X136420Y1147090D01*
X136337Y1147340D01*
X136129Y1147548D01*
X135754Y1147673D01*
X135379Y1147631D01*
X135004Y1147465D01*
G01X157017Y1185500D02*
Y1188000D01*
X158058D01*
X158392Y1187875D01*
X158600Y1187708D01*
X158683Y1187375D01*
X158600Y1187042D01*
X158350Y1186833D01*
X158058Y1186708D01*
X157017D01*
G01X158058D02*
X158683Y1185500D01*
G01X160033Y1185875D02*
X160283Y1185667D01*
X160575Y1185542D01*
X160950Y1185500D01*
X161325Y1185583D01*
X161617Y1185750D01*
X161825Y1186042D01*
X161867Y1186375D01*
X161783Y1186708D01*
X161575Y1186917D01*
X161283Y1187083D01*
X160992Y1187125D01*
X160700Y1187083D01*
X160325Y1186917D01*
X160450Y1188000D01*
X161575D01*
G01X163258Y1186542D02*
X163550Y1186833D01*
X163800Y1187000D01*
X164133Y1187083D01*
X164425Y1187000D01*
X164633Y1186833D01*
X164800Y1186583D01*
X164842Y1186292D01*
X164800Y1186042D01*
X164633Y1185792D01*
X164383Y1185583D01*
X164092Y1185500D01*
X163758Y1185583D01*
X163467Y1185833D01*
X163300Y1186208D01*
X163258Y1186625D01*
X163342Y1187167D01*
X163467Y1187458D01*
X163675Y1187750D01*
X163967Y1187958D01*
X164258Y1188000D01*
X164550Y1187917D01*
X164758Y1187708D01*
G01X167650Y1185500D02*
Y1188000D01*
X166108Y1186208D01*
X168192D01*
G01X148482Y1188220D02*
Y1184220D01*
X155882D01*
G01X156341Y1181092D02*
X143341D01*
G01X145837Y1205749D02*
X145504Y1205791D01*
X145212Y1205957D01*
X144962Y1206207D01*
X144795Y1206499D01*
X144712Y1206832D01*
Y1207166D01*
X144795Y1207499D01*
X144962Y1207791D01*
X145212Y1208041D01*
X145504Y1208207D01*
X145837Y1208249D01*
X146170Y1208207D01*
X146462Y1208041D01*
X146712Y1207791D01*
X146879Y1207499D01*
X146962Y1207166D01*
Y1206832D01*
X146879Y1206499D01*
X146712Y1206207D01*
X146462Y1205957D01*
X146170Y1205791D01*
X145837Y1205749D01*
G01X146170Y1206416D02*
X146670Y1205749D01*
G01X148145Y1207832D02*
X148395Y1208082D01*
X148687Y1208207D01*
X149020Y1208249D01*
X149437Y1208166D01*
X149729Y1207957D01*
X149812Y1207707D01*
X149770Y1207457D01*
X149604Y1207249D01*
X148770Y1206832D01*
X148395Y1206541D01*
X148145Y1206124D01*
X148062Y1205749D01*
X149812D01*
G01X151120Y1206124D02*
X151370Y1205916D01*
X151662Y1205791D01*
X152037Y1205749D01*
X152412Y1205832D01*
X152704Y1205999D01*
X152912Y1206291D01*
X152954Y1206624D01*
X152870Y1206957D01*
X152662Y1207166D01*
X152370Y1207332D01*
X152079Y1207374D01*
X151787Y1207332D01*
X151412Y1207166D01*
X151537Y1208249D01*
X152662D01*
G01X154345Y1207832D02*
X154595Y1208082D01*
X154887Y1208207D01*
X155220Y1208249D01*
X155637Y1208166D01*
X155929Y1207957D01*
X156012Y1207707D01*
X155970Y1207457D01*
X155804Y1207249D01*
X154970Y1206832D01*
X154595Y1206541D01*
X154345Y1206124D01*
X154262Y1205749D01*
X156012D01*
G01X143501Y1203474D02*
Y1189474D01*
G01X156501Y1203474D02*
X143501D01*
G01X156501Y1189474D02*
Y1203474D01*
G01X143501Y1189474D02*
X156501D01*
G01X131774Y1206542D02*
X129274D01*
Y1207583D01*
X129399Y1207917D01*
X129566Y1208125D01*
X129899Y1208208D01*
X130232Y1208125D01*
X130441Y1207875D01*
X130566Y1207583D01*
Y1206542D01*
G01Y1207583D02*
X131774Y1208208D01*
G01X129691Y1209683D02*
X129441Y1209933D01*
X129316Y1210225D01*
X129274Y1210558D01*
X129357Y1210975D01*
X129566Y1211267D01*
X129816Y1211350D01*
X130066Y1211308D01*
X130274Y1211142D01*
X130691Y1210308D01*
X130982Y1209933D01*
X131399Y1209683D01*
X131774Y1209600D01*
Y1211350D01*
G01Y1213575D02*
X129274D01*
X129774Y1213075D01*
G01X131774D02*
Y1214075D01*
G01X129274Y1216675D02*
X129357Y1216342D01*
X129566Y1216092D01*
X129816Y1215925D01*
X130149Y1215800D01*
X130524Y1215758D01*
X130899Y1215800D01*
X131232Y1215925D01*
X131482Y1216092D01*
X131691Y1216342D01*
X131774Y1216675D01*
X131691Y1217008D01*
X131482Y1217258D01*
X131232Y1217425D01*
X130899Y1217550D01*
X130524Y1217592D01*
X130149Y1217550D01*
X129816Y1217425D01*
X129566Y1217258D01*
X129357Y1217008D01*
X129274Y1216675D01*
G01X136788Y1206626D02*
X134288D01*
Y1207667D01*
X134413Y1208001D01*
X134580Y1208209D01*
X134913Y1208292D01*
X135246Y1208209D01*
X135455Y1207959D01*
X135580Y1207667D01*
Y1206626D01*
G01Y1207667D02*
X136788Y1208292D01*
G01X134705Y1209767D02*
X134455Y1210017D01*
X134330Y1210309D01*
X134288Y1210642D01*
X134371Y1211059D01*
X134580Y1211351D01*
X134830Y1211434D01*
X135080Y1211392D01*
X135288Y1211226D01*
X135705Y1210392D01*
X135996Y1210017D01*
X136413Y1209767D01*
X136788Y1209684D01*
Y1211434D01*
G01X134288Y1213659D02*
X134371Y1213326D01*
X134580Y1213076D01*
X134830Y1212909D01*
X135163Y1212784D01*
X135538Y1212742D01*
X135913Y1212784D01*
X136246Y1212909D01*
X136496Y1213076D01*
X136705Y1213326D01*
X136788Y1213659D01*
X136705Y1213992D01*
X136496Y1214242D01*
X136246Y1214409D01*
X135913Y1214534D01*
X135538Y1214576D01*
X135163Y1214534D01*
X134830Y1214409D01*
X134580Y1214242D01*
X134371Y1213992D01*
X134288Y1213659D01*
G01X136496Y1216051D02*
X136705Y1216342D01*
X136788Y1216676D01*
X136705Y1217009D01*
X136455Y1217301D01*
X136080Y1217509D01*
X135705Y1217592D01*
X135246D01*
X134871Y1217509D01*
X134538Y1217301D01*
X134371Y1217051D01*
X134288Y1216759D01*
X134371Y1216426D01*
X134538Y1216176D01*
X134788Y1216009D01*
X135121Y1215926D01*
X135413Y1216009D01*
X135705Y1216217D01*
X135871Y1216467D01*
X135913Y1216759D01*
X135830Y1217092D01*
X135621Y1217342D01*
X135246Y1217592D01*
G01X197900Y162517D02*
X195400D01*
Y163558D01*
X195525Y163892D01*
X195692Y164100D01*
X196025Y164183D01*
X196358Y164100D01*
X196567Y163850D01*
X196692Y163558D01*
Y162517D01*
G01Y163558D02*
X197900Y164183D01*
G01Y166367D02*
X197358Y166450D01*
X196900Y166575D01*
X196483Y166742D01*
X196025Y166950D01*
X195400Y167283D01*
Y165617D01*
G01X195817Y168758D02*
X195567Y169008D01*
X195442Y169300D01*
X195400Y169633D01*
X195483Y170050D01*
X195692Y170342D01*
X195942Y170425D01*
X196192Y170383D01*
X196400Y170217D01*
X196817Y169383D01*
X197108Y169008D01*
X197525Y168758D01*
X197900Y168675D01*
Y170425D01*
G01X195817Y171858D02*
X195567Y172108D01*
X195442Y172400D01*
X195400Y172733D01*
X195483Y173150D01*
X195692Y173442D01*
X195942Y173525D01*
X196192Y173483D01*
X196400Y173317D01*
X196817Y172483D01*
X197108Y172108D01*
X197525Y171858D01*
X197900Y171775D01*
Y173525D01*
G01X209266Y161661D02*
Y164161D01*
X210307D01*
X210641Y164036D01*
X210849Y163869D01*
X210932Y163536D01*
X210849Y163203D01*
X210599Y162994D01*
X210307Y162869D01*
X209266D01*
G01X210307D02*
X210932Y161661D01*
G01X213116D02*
X213199Y162203D01*
X213324Y162661D01*
X213491Y163078D01*
X213699Y163536D01*
X214032Y164161D01*
X212366D01*
G01X216299Y161661D02*
Y164161D01*
X215799Y163661D01*
G01Y161661D02*
X216799D01*
G01X218607Y162703D02*
X218899Y162994D01*
X219149Y163161D01*
X219482Y163244D01*
X219774Y163161D01*
X219982Y162994D01*
X220149Y162744D01*
X220191Y162453D01*
X220149Y162203D01*
X219982Y161953D01*
X219732Y161744D01*
X219441Y161661D01*
X219107Y161744D01*
X218816Y161994D01*
X218649Y162369D01*
X218607Y162786D01*
X218691Y163328D01*
X218816Y163619D01*
X219024Y163911D01*
X219316Y164119D01*
X219607Y164161D01*
X219899Y164078D01*
X220107Y163869D01*
G01X191500Y162983D02*
X189000D01*
Y163817D01*
X189125Y164150D01*
X189292Y164400D01*
X189542Y164608D01*
X189833Y164775D01*
X190250Y164817D01*
X190667Y164775D01*
X190958Y164608D01*
X191208Y164400D01*
X191375Y164150D01*
X191500Y163817D01*
Y162983D01*
G01X189417Y166208D02*
X189167Y166458D01*
X189042Y166750D01*
X189000Y167083D01*
X189083Y167500D01*
X189292Y167792D01*
X189542Y167875D01*
X189792Y167833D01*
X190000Y167667D01*
X190417Y166833D01*
X190708Y166458D01*
X191125Y166208D01*
X191500Y166125D01*
Y167875D01*
G01X191125Y169183D02*
X191333Y169433D01*
X191458Y169725D01*
X191500Y170100D01*
X191417Y170475D01*
X191250Y170767D01*
X190958Y170975D01*
X190625Y171017D01*
X190292Y170933D01*
X190083Y170725D01*
X189917Y170433D01*
X189875Y170142D01*
X189917Y169850D01*
X190083Y169475D01*
X189000Y169600D01*
Y170725D01*
G01X174317Y173500D02*
Y176000D01*
X175358D01*
X175692Y175875D01*
X175900Y175708D01*
X175983Y175375D01*
X175900Y175042D01*
X175650Y174833D01*
X175358Y174708D01*
X174317D01*
G01X175358D02*
X175983Y173500D01*
G01X178167D02*
X178250Y174042D01*
X178375Y174500D01*
X178542Y174917D01*
X178750Y175375D01*
X179083Y176000D01*
X177417D01*
G01X181350Y173500D02*
Y176000D01*
X180850Y175500D01*
G01Y173500D02*
X181850D01*
G01X183742Y173792D02*
X184033Y173583D01*
X184367Y173500D01*
X184700Y173583D01*
X184992Y173833D01*
X185200Y174208D01*
X185283Y174583D01*
Y175042D01*
X185200Y175417D01*
X184992Y175750D01*
X184742Y175917D01*
X184450Y176000D01*
X184117Y175917D01*
X183867Y175750D01*
X183700Y175500D01*
X183617Y175167D01*
X183700Y174875D01*
X183908Y174583D01*
X184158Y174417D01*
X184450Y174375D01*
X184783Y174458D01*
X185033Y174667D01*
X185283Y175042D01*
G01X178749Y181661D02*
Y177661D01*
X186149D01*
G01X181000Y184117D02*
X178500D01*
Y185158D01*
X178625Y185492D01*
X178792Y185700D01*
X179125Y185783D01*
X179458Y185700D01*
X179667Y185450D01*
X179792Y185158D01*
Y184117D01*
G01Y185158D02*
X181000Y185783D01*
G01Y187967D02*
X180458Y188050D01*
X180000Y188175D01*
X179583Y188342D01*
X179125Y188550D01*
X178500Y188883D01*
Y187217D01*
G01X178917Y190358D02*
X178667Y190608D01*
X178542Y190900D01*
X178500Y191233D01*
X178583Y191650D01*
X178792Y191942D01*
X179042Y192025D01*
X179292Y191983D01*
X179500Y191817D01*
X179917Y190983D01*
X180208Y190608D01*
X180625Y190358D01*
X181000Y190275D01*
Y192025D01*
G01Y194250D02*
X178500D01*
X179000Y193750D01*
G01X181000D02*
Y194750D01*
G01X182149Y182061D02*
X186149D01*
Y189461D01*
G01X199049Y183361D02*
X195049D01*
Y175961D01*
G01X173466Y200461D02*
Y202961D01*
X174507D01*
X174841Y202836D01*
X175049Y202669D01*
X175132Y202336D01*
X175049Y202003D01*
X174799Y201794D01*
X174507Y201669D01*
X173466D01*
G01X174507D02*
X175132Y200461D01*
G01X177316D02*
X177399Y201003D01*
X177524Y201461D01*
X177691Y201878D01*
X177899Y202336D01*
X178232Y202961D01*
X176566D01*
G01X180499Y200461D02*
Y202961D01*
X179999Y202461D01*
G01Y200461D02*
X180999D01*
G01X182807Y202544D02*
X183057Y202794D01*
X183349Y202919D01*
X183682Y202961D01*
X184099Y202878D01*
X184391Y202669D01*
X184474Y202419D01*
X184432Y202169D01*
X184266Y201961D01*
X183432Y201544D01*
X183057Y201253D01*
X182807Y200836D01*
X182724Y200461D01*
X184474D01*
G01X186749Y206961D02*
Y202961D01*
X194149D01*
G01X186349Y208561D02*
Y212561D01*
X178949D01*
G01X209266Y166361D02*
Y168861D01*
X210307D01*
X210641Y168736D01*
X210849Y168569D01*
X210932Y168236D01*
X210849Y167903D01*
X210599Y167694D01*
X210307Y167569D01*
X209266D01*
G01X210307D02*
X210932Y166361D01*
G01X213116D02*
X213199Y166903D01*
X213324Y167361D01*
X213491Y167778D01*
X213699Y168236D01*
X214032Y168861D01*
X212366D01*
G01X216299Y166361D02*
Y168861D01*
X215799Y168361D01*
G01Y166361D02*
X216799D01*
G01X218482Y166861D02*
X218732Y166569D01*
X219066Y166403D01*
X219441Y166361D01*
X219774Y166403D01*
X220107Y166611D01*
X220316Y166861D01*
X220357Y167111D01*
X220274Y167403D01*
X219982Y167611D01*
X219691Y167694D01*
X219316D01*
G01X219691D02*
X219941Y167819D01*
X220149Y168028D01*
X220232Y168278D01*
X220149Y168528D01*
X219941Y168736D01*
X219566Y168861D01*
X219191Y168819D01*
X218816Y168653D01*
G01X218449Y179361D02*
Y183361D01*
X211049D01*
G01X218449Y174661D02*
Y178661D01*
X211049D01*
G01X209617Y170500D02*
Y173000D01*
X210658D01*
X210992Y172875D01*
X211200Y172708D01*
X211283Y172375D01*
X211200Y172042D01*
X210950Y171833D01*
X210658Y171708D01*
X209617D01*
G01X210658D02*
X211283Y170500D01*
G01X213467D02*
X213550Y171042D01*
X213675Y171500D01*
X213842Y171917D01*
X214050Y172375D01*
X214383Y173000D01*
X212717D01*
G01X216650Y170500D02*
Y173000D01*
X216150Y172500D01*
G01Y170500D02*
X217150D01*
G01X219667D02*
X219750Y171042D01*
X219875Y171500D01*
X220042Y171917D01*
X220250Y172375D01*
X220583Y173000D01*
X218917D01*
G01X211049Y193161D02*
Y189161D01*
X218449D01*
G01X187850Y194000D02*
X187517Y194042D01*
X187225Y194208D01*
X186975Y194458D01*
X186808Y194750D01*
X186725Y195083D01*
Y195417D01*
X186808Y195750D01*
X186975Y196042D01*
X187225Y196292D01*
X187517Y196458D01*
X187850Y196500D01*
X188183Y196458D01*
X188475Y196292D01*
X188725Y196042D01*
X188892Y195750D01*
X188975Y195417D01*
Y195083D01*
X188892Y194750D01*
X188725Y194458D01*
X188475Y194208D01*
X188183Y194042D01*
X187850Y194000D01*
G01X188183Y194667D02*
X188683Y194000D01*
G01X190950D02*
Y196500D01*
X190450Y196000D01*
G01Y194000D02*
X191450D01*
G01X193133Y194375D02*
X193383Y194167D01*
X193675Y194042D01*
X194050Y194000D01*
X194425Y194083D01*
X194717Y194250D01*
X194925Y194542D01*
X194967Y194875D01*
X194883Y195208D01*
X194675Y195417D01*
X194383Y195583D01*
X194092Y195625D01*
X193800Y195583D01*
X193425Y195417D01*
X193550Y196500D01*
X194675D01*
G01X197150Y194000D02*
Y196500D01*
X196650Y196000D01*
G01Y194000D02*
X197650D01*
G01X198949Y197861D02*
Y184461D01*
G01D02*
X210349D01*
G01D02*
Y197861D01*
G01D02*
X198949D01*
G01X194149Y176061D02*
X187149D01*
G01D02*
Y192161D01*
G01D02*
X194149D01*
G01D02*
Y176061D01*
G01X216449Y223261D02*
X197249D01*
Y212061D01*
X216449D01*
Y223261D01*
X216049D01*
G01X175216Y206853D02*
X174966Y206978D01*
X174674Y207061D01*
X174341D01*
X173966Y206936D01*
X173674Y206728D01*
X173466Y206478D01*
X173299Y206061D01*
X173257Y205686D01*
X173341Y205311D01*
X173466Y205061D01*
X173716Y204811D01*
X174007Y204644D01*
X174299Y204561D01*
X174591D01*
X174882Y204644D01*
X175132Y204769D01*
X175341Y204936D01*
G01X176482Y205061D02*
X176732Y204769D01*
X177066Y204603D01*
X177441Y204561D01*
X177774Y204603D01*
X178107Y204811D01*
X178316Y205061D01*
X178357Y205311D01*
X178274Y205603D01*
X177982Y205811D01*
X177691Y205894D01*
X177316D01*
G01X177691D02*
X177941Y206019D01*
X178149Y206228D01*
X178232Y206478D01*
X178149Y206728D01*
X177941Y206936D01*
X177566Y207061D01*
X177191Y207019D01*
X176816Y206853D01*
G01X180416Y204561D02*
X180499Y205103D01*
X180624Y205561D01*
X180791Y205978D01*
X180999Y206436D01*
X181332Y207061D01*
X179666D01*
G01X182682Y205061D02*
X182932Y204769D01*
X183266Y204603D01*
X183641Y204561D01*
X183974Y204603D01*
X184307Y204811D01*
X184516Y205061D01*
X184557Y205311D01*
X184474Y205603D01*
X184182Y205811D01*
X183891Y205894D01*
X183516D01*
G01X183891D02*
X184141Y206019D01*
X184349Y206228D01*
X184432Y206478D01*
X184349Y206728D01*
X184141Y206936D01*
X183766Y207061D01*
X183391Y207019D01*
X183016Y206853D01*
G01X189849Y250661D02*
Y258661D01*
X207449D01*
Y250661D01*
X189849D01*
G01X218500Y256017D02*
X216000D01*
Y257058D01*
X216125Y257392D01*
X216292Y257600D01*
X216625Y257683D01*
X216958Y257600D01*
X217167Y257350D01*
X217292Y257058D01*
Y256017D01*
G01Y257058D02*
X218500Y257683D01*
G01Y259867D02*
X217958Y259950D01*
X217500Y260075D01*
X217083Y260242D01*
X216625Y260450D01*
X216000Y260783D01*
Y259117D01*
G01Y263050D02*
X216083Y262717D01*
X216292Y262467D01*
X216542Y262300D01*
X216875Y262175D01*
X217250Y262133D01*
X217625Y262175D01*
X217958Y262300D01*
X218208Y262467D01*
X218417Y262717D01*
X218500Y263050D01*
X218417Y263383D01*
X218208Y263633D01*
X217958Y263800D01*
X217625Y263925D01*
X217250Y263967D01*
X216875Y263925D01*
X216542Y263800D01*
X216292Y263633D01*
X216083Y263383D01*
X216000Y263050D01*
G01X218500Y266650D02*
X216000D01*
X217792Y265108D01*
Y267192D01*
G01X213649Y253961D02*
X221649D01*
Y236361D01*
X213649D01*
Y253961D01*
G01X178767Y262292D02*
X178517Y262417D01*
X178225Y262500D01*
X177892D01*
X177517Y262375D01*
X177225Y262167D01*
X177017Y261917D01*
X176850Y261500D01*
X176808Y261125D01*
X176892Y260750D01*
X177017Y260500D01*
X177267Y260250D01*
X177558Y260083D01*
X177850Y260000D01*
X178142D01*
X178433Y260083D01*
X178683Y260208D01*
X178892Y260375D01*
G01X180033Y260500D02*
X180283Y260208D01*
X180617Y260042D01*
X180992Y260000D01*
X181325Y260042D01*
X181658Y260250D01*
X181867Y260500D01*
X181908Y260750D01*
X181825Y261042D01*
X181533Y261250D01*
X181242Y261333D01*
X180867D01*
G01X181242D02*
X181492Y261458D01*
X181700Y261667D01*
X181783Y261917D01*
X181700Y262167D01*
X181492Y262375D01*
X181117Y262500D01*
X180742Y262458D01*
X180367Y262292D01*
G01X183967Y260000D02*
X184050Y260542D01*
X184175Y261000D01*
X184342Y261417D01*
X184550Y261875D01*
X184883Y262500D01*
X183217D01*
G01X187150D02*
X186817Y262417D01*
X186567Y262208D01*
X186400Y261958D01*
X186275Y261625D01*
X186233Y261250D01*
X186275Y260875D01*
X186400Y260542D01*
X186567Y260292D01*
X186817Y260083D01*
X187150Y260000D01*
X187483Y260083D01*
X187733Y260292D01*
X187900Y260542D01*
X188025Y260875D01*
X188067Y261250D01*
X188025Y261625D01*
X187900Y261958D01*
X187733Y262208D01*
X187483Y262417D01*
X187150Y262500D01*
G01X199849Y236161D02*
X194349D01*
G01D02*
Y244161D01*
G01D02*
X199849D01*
G01X206449D02*
X211949D01*
G01D02*
Y236161D01*
G01D02*
X206449D01*
G01X171849Y230061D02*
X191049D01*
Y241261D01*
X171849D01*
Y230061D01*
X172249D01*
G01X171949Y237661D02*
X174049Y235861D01*
X171949Y233661D01*
G01X216349Y215661D02*
X214249Y217461D01*
X216349Y219661D01*
G01X196017Y271000D02*
Y273500D01*
X197058D01*
X197392Y273375D01*
X197600Y273208D01*
X197683Y272875D01*
X197600Y272542D01*
X197350Y272333D01*
X197058Y272208D01*
X196017D01*
G01X197058D02*
X197683Y271000D01*
G01X199867D02*
X199950Y271542D01*
X200075Y272000D01*
X200242Y272417D01*
X200450Y272875D01*
X200783Y273500D01*
X199117D01*
G01X203050D02*
X202717Y273417D01*
X202467Y273208D01*
X202300Y272958D01*
X202175Y272625D01*
X202133Y272250D01*
X202175Y271875D01*
X202300Y271542D01*
X202467Y271292D01*
X202717Y271083D01*
X203050Y271000D01*
X203383Y271083D01*
X203633Y271292D01*
X203800Y271542D01*
X203925Y271875D01*
X203967Y272250D01*
X203925Y272625D01*
X203800Y272958D01*
X203633Y273208D01*
X203383Y273417D01*
X203050Y273500D01*
G01X205358Y272042D02*
X205650Y272333D01*
X205900Y272500D01*
X206233Y272583D01*
X206525Y272500D01*
X206733Y272333D01*
X206900Y272083D01*
X206942Y271792D01*
X206900Y271542D01*
X206733Y271292D01*
X206483Y271083D01*
X206192Y271000D01*
X205858Y271083D01*
X205567Y271333D01*
X205400Y271708D01*
X205358Y272125D01*
X205442Y272667D01*
X205567Y272958D01*
X205775Y273250D01*
X206067Y273458D01*
X206358Y273500D01*
X206650Y273417D01*
X206858Y273208D01*
G01X210708Y280767D02*
X210583Y280517D01*
X210500Y280225D01*
Y279892D01*
X210625Y279517D01*
X210833Y279225D01*
X211083Y279017D01*
X211500Y278850D01*
X211875Y278808D01*
X212250Y278892D01*
X212500Y279017D01*
X212750Y279267D01*
X212917Y279558D01*
X213000Y279850D01*
Y280142D01*
X212917Y280433D01*
X212792Y280683D01*
X212625Y280892D01*
G01X212500Y282033D02*
X212792Y282283D01*
X212958Y282617D01*
X213000Y282992D01*
X212958Y283325D01*
X212750Y283658D01*
X212500Y283867D01*
X212250Y283908D01*
X211958Y283825D01*
X211750Y283533D01*
X211667Y283242D01*
Y282867D01*
G01Y283242D02*
X211542Y283492D01*
X211333Y283700D01*
X211083Y283783D01*
X210833Y283700D01*
X210625Y283492D01*
X210500Y283117D01*
X210542Y282742D01*
X210708Y282367D01*
G01X211958Y285258D02*
X211667Y285550D01*
X211500Y285800D01*
X211417Y286133D01*
X211500Y286425D01*
X211667Y286633D01*
X211917Y286800D01*
X212208Y286842D01*
X212458Y286800D01*
X212708Y286633D01*
X212917Y286383D01*
X213000Y286092D01*
X212917Y285758D01*
X212667Y285467D01*
X212292Y285300D01*
X211875Y285258D01*
X211333Y285342D01*
X211042Y285467D01*
X210750Y285675D01*
X210542Y285967D01*
X210500Y286258D01*
X210583Y286550D01*
X210792Y286758D01*
G01X212708Y288442D02*
X212917Y288733D01*
X213000Y289067D01*
X212917Y289400D01*
X212667Y289692D01*
X212292Y289900D01*
X211917Y289983D01*
X211458D01*
X211083Y289900D01*
X210750Y289692D01*
X210583Y289442D01*
X210500Y289150D01*
X210583Y288817D01*
X210750Y288567D01*
X211000Y288400D01*
X211333Y288317D01*
X211625Y288400D01*
X211917Y288608D01*
X212083Y288858D01*
X212125Y289150D01*
X212042Y289483D01*
X211833Y289733D01*
X211458Y289983D01*
G01X197767Y265292D02*
X197517Y265417D01*
X197225Y265500D01*
X196892D01*
X196517Y265375D01*
X196225Y265167D01*
X196017Y264917D01*
X195850Y264500D01*
X195808Y264125D01*
X195892Y263750D01*
X196017Y263500D01*
X196267Y263250D01*
X196558Y263083D01*
X196850Y263000D01*
X197142D01*
X197433Y263083D01*
X197683Y263208D01*
X197892Y263375D01*
G01X199033Y263500D02*
X199283Y263208D01*
X199617Y263042D01*
X199992Y263000D01*
X200325Y263042D01*
X200658Y263250D01*
X200867Y263500D01*
X200908Y263750D01*
X200825Y264042D01*
X200533Y264250D01*
X200242Y264333D01*
X199867D01*
G01X200242D02*
X200492Y264458D01*
X200700Y264667D01*
X200783Y264917D01*
X200700Y265167D01*
X200492Y265375D01*
X200117Y265500D01*
X199742Y265458D01*
X199367Y265292D01*
G01X202258Y264042D02*
X202550Y264333D01*
X202800Y264500D01*
X203133Y264583D01*
X203425Y264500D01*
X203633Y264333D01*
X203800Y264083D01*
X203842Y263792D01*
X203800Y263542D01*
X203633Y263292D01*
X203383Y263083D01*
X203092Y263000D01*
X202758Y263083D01*
X202467Y263333D01*
X202300Y263708D01*
X202258Y264125D01*
X202342Y264667D01*
X202467Y264958D01*
X202675Y265250D01*
X202967Y265458D01*
X203258Y265500D01*
X203550Y265417D01*
X203758Y265208D01*
G01X205358Y264042D02*
X205650Y264333D01*
X205900Y264500D01*
X206233Y264583D01*
X206525Y264500D01*
X206733Y264333D01*
X206900Y264083D01*
X206942Y263792D01*
X206900Y263542D01*
X206733Y263292D01*
X206483Y263083D01*
X206192Y263000D01*
X205858Y263083D01*
X205567Y263333D01*
X205400Y263708D01*
X205358Y264125D01*
X205442Y264667D01*
X205567Y264958D01*
X205775Y265250D01*
X206067Y265458D01*
X206358Y265500D01*
X206650Y265417D01*
X206858Y265208D01*
G01X197767Y269292D02*
X197517Y269417D01*
X197225Y269500D01*
X196892D01*
X196517Y269375D01*
X196225Y269167D01*
X196017Y268917D01*
X195850Y268500D01*
X195808Y268125D01*
X195892Y267750D01*
X196017Y267500D01*
X196267Y267250D01*
X196558Y267083D01*
X196850Y267000D01*
X197142D01*
X197433Y267083D01*
X197683Y267208D01*
X197892Y267375D01*
G01X199033Y267500D02*
X199283Y267208D01*
X199617Y267042D01*
X199992Y267000D01*
X200325Y267042D01*
X200658Y267250D01*
X200867Y267500D01*
X200908Y267750D01*
X200825Y268042D01*
X200533Y268250D01*
X200242Y268333D01*
X199867D01*
G01X200242D02*
X200492Y268458D01*
X200700Y268667D01*
X200783Y268917D01*
X200700Y269167D01*
X200492Y269375D01*
X200117Y269500D01*
X199742Y269458D01*
X199367Y269292D01*
G01X202258Y268042D02*
X202550Y268333D01*
X202800Y268500D01*
X203133Y268583D01*
X203425Y268500D01*
X203633Y268333D01*
X203800Y268083D01*
X203842Y267792D01*
X203800Y267542D01*
X203633Y267292D01*
X203383Y267083D01*
X203092Y267000D01*
X202758Y267083D01*
X202467Y267333D01*
X202300Y267708D01*
X202258Y268125D01*
X202342Y268667D01*
X202467Y268958D01*
X202675Y269250D01*
X202967Y269458D01*
X203258Y269500D01*
X203550Y269417D01*
X203758Y269208D01*
G01X205233Y267375D02*
X205483Y267167D01*
X205775Y267042D01*
X206150Y267000D01*
X206525Y267083D01*
X206817Y267250D01*
X207025Y267542D01*
X207067Y267875D01*
X206983Y268208D01*
X206775Y268417D01*
X206483Y268583D01*
X206192Y268625D01*
X205900Y268583D01*
X205525Y268417D01*
X205650Y269500D01*
X206775D01*
G01X214208Y292767D02*
X214083Y292517D01*
X214000Y292225D01*
Y291892D01*
X214125Y291517D01*
X214333Y291225D01*
X214583Y291017D01*
X215000Y290850D01*
X215375Y290808D01*
X215750Y290892D01*
X216000Y291017D01*
X216250Y291267D01*
X216417Y291558D01*
X216500Y291850D01*
Y292142D01*
X216417Y292433D01*
X216292Y292683D01*
X216125Y292892D01*
G01X216000Y294033D02*
X216292Y294283D01*
X216458Y294617D01*
X216500Y294992D01*
X216458Y295325D01*
X216250Y295658D01*
X216000Y295867D01*
X215750Y295908D01*
X215458Y295825D01*
X215250Y295533D01*
X215167Y295242D01*
Y294867D01*
G01Y295242D02*
X215042Y295492D01*
X214833Y295700D01*
X214583Y295783D01*
X214333Y295700D01*
X214125Y295492D01*
X214000Y295117D01*
X214042Y294742D01*
X214208Y294367D01*
G01X216500Y297967D02*
X215958Y298050D01*
X215500Y298175D01*
X215083Y298342D01*
X214625Y298550D01*
X214000Y298883D01*
Y297217D01*
G01X214417Y300358D02*
X214167Y300608D01*
X214042Y300900D01*
X214000Y301233D01*
X214083Y301650D01*
X214292Y301942D01*
X214542Y302025D01*
X214792Y301983D01*
X215000Y301817D01*
X215417Y300983D01*
X215708Y300608D01*
X216125Y300358D01*
X216500Y300275D01*
Y302025D01*
G01X187249Y381654D02*
Y384154D01*
X188833D01*
G01X188249Y382946D02*
X187249D01*
G01X190308Y384154D02*
Y381654D01*
X191974D01*
G01X195074D02*
X193408D01*
Y384154D01*
X195074D01*
G01X194408Y382946D02*
X193408D01*
G01X196424Y381654D02*
Y384154D01*
X197258D01*
X197591Y384029D01*
X197841Y383862D01*
X198049Y383612D01*
X198216Y383321D01*
X198258Y382904D01*
X198216Y382487D01*
X198049Y382196D01*
X197841Y381946D01*
X197591Y381779D01*
X197258Y381654D01*
X196424D01*
G01X200441D02*
Y384154D01*
X199941Y383654D01*
G01Y381654D02*
X200941D01*
G01X204041D02*
Y384154D01*
X202499Y382362D01*
X204583D01*
G01X189891Y366054D02*
Y377254D01*
X198691D01*
Y366054D01*
X189891D01*
G01X192173Y458631D02*
Y468631D01*
X190173Y466631D01*
G01Y458631D02*
X194173D01*
G01X199606Y462797D02*
X200773Y463964D01*
X201773Y464631D01*
X203106Y464964D01*
X204273Y464631D01*
X205106Y463964D01*
X205773Y462964D01*
X205940Y461798D01*
X205773Y460798D01*
X205106Y459797D01*
X204106Y458964D01*
X202940Y458631D01*
X201606Y458964D01*
X200440Y459964D01*
X199773Y461464D01*
X199606Y463131D01*
X199940Y465297D01*
X200440Y466464D01*
X201273Y467631D01*
X202440Y468464D01*
X203606Y468631D01*
X204773Y468298D01*
X205606Y467464D01*
G01X209706Y460631D02*
X210706Y459464D01*
X212039Y458798D01*
X213540Y458631D01*
X214873Y458798D01*
X216206Y459631D01*
X217040Y460631D01*
X217206Y461631D01*
X216873Y462797D01*
X215706Y463631D01*
X214540Y463964D01*
X213040D01*
G01X214540D02*
X215540Y464464D01*
X216373Y465297D01*
X216706Y466298D01*
X216373Y467298D01*
X215540Y468131D01*
X214040Y468631D01*
X212540Y468464D01*
X211040Y467798D01*
G01X223973Y458631D02*
Y468631D01*
X221973Y466631D01*
G01Y458631D02*
X225973D01*
G01X230906Y460131D02*
X231906Y459298D01*
X233073Y458798D01*
X234573Y458631D01*
X236073Y458964D01*
X237240Y459631D01*
X238073Y460798D01*
X238240Y462131D01*
X237906Y463464D01*
X237073Y464298D01*
X235906Y464964D01*
X234740Y465131D01*
X233573Y464964D01*
X232073Y464298D01*
X232573Y468631D01*
X237073D01*
G01X243006Y461964D02*
X247340D01*
G01X255773Y458631D02*
Y468631D01*
X253773Y466631D01*
G01Y458631D02*
X257773D01*
G01X174482Y496142D02*
Y510142D01*
G01X177067Y491605D02*
X176734Y491647D01*
X176442Y491813D01*
X176192Y492063D01*
X176025Y492355D01*
X175942Y492688D01*
Y493022D01*
X176025Y493355D01*
X176192Y493647D01*
X176442Y493897D01*
X176734Y494063D01*
X177067Y494105D01*
X177400Y494063D01*
X177692Y493897D01*
X177942Y493647D01*
X178109Y493355D01*
X178192Y493022D01*
Y492688D01*
X178109Y492355D01*
X177942Y492063D01*
X177692Y491813D01*
X177400Y491647D01*
X177067Y491605D01*
G01X177400Y492272D02*
X177900Y491605D01*
G01X179375Y493688D02*
X179625Y493938D01*
X179917Y494063D01*
X180250Y494105D01*
X180667Y494022D01*
X180959Y493813D01*
X181042Y493563D01*
X181000Y493313D01*
X180834Y493105D01*
X180000Y492688D01*
X179625Y492397D01*
X179375Y491980D01*
X179292Y491605D01*
X181042D01*
G01X183767D02*
Y494105D01*
X182225Y492313D01*
X184309D01*
G01X186367Y494105D02*
X186034Y494022D01*
X185784Y493813D01*
X185617Y493563D01*
X185492Y493230D01*
X185450Y492855D01*
X185492Y492480D01*
X185617Y492147D01*
X185784Y491897D01*
X186034Y491688D01*
X186367Y491605D01*
X186700Y491688D01*
X186950Y491897D01*
X187117Y492147D01*
X187242Y492480D01*
X187284Y492855D01*
X187242Y493230D01*
X187117Y493563D01*
X186950Y493813D01*
X186700Y494022D01*
X186367Y494105D01*
G01X188717Y496105D02*
Y510105D01*
G01X175717Y496105D02*
X188717D01*
G01X175717Y510105D02*
Y496105D01*
G01X178855Y522878D02*
Y525378D01*
X179896D01*
X180230Y525253D01*
X180438Y525086D01*
X180521Y524753D01*
X180438Y524420D01*
X180188Y524211D01*
X179896Y524086D01*
X178855D01*
G01X179896D02*
X180521Y522878D01*
G01X181871Y523253D02*
X182121Y523045D01*
X182413Y522920D01*
X182788Y522878D01*
X183163Y522961D01*
X183455Y523128D01*
X183663Y523420D01*
X183705Y523753D01*
X183621Y524086D01*
X183413Y524295D01*
X183121Y524461D01*
X182830Y524503D01*
X182538Y524461D01*
X182163Y524295D01*
X182288Y525378D01*
X183413D01*
G01X185888D02*
X185555Y525295D01*
X185305Y525086D01*
X185138Y524836D01*
X185013Y524503D01*
X184971Y524128D01*
X185013Y523753D01*
X185138Y523420D01*
X185305Y523170D01*
X185555Y522961D01*
X185888Y522878D01*
X186221Y522961D01*
X186471Y523170D01*
X186638Y523420D01*
X186763Y523753D01*
X186805Y524128D01*
X186763Y524503D01*
X186638Y524836D01*
X186471Y525086D01*
X186221Y525295D01*
X185888Y525378D01*
G01X188905Y522878D02*
X188988Y523420D01*
X189113Y523878D01*
X189280Y524295D01*
X189488Y524753D01*
X189821Y525378D01*
X188155D01*
G01X188038Y510878D02*
Y514878D01*
X180638D01*
G01X188717Y510105D02*
X175717D01*
G01X182967Y545000D02*
Y547500D01*
X184008D01*
X184342Y547375D01*
X184550Y547208D01*
X184633Y546875D01*
X184550Y546542D01*
X184300Y546333D01*
X184008Y546208D01*
X182967D01*
G01X184008D02*
X184633Y545000D01*
G01X186900D02*
Y547500D01*
X186400Y547000D01*
G01Y545000D02*
X187400D01*
G01X189208Y547083D02*
X189458Y547333D01*
X189750Y547458D01*
X190083Y547500D01*
X190500Y547417D01*
X190792Y547208D01*
X190875Y546958D01*
X190833Y546708D01*
X190667Y546500D01*
X189833Y546083D01*
X189458Y545792D01*
X189208Y545375D01*
X189125Y545000D01*
X190875D01*
G01X192183Y545500D02*
X192433Y545208D01*
X192767Y545042D01*
X193142Y545000D01*
X193475Y545042D01*
X193808Y545250D01*
X194017Y545500D01*
X194058Y545750D01*
X193975Y546042D01*
X193683Y546250D01*
X193392Y546333D01*
X193017D01*
G01X193392D02*
X193642Y546458D01*
X193850Y546667D01*
X193933Y546917D01*
X193850Y547167D01*
X193642Y547375D01*
X193267Y547500D01*
X192892Y547458D01*
X192517Y547292D01*
G01X196200Y545000D02*
Y547500D01*
X195700Y547000D01*
G01Y545000D02*
X196700D01*
G01X195194Y550575D02*
X189994D01*
G01X195194D02*
Y557575D01*
G01X181794Y550575D02*
X190494D01*
G01X181794Y557575D02*
Y550575D01*
G01X199141Y511764D02*
X196641D01*
Y512805D01*
X196766Y513139D01*
X196933Y513347D01*
X197266Y513430D01*
X197599Y513347D01*
X197808Y513097D01*
X197933Y512805D01*
Y511764D01*
G01Y512805D02*
X199141Y513430D01*
G01X197058Y514905D02*
X196808Y515155D01*
X196683Y515447D01*
X196641Y515780D01*
X196724Y516197D01*
X196933Y516489D01*
X197183Y516572D01*
X197433Y516530D01*
X197641Y516364D01*
X198058Y515530D01*
X198349Y515155D01*
X198766Y514905D01*
X199141Y514822D01*
Y516572D01*
G01Y518797D02*
X199099Y519089D01*
X198974Y519422D01*
X198766Y519630D01*
X198474Y519714D01*
X198183Y519630D01*
X197933Y519380D01*
X197808Y519005D01*
Y518589D01*
X197724Y518339D01*
X197516Y518130D01*
X197224Y518047D01*
X196933Y518172D01*
X196724Y518464D01*
X196641Y518797D01*
X196724Y519130D01*
X196933Y519422D01*
X197224Y519547D01*
X197516Y519464D01*
X197724Y519255D01*
X197808Y519005D01*
Y518589D01*
X197933Y518214D01*
X198183Y517964D01*
X198474Y517880D01*
X198766Y517964D01*
X198974Y518172D01*
X199099Y518505D01*
X199141Y518797D01*
G01Y521897D02*
X199099Y522189D01*
X198974Y522522D01*
X198766Y522730D01*
X198474Y522814D01*
X198183Y522730D01*
X197933Y522480D01*
X197808Y522105D01*
Y521689D01*
X197724Y521439D01*
X197516Y521230D01*
X197224Y521147D01*
X196933Y521272D01*
X196724Y521564D01*
X196641Y521897D01*
X196724Y522230D01*
X196933Y522522D01*
X197224Y522647D01*
X197516Y522564D01*
X197724Y522355D01*
X197808Y522105D01*
Y521689D01*
X197933Y521314D01*
X198183Y521064D01*
X198474Y520980D01*
X198766Y521064D01*
X198974Y521272D01*
X199099Y521605D01*
X199141Y521897D01*
G01X194401Y511895D02*
X191901D01*
Y512936D01*
X192026Y513270D01*
X192193Y513478D01*
X192526Y513561D01*
X192859Y513478D01*
X193068Y513228D01*
X193193Y512936D01*
Y511895D01*
G01Y512936D02*
X194401Y513561D01*
G01X192318Y515036D02*
X192068Y515286D01*
X191943Y515578D01*
X191901Y515911D01*
X191984Y516328D01*
X192193Y516620D01*
X192443Y516703D01*
X192693Y516661D01*
X192901Y516495D01*
X193318Y515661D01*
X193609Y515286D01*
X194026Y515036D01*
X194401Y514953D01*
Y516703D01*
G01Y518928D02*
X194359Y519220D01*
X194234Y519553D01*
X194026Y519761D01*
X193734Y519845D01*
X193443Y519761D01*
X193193Y519511D01*
X193068Y519136D01*
Y518720D01*
X192984Y518470D01*
X192776Y518261D01*
X192484Y518178D01*
X192193Y518303D01*
X191984Y518595D01*
X191901Y518928D01*
X191984Y519261D01*
X192193Y519553D01*
X192484Y519678D01*
X192776Y519595D01*
X192984Y519386D01*
X193068Y519136D01*
Y518720D01*
X193193Y518345D01*
X193443Y518095D01*
X193734Y518011D01*
X194026Y518095D01*
X194234Y518303D01*
X194359Y518636D01*
X194401Y518928D01*
G01X193359Y521236D02*
X193068Y521528D01*
X192901Y521778D01*
X192818Y522111D01*
X192901Y522403D01*
X193068Y522611D01*
X193318Y522778D01*
X193609Y522820D01*
X193859Y522778D01*
X194109Y522611D01*
X194318Y522361D01*
X194401Y522070D01*
X194318Y521736D01*
X194068Y521445D01*
X193693Y521278D01*
X193276Y521236D01*
X192734Y521320D01*
X192443Y521445D01*
X192151Y521653D01*
X191943Y521945D01*
X191901Y522236D01*
X191984Y522528D01*
X192193Y522736D01*
G01X201763Y599425D02*
X197763D01*
Y592025D01*
G01X209263Y591625D02*
Y595625D01*
X201863D01*
G01X197463Y587725D02*
Y591725D01*
X190063D01*
G01X205910Y579464D02*
Y581964D01*
X206951D01*
X207285Y581839D01*
X207493Y581672D01*
X207576Y581339D01*
X207493Y581006D01*
X207243Y580797D01*
X206951Y580672D01*
X205910D01*
G01X206951D02*
X207576Y579464D01*
G01X209843D02*
Y581964D01*
X209343Y581464D01*
G01Y579464D02*
X210343D01*
G01X212151Y581547D02*
X212401Y581797D01*
X212693Y581922D01*
X213026Y581964D01*
X213443Y581881D01*
X213735Y581672D01*
X213818Y581422D01*
X213776Y581172D01*
X213610Y580964D01*
X212776Y580547D01*
X212401Y580256D01*
X212151Y579839D01*
X212068Y579464D01*
X213818D01*
G01X215251Y581547D02*
X215501Y581797D01*
X215793Y581922D01*
X216126Y581964D01*
X216543Y581881D01*
X216835Y581672D01*
X216918Y581422D01*
X216876Y581172D01*
X216710Y580964D01*
X215876Y580547D01*
X215501Y580256D01*
X215251Y579839D01*
X215168Y579464D01*
X216918D01*
G01X218435Y579756D02*
X218726Y579547D01*
X219060Y579464D01*
X219393Y579547D01*
X219685Y579797D01*
X219893Y580172D01*
X219976Y580547D01*
Y581006D01*
X219893Y581381D01*
X219685Y581714D01*
X219435Y581881D01*
X219143Y581964D01*
X218810Y581881D01*
X218560Y581714D01*
X218393Y581464D01*
X218310Y581131D01*
X218393Y580839D01*
X218601Y580547D01*
X218851Y580381D01*
X219143Y580339D01*
X219476Y580422D01*
X219726Y580631D01*
X219976Y581006D01*
G01X209222Y583250D02*
Y587250D01*
X201822D01*
G01X189097Y581001D02*
Y585001D01*
X181697D01*
G01X180967Y597000D02*
Y599500D01*
X182008D01*
X182342Y599375D01*
X182550Y599208D01*
X182633Y598875D01*
X182550Y598542D01*
X182300Y598333D01*
X182008Y598208D01*
X180967D01*
G01X182008D02*
X182633Y597000D01*
G01X184900D02*
Y599500D01*
X184400Y599000D01*
G01Y597000D02*
X185400D01*
G01X187208Y599083D02*
X187458Y599333D01*
X187750Y599458D01*
X188083Y599500D01*
X188500Y599417D01*
X188792Y599208D01*
X188875Y598958D01*
X188833Y598708D01*
X188667Y598500D01*
X187833Y598083D01*
X187458Y597792D01*
X187208Y597375D01*
X187125Y597000D01*
X188875D01*
G01X190183Y597500D02*
X190433Y597208D01*
X190767Y597042D01*
X191142Y597000D01*
X191475Y597042D01*
X191808Y597250D01*
X192017Y597500D01*
X192058Y597750D01*
X191975Y598042D01*
X191683Y598250D01*
X191392Y598333D01*
X191017D01*
G01X191392D02*
X191642Y598458D01*
X191850Y598667D01*
X191933Y598917D01*
X191850Y599167D01*
X191642Y599375D01*
X191267Y599500D01*
X190892Y599458D01*
X190517Y599292D01*
G01X193283Y597500D02*
X193533Y597208D01*
X193867Y597042D01*
X194242Y597000D01*
X194575Y597042D01*
X194908Y597250D01*
X195117Y597500D01*
X195158Y597750D01*
X195075Y598042D01*
X194783Y598250D01*
X194492Y598333D01*
X194117D01*
G01X194492D02*
X194742Y598458D01*
X194950Y598667D01*
X195033Y598917D01*
X194950Y599167D01*
X194742Y599375D01*
X194367Y599500D01*
X193992Y599458D01*
X193617Y599292D01*
G01X196555Y578723D02*
Y582723D01*
X189155D01*
G01X181695Y589067D02*
Y585067D01*
X189095D01*
G01X173063Y581525D02*
X177063D01*
Y588925D01*
G01X177200Y581580D02*
X181200D01*
Y588980D01*
G01X195194Y557575D02*
X187394D01*
G01X188194D02*
X181794D01*
G01X216000Y563467D02*
X213500D01*
Y564508D01*
X213625Y564842D01*
X213792Y565050D01*
X214125Y565133D01*
X214458Y565050D01*
X214667Y564800D01*
X214792Y564508D01*
Y563467D01*
G01Y564508D02*
X216000Y565133D01*
G01Y567400D02*
X213500D01*
X214000Y566900D01*
G01X216000D02*
Y567900D01*
G01X213917Y569708D02*
X213667Y569958D01*
X213542Y570250D01*
X213500Y570583D01*
X213583Y571000D01*
X213792Y571292D01*
X214042Y571375D01*
X214292Y571333D01*
X214500Y571167D01*
X214917Y570333D01*
X215208Y569958D01*
X215625Y569708D01*
X216000Y569625D01*
Y571375D01*
G01X213917Y572808D02*
X213667Y573058D01*
X213542Y573350D01*
X213500Y573683D01*
X213583Y574100D01*
X213792Y574392D01*
X214042Y574475D01*
X214292Y574433D01*
X214500Y574267D01*
X214917Y573433D01*
X215208Y573058D01*
X215625Y572808D01*
X216000Y572725D01*
Y574475D01*
G01Y576700D02*
X215958Y576992D01*
X215833Y577325D01*
X215625Y577533D01*
X215333Y577617D01*
X215042Y577533D01*
X214792Y577283D01*
X214667Y576908D01*
Y576492D01*
X214583Y576242D01*
X214375Y576033D01*
X214083Y575950D01*
X213792Y576075D01*
X213583Y576367D01*
X213500Y576700D01*
X213583Y577033D01*
X213792Y577325D01*
X214083Y577450D01*
X214375Y577367D01*
X214583Y577158D01*
X214667Y576908D01*
Y576492D01*
X214792Y576117D01*
X215042Y575867D01*
X215333Y575783D01*
X215625Y575867D01*
X215833Y576075D01*
X215958Y576408D01*
X216000Y576700D01*
G01X214195Y555527D02*
X213945Y555652D01*
X213653Y555735D01*
X213320D01*
X212945Y555610D01*
X212653Y555402D01*
X212445Y555152D01*
X212278Y554735D01*
X212236Y554360D01*
X212320Y553985D01*
X212445Y553735D01*
X212695Y553485D01*
X212986Y553318D01*
X213278Y553235D01*
X213570D01*
X213861Y553318D01*
X214111Y553443D01*
X214320Y553610D01*
G01X215586Y554277D02*
X215878Y554568D01*
X216128Y554735D01*
X216461Y554818D01*
X216753Y554735D01*
X216961Y554568D01*
X217128Y554318D01*
X217170Y554027D01*
X217128Y553777D01*
X216961Y553527D01*
X216711Y553318D01*
X216420Y553235D01*
X216086Y553318D01*
X215795Y553568D01*
X215628Y553943D01*
X215586Y554360D01*
X215670Y554902D01*
X215795Y555193D01*
X216003Y555485D01*
X216295Y555693D01*
X216586Y555735D01*
X216878Y555652D01*
X217086Y555443D01*
G01X218686Y555318D02*
X218936Y555568D01*
X219228Y555693D01*
X219561Y555735D01*
X219978Y555652D01*
X220270Y555443D01*
X220353Y555193D01*
X220311Y554943D01*
X220145Y554735D01*
X219311Y554318D01*
X218936Y554027D01*
X218686Y553610D01*
X218603Y553235D01*
X220353D01*
G01X221661Y553735D02*
X221911Y553443D01*
X222245Y553277D01*
X222620Y553235D01*
X222953Y553277D01*
X223286Y553485D01*
X223495Y553735D01*
X223536Y553985D01*
X223453Y554277D01*
X223161Y554485D01*
X222870Y554568D01*
X222495D01*
G01X222870D02*
X223120Y554693D01*
X223328Y554902D01*
X223411Y555152D01*
X223328Y555402D01*
X223120Y555610D01*
X222745Y555735D01*
X222370Y555693D01*
X221995Y555527D01*
G01X214223Y560554D02*
X213973Y560679D01*
X213681Y560762D01*
X213348D01*
X212973Y560637D01*
X212681Y560429D01*
X212473Y560179D01*
X212306Y559762D01*
X212264Y559387D01*
X212348Y559012D01*
X212473Y558762D01*
X212723Y558512D01*
X213014Y558345D01*
X213306Y558262D01*
X213598D01*
X213889Y558345D01*
X214139Y558470D01*
X214348Y558637D01*
G01X215614Y559304D02*
X215906Y559595D01*
X216156Y559762D01*
X216489Y559845D01*
X216781Y559762D01*
X216989Y559595D01*
X217156Y559345D01*
X217198Y559054D01*
X217156Y558804D01*
X216989Y558554D01*
X216739Y558345D01*
X216448Y558262D01*
X216114Y558345D01*
X215823Y558595D01*
X215656Y558970D01*
X215614Y559387D01*
X215698Y559929D01*
X215823Y560220D01*
X216031Y560512D01*
X216323Y560720D01*
X216614Y560762D01*
X216906Y560679D01*
X217114Y560470D01*
G01X218714Y560345D02*
X218964Y560595D01*
X219256Y560720D01*
X219589Y560762D01*
X220006Y560679D01*
X220298Y560470D01*
X220381Y560220D01*
X220339Y559970D01*
X220173Y559762D01*
X219339Y559345D01*
X218964Y559054D01*
X218714Y558637D01*
X218631Y558262D01*
X220381D01*
G01X221814Y560345D02*
X222064Y560595D01*
X222356Y560720D01*
X222689Y560762D01*
X223106Y560679D01*
X223398Y560470D01*
X223481Y560220D01*
X223439Y559970D01*
X223273Y559762D01*
X222439Y559345D01*
X222064Y559054D01*
X221814Y558637D01*
X221731Y558262D01*
X223481D01*
G01X201000Y602967D02*
X198500D01*
Y604008D01*
X198625Y604342D01*
X198792Y604550D01*
X199125Y604633D01*
X199458Y604550D01*
X199667Y604300D01*
X199792Y604008D01*
Y602967D01*
G01Y604008D02*
X201000Y604633D01*
G01Y606900D02*
X198500D01*
X199000Y606400D01*
G01X201000D02*
Y607400D01*
G01X198917Y609208D02*
X198667Y609458D01*
X198542Y609750D01*
X198500Y610083D01*
X198583Y610500D01*
X198792Y610792D01*
X199042Y610875D01*
X199292Y610833D01*
X199500Y610667D01*
X199917Y609833D01*
X200208Y609458D01*
X200625Y609208D01*
X201000Y609125D01*
Y610875D01*
G01X198917Y612308D02*
X198667Y612558D01*
X198542Y612850D01*
X198500Y613183D01*
X198583Y613600D01*
X198792Y613892D01*
X199042Y613975D01*
X199292Y613933D01*
X199500Y613767D01*
X199917Y612933D01*
X200208Y612558D01*
X200625Y612308D01*
X201000Y612225D01*
Y613975D01*
G01Y616700D02*
X198500D01*
X200292Y615158D01*
Y617242D01*
G01X203243Y600269D02*
Y602769D01*
X204284D01*
X204618Y602644D01*
X204826Y602477D01*
X204909Y602144D01*
X204826Y601811D01*
X204576Y601602D01*
X204284Y601477D01*
X203243D01*
G01X204284D02*
X204909Y600269D01*
G01X207176D02*
Y602769D01*
X206676Y602269D01*
G01Y600269D02*
X207676D01*
G01X209484Y602352D02*
X209734Y602602D01*
X210026Y602727D01*
X210359Y602769D01*
X210776Y602686D01*
X211068Y602477D01*
X211151Y602227D01*
X211109Y601977D01*
X210943Y601769D01*
X210109Y601352D01*
X209734Y601061D01*
X209484Y600644D01*
X209401Y600269D01*
X211151D01*
G01X212584Y602352D02*
X212834Y602602D01*
X213126Y602727D01*
X213459Y602769D01*
X213876Y602686D01*
X214168Y602477D01*
X214251Y602227D01*
X214209Y601977D01*
X214043Y601769D01*
X213209Y601352D01*
X212834Y601061D01*
X212584Y600644D01*
X212501Y600269D01*
X214251D01*
G01X215559Y600644D02*
X215809Y600436D01*
X216101Y600311D01*
X216476Y600269D01*
X216851Y600352D01*
X217143Y600519D01*
X217351Y600811D01*
X217393Y601144D01*
X217309Y601477D01*
X217101Y601686D01*
X216809Y601852D01*
X216518Y601894D01*
X216226Y601852D01*
X215851Y601686D01*
X215976Y602769D01*
X217101D01*
G01X181230Y604725D02*
Y607225D01*
X182271D01*
X182605Y607100D01*
X182813Y606933D01*
X182896Y606600D01*
X182813Y606267D01*
X182563Y606058D01*
X182271Y605933D01*
X181230D01*
G01X182271D02*
X182896Y604725D01*
G01X185163D02*
Y607225D01*
X184663Y606725D01*
G01Y604725D02*
X185663D01*
G01X187471Y606808D02*
X187721Y607058D01*
X188013Y607183D01*
X188346Y607225D01*
X188763Y607142D01*
X189055Y606933D01*
X189138Y606683D01*
X189096Y606433D01*
X188930Y606225D01*
X188096Y605808D01*
X187721Y605517D01*
X187471Y605100D01*
X187388Y604725D01*
X189138D01*
G01X190571Y606808D02*
X190821Y607058D01*
X191113Y607183D01*
X191446Y607225D01*
X191863Y607142D01*
X192155Y606933D01*
X192238Y606683D01*
X192196Y606433D01*
X192030Y606225D01*
X191196Y605808D01*
X190821Y605517D01*
X190571Y605100D01*
X190488Y604725D01*
X192238D01*
G01X194380D02*
X194463Y605267D01*
X194588Y605725D01*
X194755Y606142D01*
X194963Y606600D01*
X195296Y607225D01*
X193630D01*
G01X207113Y609442D02*
Y611942D01*
X208154D01*
X208488Y611817D01*
X208696Y611650D01*
X208779Y611317D01*
X208696Y610984D01*
X208446Y610775D01*
X208154Y610650D01*
X207113D01*
G01X208154D02*
X208779Y609442D01*
G01X211546D02*
Y611942D01*
X210004Y610150D01*
X212088D01*
G01X213229Y609942D02*
X213479Y609650D01*
X213813Y609484D01*
X214188Y609442D01*
X214521Y609484D01*
X214854Y609692D01*
X215063Y609942D01*
X215104Y610192D01*
X215021Y610484D01*
X214729Y610692D01*
X214438Y610775D01*
X214063D01*
G01X214438D02*
X214688Y610900D01*
X214896Y611109D01*
X214979Y611359D01*
X214896Y611609D01*
X214688Y611817D01*
X214313Y611942D01*
X213938Y611900D01*
X213563Y611734D01*
G01X217163Y609442D02*
X217246Y609984D01*
X217371Y610442D01*
X217538Y610859D01*
X217746Y611317D01*
X218079Y611942D01*
X216413D01*
G01X218449Y621417D02*
Y625417D01*
X211049D01*
G01X207113Y605742D02*
Y608242D01*
X208154D01*
X208488Y608117D01*
X208696Y607950D01*
X208779Y607617D01*
X208696Y607284D01*
X208446Y607075D01*
X208154Y606950D01*
X207113D01*
G01X208154D02*
X208779Y605742D01*
G01X211546D02*
Y608242D01*
X210004Y606450D01*
X212088D01*
G01X213229Y606242D02*
X213479Y605950D01*
X213813Y605784D01*
X214188Y605742D01*
X214521Y605784D01*
X214854Y605992D01*
X215063Y606242D01*
X215104Y606492D01*
X215021Y606784D01*
X214729Y606992D01*
X214438Y607075D01*
X214063D01*
G01X214438D02*
X214688Y607200D01*
X214896Y607409D01*
X214979Y607659D01*
X214896Y607909D01*
X214688Y608117D01*
X214313Y608242D01*
X213938Y608200D01*
X213563Y608034D01*
G01X216538Y606034D02*
X216829Y605825D01*
X217163Y605742D01*
X217496Y605825D01*
X217788Y606075D01*
X217996Y606450D01*
X218079Y606825D01*
Y607284D01*
X217996Y607659D01*
X217788Y607992D01*
X217538Y608159D01*
X217246Y608242D01*
X216913Y608159D01*
X216663Y607992D01*
X216496Y607742D01*
X216413Y607409D01*
X216496Y607117D01*
X216704Y606825D01*
X216954Y606659D01*
X217246Y606617D01*
X217579Y606700D01*
X217829Y606909D01*
X218079Y607284D01*
G01X218449Y616917D02*
Y620917D01*
X211049D01*
G01X211052Y642771D02*
Y645271D01*
X212093D01*
X212427Y645146D01*
X212635Y644979D01*
X212718Y644646D01*
X212635Y644313D01*
X212385Y644104D01*
X212093Y643979D01*
X211052D01*
G01X212093D02*
X212718Y642771D01*
G01X215485D02*
Y645271D01*
X213943Y643479D01*
X216027D01*
G01X218585Y642771D02*
Y645271D01*
X217043Y643479D01*
X219127D01*
G01X221185Y642771D02*
Y645271D01*
X220685Y644771D01*
G01Y642771D02*
X221685D01*
G01X211049Y635417D02*
Y631417D01*
X218449D01*
G01X170788Y620053D02*
Y622553D01*
X171829D01*
X172163Y622428D01*
X172371Y622261D01*
X172454Y621928D01*
X172371Y621595D01*
X172121Y621386D01*
X171829Y621261D01*
X170788D01*
G01X171829D02*
X172454Y620053D01*
G01X175221D02*
Y622553D01*
X173679Y620761D01*
X175763D01*
G01X178321Y620053D02*
Y622553D01*
X176779Y620761D01*
X178863D01*
G01X181421Y620053D02*
Y622553D01*
X179879Y620761D01*
X181963D01*
G01X183199Y623417D02*
Y619417D01*
X190599D01*
G01X174311Y625748D02*
Y628248D01*
X175352D01*
X175686Y628123D01*
X175894Y627956D01*
X175977Y627623D01*
X175894Y627290D01*
X175644Y627081D01*
X175352Y626956D01*
X174311D01*
G01X175352D02*
X175977Y625748D01*
G01X178744D02*
Y628248D01*
X177202Y626456D01*
X179286D01*
G01X181844Y625748D02*
Y628248D01*
X180302Y626456D01*
X182386D01*
G01X183527Y626123D02*
X183777Y625915D01*
X184069Y625790D01*
X184444Y625748D01*
X184819Y625831D01*
X185111Y625998D01*
X185319Y626290D01*
X185361Y626623D01*
X185277Y626956D01*
X185069Y627165D01*
X184777Y627331D01*
X184486Y627373D01*
X184194Y627331D01*
X183819Y627165D01*
X183944Y628248D01*
X185069D01*
G01X186649Y624217D02*
X190649D01*
Y631617D01*
G01X202493Y613587D02*
Y616087D01*
X203534D01*
X203868Y615962D01*
X204076Y615795D01*
X204159Y615462D01*
X204076Y615129D01*
X203826Y614920D01*
X203534Y614795D01*
X202493D01*
G01X203534D02*
X204159Y613587D01*
G01X206926D02*
Y616087D01*
X205384Y614295D01*
X207468D01*
G01X210026Y613587D02*
Y616087D01*
X208484Y614295D01*
X210568D01*
G01X211834Y614629D02*
X212126Y614920D01*
X212376Y615087D01*
X212709Y615170D01*
X213001Y615087D01*
X213209Y614920D01*
X213376Y614670D01*
X213418Y614379D01*
X213376Y614129D01*
X213209Y613879D01*
X212959Y613670D01*
X212668Y613587D01*
X212334Y613670D01*
X212043Y613920D01*
X211876Y614295D01*
X211834Y614712D01*
X211918Y615254D01*
X212043Y615545D01*
X212251Y615837D01*
X212543Y616045D01*
X212834Y616087D01*
X213126Y616004D01*
X213334Y615795D01*
G01X199102Y622496D02*
Y618496D01*
X206502D01*
G01X187086Y636147D02*
X186753Y636189D01*
X186461Y636355D01*
X186211Y636605D01*
X186044Y636897D01*
X185961Y637230D01*
Y637564D01*
X186044Y637897D01*
X186211Y638189D01*
X186461Y638439D01*
X186753Y638605D01*
X187086Y638647D01*
X187419Y638605D01*
X187711Y638439D01*
X187961Y638189D01*
X188128Y637897D01*
X188211Y637564D01*
Y637230D01*
X188128Y636897D01*
X187961Y636605D01*
X187711Y636355D01*
X187419Y636189D01*
X187086Y636147D01*
G01X187419Y636814D02*
X187919Y636147D01*
G01X190103D02*
X190186Y636689D01*
X190311Y637147D01*
X190478Y637564D01*
X190686Y638022D01*
X191019Y638647D01*
X189353D01*
G01X192578Y636439D02*
X192869Y636230D01*
X193203Y636147D01*
X193536Y636230D01*
X193828Y636480D01*
X194036Y636855D01*
X194119Y637230D01*
Y637689D01*
X194036Y638064D01*
X193828Y638397D01*
X193578Y638564D01*
X193286Y638647D01*
X192953Y638564D01*
X192703Y638397D01*
X192536Y638147D01*
X192453Y637814D01*
X192536Y637522D01*
X192744Y637230D01*
X192994Y637064D01*
X193286Y637022D01*
X193619Y637105D01*
X193869Y637314D01*
X194119Y637689D01*
G01X210549Y641617D02*
X199149D01*
G01X210549Y628217D02*
Y641617D01*
G01X199149Y628217D02*
X210549D01*
G01X199149Y641617D02*
Y628217D01*
G01X195570Y608923D02*
X193070D01*
Y609757D01*
X193195Y610090D01*
X193362Y610340D01*
X193612Y610548D01*
X193903Y610715D01*
X194320Y610757D01*
X194737Y610715D01*
X195028Y610548D01*
X195278Y610340D01*
X195445Y610090D01*
X195570Y609757D01*
Y608923D01*
G01Y612940D02*
X193070D01*
X193570Y612440D01*
G01X195570D02*
Y613440D01*
G01X195070Y615123D02*
X195362Y615373D01*
X195528Y615707D01*
X195570Y616082D01*
X195528Y616415D01*
X195320Y616748D01*
X195070Y616957D01*
X194820Y616998D01*
X194528Y616915D01*
X194320Y616623D01*
X194237Y616332D01*
Y615957D01*
G01Y616332D02*
X194112Y616582D01*
X193903Y616790D01*
X193653Y616873D01*
X193403Y616790D01*
X193195Y616582D01*
X193070Y616207D01*
X193112Y615832D01*
X193278Y615457D01*
G01X198249Y634417D02*
Y618317D01*
G01X191249Y634417D02*
X198249D01*
G01X191249Y618317D02*
Y634417D01*
G01X198249Y618317D02*
X191249D01*
G01X182767Y603292D02*
X182517Y603417D01*
X182225Y603500D01*
X181892D01*
X181517Y603375D01*
X181225Y603167D01*
X181017Y602917D01*
X180850Y602500D01*
X180808Y602125D01*
X180892Y601750D01*
X181017Y601500D01*
X181267Y601250D01*
X181558Y601083D01*
X181850Y601000D01*
X182142D01*
X182433Y601083D01*
X182683Y601208D01*
X182892Y601375D01*
G01X184158Y602042D02*
X184450Y602333D01*
X184700Y602500D01*
X185033Y602583D01*
X185325Y602500D01*
X185533Y602333D01*
X185700Y602083D01*
X185742Y601792D01*
X185700Y601542D01*
X185533Y601292D01*
X185283Y601083D01*
X184992Y601000D01*
X184658Y601083D01*
X184367Y601333D01*
X184200Y601708D01*
X184158Y602125D01*
X184242Y602667D01*
X184367Y602958D01*
X184575Y603250D01*
X184867Y603458D01*
X185158Y603500D01*
X185450Y603417D01*
X185658Y603208D01*
G01X187258Y603083D02*
X187508Y603333D01*
X187800Y603458D01*
X188133Y603500D01*
X188550Y603417D01*
X188842Y603208D01*
X188925Y602958D01*
X188883Y602708D01*
X188717Y602500D01*
X187883Y602083D01*
X187508Y601792D01*
X187258Y601375D01*
X187175Y601000D01*
X188925D01*
G01X191150Y603500D02*
X190817Y603417D01*
X190567Y603208D01*
X190400Y602958D01*
X190275Y602625D01*
X190233Y602250D01*
X190275Y601875D01*
X190400Y601542D01*
X190567Y601292D01*
X190817Y601083D01*
X191150Y601000D01*
X191483Y601083D01*
X191733Y601292D01*
X191900Y601542D01*
X192025Y601875D01*
X192067Y602250D01*
X192025Y602625D01*
X191900Y602958D01*
X191733Y603208D01*
X191483Y603417D01*
X191150Y603500D01*
G01X190108Y645175D02*
X189858Y645300D01*
X189566Y645383D01*
X189233D01*
X188858Y645258D01*
X188566Y645050D01*
X188358Y644800D01*
X188191Y644383D01*
X188149Y644008D01*
X188233Y643633D01*
X188358Y643383D01*
X188608Y643133D01*
X188899Y642966D01*
X189191Y642883D01*
X189483D01*
X189774Y642966D01*
X190024Y643091D01*
X190233Y643258D01*
G01X191499Y644966D02*
X191749Y645216D01*
X192041Y645341D01*
X192374Y645383D01*
X192791Y645300D01*
X193083Y645091D01*
X193166Y644841D01*
X193124Y644591D01*
X192958Y644383D01*
X192124Y643966D01*
X191749Y643675D01*
X191499Y643258D01*
X191416Y642883D01*
X193166D01*
G01X195391D02*
Y645383D01*
X194891Y644883D01*
G01Y642883D02*
X195891D01*
G01X198408D02*
X198491Y643425D01*
X198616Y643883D01*
X198783Y644300D01*
X198991Y644758D01*
X199324Y645383D01*
X197658D01*
G01X181986Y660847D02*
Y663347D01*
X183027D01*
X183361Y663222D01*
X183569Y663055D01*
X183652Y662722D01*
X183569Y662389D01*
X183319Y662180D01*
X183027Y662055D01*
X181986D01*
G01X183027D02*
X183652Y660847D01*
G01X186419D02*
Y663347D01*
X184877Y661555D01*
X186961D01*
G01X188102Y661347D02*
X188352Y661055D01*
X188686Y660889D01*
X189061Y660847D01*
X189394Y660889D01*
X189727Y661097D01*
X189936Y661347D01*
X189977Y661597D01*
X189894Y661889D01*
X189602Y662097D01*
X189311Y662180D01*
X188936D01*
G01X189311D02*
X189561Y662305D01*
X189769Y662514D01*
X189852Y662764D01*
X189769Y663014D01*
X189561Y663222D01*
X189186Y663347D01*
X188811Y663305D01*
X188436Y663139D01*
G01X191327Y661889D02*
X191619Y662180D01*
X191869Y662347D01*
X192202Y662430D01*
X192494Y662347D01*
X192702Y662180D01*
X192869Y661930D01*
X192911Y661639D01*
X192869Y661389D01*
X192702Y661139D01*
X192452Y660930D01*
X192161Y660847D01*
X191827Y660930D01*
X191536Y661180D01*
X191369Y661555D01*
X191327Y661972D01*
X191411Y662514D01*
X191536Y662805D01*
X191744Y663097D01*
X192036Y663305D01*
X192327Y663347D01*
X192619Y663264D01*
X192827Y663055D01*
G01X208200Y648000D02*
Y652000D01*
X200800D01*
G01X170916Y666589D02*
Y669089D01*
X171957D01*
X172291Y668964D01*
X172499Y668797D01*
X172582Y668464D01*
X172499Y668131D01*
X172249Y667922D01*
X171957Y667797D01*
X170916D01*
G01X171957D02*
X172582Y666589D01*
G01X175349D02*
Y669089D01*
X173807Y667297D01*
X175891D01*
G01X178449Y666589D02*
Y669089D01*
X176907Y667297D01*
X178991D01*
G01X180257Y668672D02*
X180507Y668922D01*
X180799Y669047D01*
X181132Y669089D01*
X181549Y669006D01*
X181841Y668797D01*
X181924Y668547D01*
X181882Y668297D01*
X181716Y668089D01*
X180882Y667672D01*
X180507Y667381D01*
X180257Y666964D01*
X180174Y666589D01*
X181924D01*
G01X192099Y665589D02*
Y669589D01*
X184699D01*
G01X213649Y706717D02*
X221649D01*
Y689117D01*
X213649D01*
Y706717D01*
G01X211949Y688917D02*
X206449D01*
G01X211949Y696917D02*
Y688917D01*
G01X194349D02*
Y696917D01*
G01X199849Y688917D02*
X194349D01*
G01X171949Y690417D02*
X174049Y688617D01*
X171949Y686417D01*
G01X171849Y682817D02*
X191049D01*
Y694017D01*
X171849D01*
Y682817D01*
X172249D01*
G01X216349Y668417D02*
X214249Y670217D01*
X216349Y672417D01*
G01X216449Y676017D02*
X197249D01*
Y664817D01*
X216449D01*
Y676017D01*
X216049D01*
G01X172666Y672981D02*
X172416Y673106D01*
X172124Y673189D01*
X171791D01*
X171416Y673064D01*
X171124Y672856D01*
X170916Y672606D01*
X170749Y672189D01*
X170707Y671814D01*
X170791Y671439D01*
X170916Y671189D01*
X171166Y670939D01*
X171457Y670772D01*
X171749Y670689D01*
X172041D01*
X172332Y670772D01*
X172582Y670897D01*
X172791Y671064D01*
G01X174057Y672772D02*
X174307Y673022D01*
X174599Y673147D01*
X174932Y673189D01*
X175349Y673106D01*
X175641Y672897D01*
X175724Y672647D01*
X175682Y672397D01*
X175516Y672189D01*
X174682Y671772D01*
X174307Y671481D01*
X174057Y671064D01*
X173974Y670689D01*
X175724D01*
G01X177949D02*
Y673189D01*
X177449Y672689D01*
G01Y670689D02*
X178449D01*
G01X181049D02*
X181341Y670731D01*
X181674Y670856D01*
X181882Y671064D01*
X181966Y671356D01*
X181882Y671647D01*
X181632Y671897D01*
X181257Y672022D01*
X180841D01*
X180591Y672106D01*
X180382Y672314D01*
X180299Y672606D01*
X180424Y672897D01*
X180716Y673106D01*
X181049Y673189D01*
X181382Y673106D01*
X181674Y672897D01*
X181799Y672606D01*
X181716Y672314D01*
X181507Y672106D01*
X181257Y672022D01*
X180841D01*
X180466Y671897D01*
X180216Y671647D01*
X180132Y671356D01*
X180216Y671064D01*
X180424Y670856D01*
X180757Y670731D01*
X181049Y670689D01*
G01X219000Y708517D02*
X216500D01*
Y709558D01*
X216625Y709892D01*
X216792Y710100D01*
X217125Y710183D01*
X217458Y710100D01*
X217667Y709850D01*
X217792Y709558D01*
Y708517D01*
G01Y709558D02*
X219000Y710183D01*
G01Y712950D02*
X216500D01*
X218292Y711408D01*
Y713492D01*
G01X216917Y714758D02*
X216667Y715008D01*
X216542Y715300D01*
X216500Y715633D01*
X216583Y716050D01*
X216792Y716342D01*
X217042Y716425D01*
X217292Y716383D01*
X217500Y716217D01*
X217917Y715383D01*
X218208Y715008D01*
X218625Y714758D01*
X219000Y714675D01*
Y716425D01*
G01Y718650D02*
X218958Y718942D01*
X218833Y719275D01*
X218625Y719483D01*
X218333Y719567D01*
X218042Y719483D01*
X217792Y719233D01*
X217667Y718858D01*
Y718442D01*
X217583Y718192D01*
X217375Y717983D01*
X217083Y717900D01*
X216792Y718025D01*
X216583Y718317D01*
X216500Y718650D01*
X216583Y718983D01*
X216792Y719275D01*
X217083Y719400D01*
X217375Y719317D01*
X217583Y719108D01*
X217667Y718858D01*
Y718442D01*
X217792Y718067D01*
X218042Y717817D01*
X218333Y717733D01*
X218625Y717817D01*
X218833Y718025D01*
X218958Y718358D01*
X219000Y718650D01*
G01X196017Y723500D02*
Y726000D01*
X197058D01*
X197392Y725875D01*
X197600Y725708D01*
X197683Y725375D01*
X197600Y725042D01*
X197350Y724833D01*
X197058Y724708D01*
X196017D01*
G01X197058D02*
X197683Y723500D01*
G01X200450D02*
Y726000D01*
X198908Y724208D01*
X200992D01*
G01X202133Y724000D02*
X202383Y723708D01*
X202717Y723542D01*
X203092Y723500D01*
X203425Y723542D01*
X203758Y723750D01*
X203967Y724000D01*
X204008Y724250D01*
X203925Y724542D01*
X203633Y724750D01*
X203342Y724833D01*
X202967D01*
G01X203342D02*
X203592Y724958D01*
X203800Y725167D01*
X203883Y725417D01*
X203800Y725667D01*
X203592Y725875D01*
X203217Y726000D01*
X202842Y725958D01*
X202467Y725792D01*
G01X206150Y726000D02*
X205817Y725917D01*
X205567Y725708D01*
X205400Y725458D01*
X205275Y725125D01*
X205233Y724750D01*
X205275Y724375D01*
X205400Y724042D01*
X205567Y723792D01*
X205817Y723583D01*
X206150Y723500D01*
X206483Y723583D01*
X206733Y723792D01*
X206900Y724042D01*
X207025Y724375D01*
X207067Y724750D01*
X207025Y725125D01*
X206900Y725458D01*
X206733Y725708D01*
X206483Y725917D01*
X206150Y726000D01*
G01X189849Y703417D02*
Y711417D01*
X207449D01*
Y703417D01*
X189849D01*
G01X211208Y733267D02*
X211083Y733017D01*
X211000Y732725D01*
Y732392D01*
X211125Y732017D01*
X211333Y731725D01*
X211583Y731517D01*
X212000Y731350D01*
X212375Y731308D01*
X212750Y731392D01*
X213000Y731517D01*
X213250Y731767D01*
X213417Y732058D01*
X213500Y732350D01*
Y732642D01*
X213417Y732933D01*
X213292Y733183D01*
X213125Y733392D01*
G01X211417Y734658D02*
X211167Y734908D01*
X211042Y735200D01*
X211000Y735533D01*
X211083Y735950D01*
X211292Y736242D01*
X211542Y736325D01*
X211792Y736283D01*
X212000Y736117D01*
X212417Y735283D01*
X212708Y734908D01*
X213125Y734658D01*
X213500Y734575D01*
Y736325D01*
G01Y738550D02*
X211000D01*
X211500Y738050D01*
G01X213500D02*
Y739050D01*
G01Y742150D02*
X211000D01*
X212792Y740608D01*
Y742692D01*
G01X178267Y715292D02*
X178017Y715417D01*
X177725Y715500D01*
X177392D01*
X177017Y715375D01*
X176725Y715167D01*
X176517Y714917D01*
X176350Y714500D01*
X176308Y714125D01*
X176392Y713750D01*
X176517Y713500D01*
X176767Y713250D01*
X177058Y713083D01*
X177350Y713000D01*
X177642D01*
X177933Y713083D01*
X178183Y713208D01*
X178392Y713375D01*
G01X179658Y715083D02*
X179908Y715333D01*
X180200Y715458D01*
X180533Y715500D01*
X180950Y715417D01*
X181242Y715208D01*
X181325Y714958D01*
X181283Y714708D01*
X181117Y714500D01*
X180283Y714083D01*
X179908Y713792D01*
X179658Y713375D01*
X179575Y713000D01*
X181325D01*
G01X183550D02*
Y715500D01*
X183050Y715000D01*
G01Y713000D02*
X184050D01*
G01X185733Y713500D02*
X185983Y713208D01*
X186317Y713042D01*
X186692Y713000D01*
X187025Y713042D01*
X187358Y713250D01*
X187567Y713500D01*
X187608Y713750D01*
X187525Y714042D01*
X187233Y714250D01*
X186942Y714333D01*
X186567D01*
G01X186942D02*
X187192Y714458D01*
X187400Y714667D01*
X187483Y714917D01*
X187400Y715167D01*
X187192Y715375D01*
X186817Y715500D01*
X186442Y715458D01*
X186067Y715292D01*
G01X197416Y717709D02*
X197166Y717834D01*
X196874Y717917D01*
X196541D01*
X196166Y717792D01*
X195874Y717584D01*
X195666Y717334D01*
X195499Y716917D01*
X195457Y716542D01*
X195541Y716167D01*
X195666Y715917D01*
X195916Y715667D01*
X196207Y715500D01*
X196499Y715417D01*
X196791D01*
X197082Y715500D01*
X197332Y715625D01*
X197541Y715792D01*
G01X198807Y717500D02*
X199057Y717750D01*
X199349Y717875D01*
X199682Y717917D01*
X200099Y717834D01*
X200391Y717625D01*
X200474Y717375D01*
X200432Y717125D01*
X200266Y716917D01*
X199432Y716500D01*
X199057Y716209D01*
X198807Y715792D01*
X198724Y715417D01*
X200474D01*
G01X202699D02*
Y717917D01*
X202199Y717417D01*
G01Y715417D02*
X203199D01*
G01X205799Y717917D02*
X205466Y717834D01*
X205216Y717625D01*
X205049Y717375D01*
X204924Y717042D01*
X204882Y716667D01*
X204924Y716292D01*
X205049Y715959D01*
X205216Y715709D01*
X205466Y715500D01*
X205799Y715417D01*
X206132Y715500D01*
X206382Y715709D01*
X206549Y715959D01*
X206674Y716292D01*
X206716Y716667D01*
X206674Y717042D01*
X206549Y717375D01*
X206382Y717625D01*
X206132Y717834D01*
X205799Y717917D01*
G01X206449Y696917D02*
X211949D01*
G01X194349D02*
X199849D01*
G01X213708Y745767D02*
X213583Y745517D01*
X213500Y745225D01*
Y744892D01*
X213625Y744517D01*
X213833Y744225D01*
X214083Y744017D01*
X214500Y743850D01*
X214875Y743808D01*
X215250Y743892D01*
X215500Y744017D01*
X215750Y744267D01*
X215917Y744558D01*
X216000Y744850D01*
Y745142D01*
X215917Y745433D01*
X215792Y745683D01*
X215625Y745892D01*
G01X213917Y747158D02*
X213667Y747408D01*
X213542Y747700D01*
X213500Y748033D01*
X213583Y748450D01*
X213792Y748742D01*
X214042Y748825D01*
X214292Y748783D01*
X214500Y748617D01*
X214917Y747783D01*
X215208Y747408D01*
X215625Y747158D01*
X216000Y747075D01*
Y748825D01*
G01Y751050D02*
X213500D01*
X214000Y750550D01*
G01X216000D02*
Y751550D01*
G01X214958Y753358D02*
X214667Y753650D01*
X214500Y753900D01*
X214417Y754233D01*
X214500Y754525D01*
X214667Y754733D01*
X214917Y754900D01*
X215208Y754942D01*
X215458Y754900D01*
X215708Y754733D01*
X215917Y754483D01*
X216000Y754192D01*
X215917Y753858D01*
X215667Y753567D01*
X215292Y753400D01*
X214875Y753358D01*
X214333Y753442D01*
X214042Y753567D01*
X213750Y753775D01*
X213542Y754067D01*
X213500Y754358D01*
X213583Y754650D01*
X213792Y754858D01*
G01X197767Y721792D02*
X197517Y721917D01*
X197225Y722000D01*
X196892D01*
X196517Y721875D01*
X196225Y721667D01*
X196017Y721417D01*
X195850Y721000D01*
X195808Y720625D01*
X195892Y720250D01*
X196017Y720000D01*
X196267Y719750D01*
X196558Y719583D01*
X196850Y719500D01*
X197142D01*
X197433Y719583D01*
X197683Y719708D01*
X197892Y719875D01*
G01X199158Y721583D02*
X199408Y721833D01*
X199700Y721958D01*
X200033Y722000D01*
X200450Y721917D01*
X200742Y721708D01*
X200825Y721458D01*
X200783Y721208D01*
X200617Y721000D01*
X199783Y720583D01*
X199408Y720292D01*
X199158Y719875D01*
X199075Y719500D01*
X200825D01*
G01X203050Y722000D02*
X202717Y721917D01*
X202467Y721708D01*
X202300Y721458D01*
X202175Y721125D01*
X202133Y720750D01*
X202175Y720375D01*
X202300Y720042D01*
X202467Y719792D01*
X202717Y719583D01*
X203050Y719500D01*
X203383Y719583D01*
X203633Y719792D01*
X203800Y720042D01*
X203925Y720375D01*
X203967Y720750D01*
X203925Y721125D01*
X203800Y721458D01*
X203633Y721708D01*
X203383Y721917D01*
X203050Y722000D01*
G01X205442Y719792D02*
X205733Y719583D01*
X206067Y719500D01*
X206400Y719583D01*
X206692Y719833D01*
X206900Y720208D01*
X206983Y720583D01*
Y721042D01*
X206900Y721417D01*
X206692Y721750D01*
X206442Y721917D01*
X206150Y722000D01*
X205817Y721917D01*
X205567Y721750D01*
X205400Y721500D01*
X205317Y721167D01*
X205400Y720875D01*
X205608Y720583D01*
X205858Y720417D01*
X206150Y720375D01*
X206483Y720458D01*
X206733Y720667D01*
X206983Y721042D01*
G01X186179Y818378D02*
X183679D01*
Y819962D01*
G01X184887Y819378D02*
Y818378D01*
G01X183679Y821437D02*
X186179D01*
Y823103D01*
G01Y826203D02*
Y824537D01*
X183679D01*
Y826203D01*
G01X184887Y825537D02*
Y824537D01*
G01X186179Y827553D02*
X183679D01*
Y828387D01*
X183804Y828720D01*
X183971Y828970D01*
X184221Y829178D01*
X184512Y829345D01*
X184929Y829387D01*
X185346Y829345D01*
X185637Y829178D01*
X185887Y828970D01*
X186054Y828720D01*
X186179Y828387D01*
Y827553D01*
G01X184096Y830778D02*
X183846Y831028D01*
X183721Y831320D01*
X183679Y831653D01*
X183762Y832070D01*
X183971Y832362D01*
X184221Y832445D01*
X184471Y832403D01*
X184679Y832237D01*
X185096Y831403D01*
X185387Y831028D01*
X185804Y830778D01*
X186179Y830695D01*
Y832445D01*
G01X189891Y818809D02*
Y830009D01*
X198691D01*
Y818809D01*
X189891D01*
G01X212234Y947717D02*
X209734D01*
Y948758D01*
X209859Y949092D01*
X210026Y949300D01*
X210359Y949383D01*
X210692Y949300D01*
X210901Y949050D01*
X211026Y948758D01*
Y947717D01*
G01Y948758D02*
X212234Y949383D01*
G01Y951650D02*
X209734D01*
X210234Y951150D01*
G01X212234D02*
Y952150D01*
G01X211942Y954042D02*
X212151Y954333D01*
X212234Y954667D01*
X212151Y955000D01*
X211901Y955292D01*
X211526Y955500D01*
X211151Y955583D01*
X210692D01*
X210317Y955500D01*
X209984Y955292D01*
X209817Y955042D01*
X209734Y954750D01*
X209817Y954417D01*
X209984Y954167D01*
X210234Y954000D01*
X210567Y953917D01*
X210859Y954000D01*
X211151Y954208D01*
X211317Y954458D01*
X211359Y954750D01*
X211276Y955083D01*
X211067Y955333D01*
X210692Y955583D01*
G01X212234Y957767D02*
X211692Y957850D01*
X211234Y957975D01*
X210817Y958142D01*
X210359Y958350D01*
X209734Y958683D01*
Y957017D01*
G01X208766Y1071873D02*
Y1074373D01*
X209807D01*
X210141Y1074248D01*
X210349Y1074081D01*
X210432Y1073748D01*
X210349Y1073415D01*
X210099Y1073206D01*
X209807Y1073081D01*
X208766D01*
G01X209807D02*
X210432Y1071873D01*
G01X212699D02*
Y1074373D01*
X212199Y1073873D01*
G01Y1071873D02*
X213199D01*
G01X215007Y1072915D02*
X215299Y1073206D01*
X215549Y1073373D01*
X215882Y1073456D01*
X216174Y1073373D01*
X216382Y1073206D01*
X216549Y1072956D01*
X216591Y1072665D01*
X216549Y1072415D01*
X216382Y1072165D01*
X216132Y1071956D01*
X215841Y1071873D01*
X215507Y1071956D01*
X215216Y1072206D01*
X215049Y1072581D01*
X215007Y1072998D01*
X215091Y1073540D01*
X215216Y1073831D01*
X215424Y1074123D01*
X215716Y1074331D01*
X216007Y1074373D01*
X216299Y1074290D01*
X216507Y1074081D01*
G01X218899Y1071873D02*
Y1074373D01*
X218399Y1073873D01*
G01Y1071873D02*
X219399D01*
G01X208766Y1067173D02*
Y1069673D01*
X209807D01*
X210141Y1069548D01*
X210349Y1069381D01*
X210432Y1069048D01*
X210349Y1068715D01*
X210099Y1068506D01*
X209807Y1068381D01*
X208766D01*
G01X209807D02*
X210432Y1067173D01*
G01X212699D02*
Y1069673D01*
X212199Y1069173D01*
G01Y1067173D02*
X213199D01*
G01X215007Y1068215D02*
X215299Y1068506D01*
X215549Y1068673D01*
X215882Y1068756D01*
X216174Y1068673D01*
X216382Y1068506D01*
X216549Y1068256D01*
X216591Y1067965D01*
X216549Y1067715D01*
X216382Y1067465D01*
X216132Y1067256D01*
X215841Y1067173D01*
X215507Y1067256D01*
X215216Y1067506D01*
X215049Y1067881D01*
X215007Y1068298D01*
X215091Y1068840D01*
X215216Y1069131D01*
X215424Y1069423D01*
X215716Y1069631D01*
X216007Y1069673D01*
X216299Y1069590D01*
X216507Y1069381D01*
G01X217982Y1067673D02*
X218232Y1067381D01*
X218566Y1067215D01*
X218941Y1067173D01*
X219274Y1067215D01*
X219607Y1067423D01*
X219816Y1067673D01*
X219857Y1067923D01*
X219774Y1068215D01*
X219482Y1068423D01*
X219191Y1068506D01*
X218816D01*
G01X219191D02*
X219441Y1068631D01*
X219649Y1068840D01*
X219732Y1069090D01*
X219649Y1069340D01*
X219441Y1069548D01*
X219066Y1069673D01*
X218691Y1069631D01*
X218316Y1069465D01*
G01X208617Y1076000D02*
Y1078500D01*
X209658D01*
X209992Y1078375D01*
X210200Y1078208D01*
X210283Y1077875D01*
X210200Y1077542D01*
X209950Y1077333D01*
X209658Y1077208D01*
X208617D01*
G01X209658D02*
X210283Y1076000D01*
G01X212550D02*
Y1078500D01*
X212050Y1078000D01*
G01Y1076000D02*
X213050D01*
G01X214858Y1077042D02*
X215150Y1077333D01*
X215400Y1077500D01*
X215733Y1077583D01*
X216025Y1077500D01*
X216233Y1077333D01*
X216400Y1077083D01*
X216442Y1076792D01*
X216400Y1076542D01*
X216233Y1076292D01*
X215983Y1076083D01*
X215692Y1076000D01*
X215358Y1076083D01*
X215067Y1076333D01*
X214900Y1076708D01*
X214858Y1077125D01*
X214942Y1077667D01*
X215067Y1077958D01*
X215275Y1078250D01*
X215567Y1078458D01*
X215858Y1078500D01*
X216150Y1078417D01*
X216358Y1078208D01*
G01X219250Y1076000D02*
Y1078500D01*
X217708Y1076708D01*
X219792D01*
G01X198900Y1068517D02*
X196400D01*
Y1069558D01*
X196525Y1069892D01*
X196692Y1070100D01*
X197025Y1070183D01*
X197358Y1070100D01*
X197567Y1069850D01*
X197692Y1069558D01*
Y1068517D01*
G01Y1069558D02*
X198900Y1070183D01*
G01Y1072450D02*
X196400D01*
X196900Y1071950D01*
G01X198900D02*
Y1072950D01*
G01Y1075467D02*
X198358Y1075550D01*
X197900Y1075675D01*
X197483Y1075842D01*
X197025Y1076050D01*
X196400Y1076383D01*
Y1074717D01*
G01Y1078650D02*
X196483Y1078317D01*
X196692Y1078067D01*
X196942Y1077900D01*
X197275Y1077775D01*
X197650Y1077733D01*
X198025Y1077775D01*
X198358Y1077900D01*
X198608Y1078067D01*
X198817Y1078317D01*
X198900Y1078650D01*
X198817Y1078983D01*
X198608Y1079233D01*
X198358Y1079400D01*
X198025Y1079525D01*
X197650Y1079567D01*
X197275Y1079525D01*
X196942Y1079400D01*
X196692Y1079233D01*
X196483Y1078983D01*
X196400Y1078650D01*
G01X199449Y1088873D02*
X195449D01*
Y1081473D01*
G01X193602Y1076395D02*
X191102D01*
Y1077229D01*
X191227Y1077562D01*
X191394Y1077812D01*
X191644Y1078020D01*
X191935Y1078187D01*
X192352Y1078229D01*
X192769Y1078187D01*
X193060Y1078020D01*
X193310Y1077812D01*
X193477Y1077562D01*
X193602Y1077229D01*
Y1076395D01*
G01Y1080412D02*
X191102D01*
X191602Y1079912D01*
G01X193602D02*
Y1080912D01*
G01X186449Y1108373D02*
Y1104373D01*
X193849D01*
G01X218449Y1084873D02*
Y1088873D01*
X211049D01*
G01X218449Y1080173D02*
Y1084173D01*
X211049D01*
G01Y1098673D02*
Y1094673D01*
X218449D01*
G01X179027Y1096839D02*
Y1092839D01*
X186427D01*
G01X192149Y1117573D02*
Y1121573D01*
X184749D01*
G01X179039Y1101043D02*
Y1097043D01*
X186439D01*
G01X205950Y1086500D02*
X205617Y1086542D01*
X205325Y1086708D01*
X205075Y1086958D01*
X204908Y1087250D01*
X204825Y1087583D01*
Y1087917D01*
X204908Y1088250D01*
X205075Y1088542D01*
X205325Y1088792D01*
X205617Y1088958D01*
X205950Y1089000D01*
X206283Y1088958D01*
X206575Y1088792D01*
X206825Y1088542D01*
X206992Y1088250D01*
X207075Y1087917D01*
Y1087583D01*
X206992Y1087250D01*
X206825Y1086958D01*
X206575Y1086708D01*
X206283Y1086542D01*
X205950Y1086500D01*
G01X206283Y1087167D02*
X206783Y1086500D01*
G01X208967D02*
X209050Y1087042D01*
X209175Y1087500D01*
X209342Y1087917D01*
X209550Y1088375D01*
X209883Y1089000D01*
X208217D01*
G01X210349Y1103373D02*
X198949D01*
G01X210349Y1089973D02*
Y1103373D01*
G01X198949Y1089973D02*
X210349D01*
G01X198949Y1103373D02*
Y1089973D01*
G01X194151Y1099035D02*
Y1082935D01*
G01X187151Y1099035D02*
X194151D01*
G01X187151Y1082935D02*
Y1099035D01*
G01X194151Y1082935D02*
X187151D01*
G01X216349Y1121173D02*
X214249Y1122973D01*
X216349Y1125173D01*
G01X216449Y1128773D02*
X197249D01*
Y1117573D01*
X216449D01*
Y1128773D01*
X216049D01*
G01X218408Y1161620D02*
X215908D01*
Y1162661D01*
X216033Y1162995D01*
X216200Y1163203D01*
X216533Y1163286D01*
X216866Y1163203D01*
X217075Y1162953D01*
X217200Y1162661D01*
Y1161620D01*
G01Y1162661D02*
X218408Y1163286D01*
G01Y1165553D02*
X215908D01*
X216408Y1165053D01*
G01X218408D02*
Y1166053D01*
G01X218033Y1167736D02*
X218241Y1167986D01*
X218366Y1168278D01*
X218408Y1168653D01*
X218325Y1169028D01*
X218158Y1169320D01*
X217866Y1169528D01*
X217533Y1169570D01*
X217200Y1169486D01*
X216991Y1169278D01*
X216825Y1168986D01*
X216783Y1168695D01*
X216825Y1168403D01*
X216991Y1168028D01*
X215908Y1168153D01*
Y1169278D01*
G01X216325Y1170961D02*
X216075Y1171211D01*
X215950Y1171503D01*
X215908Y1171836D01*
X215991Y1172253D01*
X216200Y1172545D01*
X216450Y1172628D01*
X216700Y1172586D01*
X216908Y1172420D01*
X217325Y1171586D01*
X217616Y1171211D01*
X218033Y1170961D01*
X218408Y1170878D01*
Y1172628D01*
G01X213649Y1159473D02*
X221649D01*
Y1141873D01*
X213649D01*
Y1159473D01*
G01X190935Y1174204D02*
Y1176704D01*
X191976D01*
X192310Y1176579D01*
X192518Y1176412D01*
X192601Y1176079D01*
X192518Y1175746D01*
X192268Y1175537D01*
X191976Y1175412D01*
X190935D01*
G01X191976D02*
X192601Y1174204D01*
G01X194868D02*
Y1176704D01*
X194368Y1176204D01*
G01Y1174204D02*
X195368D01*
G01X197051Y1174579D02*
X197301Y1174371D01*
X197593Y1174246D01*
X197968Y1174204D01*
X198343Y1174287D01*
X198635Y1174454D01*
X198843Y1174746D01*
X198885Y1175079D01*
X198801Y1175412D01*
X198593Y1175621D01*
X198301Y1175787D01*
X198010Y1175829D01*
X197718Y1175787D01*
X197343Y1175621D01*
X197468Y1176704D01*
X198593D01*
G01X201568Y1174204D02*
Y1176704D01*
X200026Y1174912D01*
X202110D01*
G01X189849Y1156173D02*
Y1164173D01*
X207449D01*
Y1156173D01*
X189849D01*
G01X180466Y1171965D02*
X180216Y1172090D01*
X179924Y1172173D01*
X179591D01*
X179216Y1172048D01*
X178924Y1171840D01*
X178716Y1171590D01*
X178549Y1171173D01*
X178507Y1170798D01*
X178591Y1170423D01*
X178716Y1170173D01*
X178966Y1169923D01*
X179257Y1169756D01*
X179549Y1169673D01*
X179841D01*
X180132Y1169756D01*
X180382Y1169881D01*
X180591Y1170048D01*
G01X181732D02*
X181982Y1169840D01*
X182274Y1169715D01*
X182649Y1169673D01*
X183024Y1169756D01*
X183316Y1169923D01*
X183524Y1170215D01*
X183566Y1170548D01*
X183482Y1170881D01*
X183274Y1171090D01*
X182982Y1171256D01*
X182691Y1171298D01*
X182399Y1171256D01*
X182024Y1171090D01*
X182149Y1172173D01*
X183274D01*
G01X185041Y1169965D02*
X185332Y1169756D01*
X185666Y1169673D01*
X185999Y1169756D01*
X186291Y1170006D01*
X186499Y1170381D01*
X186582Y1170756D01*
Y1171215D01*
X186499Y1171590D01*
X186291Y1171923D01*
X186041Y1172090D01*
X185749Y1172173D01*
X185416Y1172090D01*
X185166Y1171923D01*
X184999Y1171673D01*
X184916Y1171340D01*
X184999Y1171048D01*
X185207Y1170756D01*
X185457Y1170590D01*
X185749Y1170548D01*
X186082Y1170631D01*
X186332Y1170840D01*
X186582Y1171215D01*
G01X198024Y1168101D02*
X197774Y1168226D01*
X197482Y1168309D01*
X197149D01*
X196774Y1168184D01*
X196482Y1167976D01*
X196274Y1167726D01*
X196107Y1167309D01*
X196065Y1166934D01*
X196149Y1166559D01*
X196274Y1166309D01*
X196524Y1166059D01*
X196815Y1165892D01*
X197107Y1165809D01*
X197399D01*
X197690Y1165892D01*
X197940Y1166017D01*
X198149Y1166184D01*
G01X199290D02*
X199540Y1165976D01*
X199832Y1165851D01*
X200207Y1165809D01*
X200582Y1165892D01*
X200874Y1166059D01*
X201082Y1166351D01*
X201124Y1166684D01*
X201040Y1167017D01*
X200832Y1167226D01*
X200540Y1167392D01*
X200249Y1167434D01*
X199957Y1167392D01*
X199582Y1167226D01*
X199707Y1168309D01*
X200832D01*
G01X203807Y1165809D02*
Y1168309D01*
X202265Y1166517D01*
X204349D01*
G01X211949Y1141673D02*
X206449D01*
G01X211949Y1149673D02*
Y1141673D01*
G01X206449Y1149673D02*
X211949D01*
G01X194349D02*
X199849D01*
G01X194349Y1141673D02*
Y1149673D01*
G01X199849Y1141673D02*
X194349D01*
G01X171949Y1143173D02*
X174049Y1141373D01*
X171949Y1139173D01*
G01X171849Y1135573D02*
X191049D01*
Y1146773D01*
X171849D01*
Y1135573D01*
X172249D01*
G01X197613Y1172291D02*
X197363Y1172416D01*
X197071Y1172499D01*
X196738D01*
X196363Y1172374D01*
X196071Y1172166D01*
X195863Y1171916D01*
X195696Y1171499D01*
X195654Y1171124D01*
X195738Y1170749D01*
X195863Y1170499D01*
X196113Y1170249D01*
X196404Y1170082D01*
X196696Y1169999D01*
X196988D01*
X197279Y1170082D01*
X197529Y1170207D01*
X197738Y1170374D01*
G01X198879D02*
X199129Y1170166D01*
X199421Y1170041D01*
X199796Y1169999D01*
X200171Y1170082D01*
X200463Y1170249D01*
X200671Y1170541D01*
X200713Y1170874D01*
X200629Y1171207D01*
X200421Y1171416D01*
X200129Y1171582D01*
X199838Y1171624D01*
X199546Y1171582D01*
X199171Y1171416D01*
X199296Y1172499D01*
X200421D01*
G01X201979Y1170499D02*
X202229Y1170207D01*
X202563Y1170041D01*
X202938Y1169999D01*
X203271Y1170041D01*
X203604Y1170249D01*
X203813Y1170499D01*
X203854Y1170749D01*
X203771Y1171041D01*
X203479Y1171249D01*
X203188Y1171332D01*
X202813D01*
G01X203188D02*
X203438Y1171457D01*
X203646Y1171666D01*
X203729Y1171916D01*
X203646Y1172166D01*
X203438Y1172374D01*
X203063Y1172499D01*
X202688Y1172457D01*
X202313Y1172291D01*
G01X211208Y1187317D02*
X211083Y1187067D01*
X211000Y1186775D01*
Y1186442D01*
X211125Y1186067D01*
X211333Y1185775D01*
X211583Y1185567D01*
X212000Y1185400D01*
X212375Y1185358D01*
X212750Y1185442D01*
X213000Y1185567D01*
X213250Y1185817D01*
X213417Y1186108D01*
X213500Y1186400D01*
Y1186692D01*
X213417Y1186983D01*
X213292Y1187233D01*
X213125Y1187442D01*
G01Y1188583D02*
X213333Y1188833D01*
X213458Y1189125D01*
X213500Y1189500D01*
X213417Y1189875D01*
X213250Y1190167D01*
X212958Y1190375D01*
X212625Y1190417D01*
X212292Y1190333D01*
X212083Y1190125D01*
X211917Y1189833D01*
X211875Y1189542D01*
X211917Y1189250D01*
X212083Y1188875D01*
X211000Y1189000D01*
Y1190125D01*
G01X213500Y1192600D02*
X213458Y1192892D01*
X213333Y1193225D01*
X213125Y1193433D01*
X212833Y1193517D01*
X212542Y1193433D01*
X212292Y1193183D01*
X212167Y1192808D01*
Y1192392D01*
X212083Y1192142D01*
X211875Y1191933D01*
X211583Y1191850D01*
X211292Y1191975D01*
X211083Y1192267D01*
X211000Y1192600D01*
X211083Y1192933D01*
X211292Y1193225D01*
X211583Y1193350D01*
X211875Y1193267D01*
X212083Y1193058D01*
X212167Y1192808D01*
Y1192392D01*
X212292Y1192017D01*
X212542Y1191767D01*
X212833Y1191683D01*
X213125Y1191767D01*
X213333Y1191975D01*
X213458Y1192308D01*
X213500Y1192600D01*
G01X214208Y1197317D02*
X214083Y1197067D01*
X214000Y1196775D01*
Y1196442D01*
X214125Y1196067D01*
X214333Y1195775D01*
X214583Y1195567D01*
X215000Y1195400D01*
X215375Y1195358D01*
X215750Y1195442D01*
X216000Y1195567D01*
X216250Y1195817D01*
X216417Y1196108D01*
X216500Y1196400D01*
Y1196692D01*
X216417Y1196983D01*
X216292Y1197233D01*
X216125Y1197442D01*
G01X215458Y1198708D02*
X215167Y1199000D01*
X215000Y1199250D01*
X214917Y1199583D01*
X215000Y1199875D01*
X215167Y1200083D01*
X215417Y1200250D01*
X215708Y1200292D01*
X215958Y1200250D01*
X216208Y1200083D01*
X216417Y1199833D01*
X216500Y1199542D01*
X216417Y1199208D01*
X216167Y1198917D01*
X215792Y1198750D01*
X215375Y1198708D01*
X214833Y1198792D01*
X214542Y1198917D01*
X214250Y1199125D01*
X214042Y1199417D01*
X214000Y1199708D01*
X214083Y1200000D01*
X214292Y1200208D01*
G01X214000Y1202600D02*
X214083Y1202267D01*
X214292Y1202017D01*
X214542Y1201850D01*
X214875Y1201725D01*
X215250Y1201683D01*
X215625Y1201725D01*
X215958Y1201850D01*
X216208Y1202017D01*
X216417Y1202267D01*
X216500Y1202600D01*
X216417Y1202933D01*
X216208Y1203183D01*
X215958Y1203350D01*
X215625Y1203475D01*
X215250Y1203517D01*
X214875Y1203475D01*
X214542Y1203350D01*
X214292Y1203183D01*
X214083Y1202933D01*
X214000Y1202600D01*
G01X204804Y1270548D02*
X202304D01*
Y1271589D01*
X202429Y1271923D01*
X202596Y1272131D01*
X202929Y1272214D01*
X203262Y1272131D01*
X203471Y1271881D01*
X203596Y1271589D01*
Y1270548D01*
G01Y1271589D02*
X204804Y1272214D01*
G01X202304Y1273648D02*
X204804D01*
Y1275314D01*
G01Y1278414D02*
Y1276748D01*
X202304D01*
Y1278414D01*
G01X203512Y1277748D02*
Y1276748D01*
G01X204804Y1279764D02*
X202304D01*
Y1280598D01*
X202429Y1280931D01*
X202596Y1281181D01*
X202846Y1281389D01*
X203137Y1281556D01*
X203554Y1281598D01*
X203971Y1281556D01*
X204262Y1281389D01*
X204512Y1281181D01*
X204679Y1280931D01*
X204804Y1280598D01*
Y1279764D01*
G01X202721Y1282989D02*
X202471Y1283239D01*
X202346Y1283531D01*
X202304Y1283864D01*
X202387Y1284281D01*
X202596Y1284573D01*
X202846Y1284656D01*
X203096Y1284614D01*
X203304Y1284448D01*
X203721Y1283614D01*
X204012Y1283239D01*
X204429Y1282989D01*
X204804Y1282906D01*
Y1284656D01*
G01X203762Y1286089D02*
X203471Y1286381D01*
X203304Y1286631D01*
X203221Y1286964D01*
X203304Y1287256D01*
X203471Y1287464D01*
X203721Y1287631D01*
X204012Y1287673D01*
X204262Y1287631D01*
X204512Y1287464D01*
X204721Y1287214D01*
X204804Y1286923D01*
X204721Y1286589D01*
X204471Y1286298D01*
X204096Y1286131D01*
X203679Y1286089D01*
X203137Y1286173D01*
X202846Y1286298D01*
X202554Y1286506D01*
X202346Y1286798D01*
X202304Y1287089D01*
X202387Y1287381D01*
X202596Y1287589D01*
G01X189891Y1271565D02*
Y1282765D01*
X198691D01*
Y1271565D01*
X189891D01*
G01X218336Y221492D02*
X223386D01*
Y320192D01*
X248036D01*
Y135792D01*
X223386D01*
Y194492D01*
X218336D01*
Y221492D01*
G01X254288Y165184D02*
X254038Y165309D01*
X253746Y165392D01*
X253413D01*
X253038Y165267D01*
X252746Y165059D01*
X252538Y164809D01*
X252371Y164392D01*
X252329Y164017D01*
X252413Y163642D01*
X252538Y163392D01*
X252788Y163142D01*
X253079Y162975D01*
X253371Y162892D01*
X253663D01*
X253954Y162975D01*
X254204Y163100D01*
X254413Y163267D01*
G01X255554Y163392D02*
X255804Y163100D01*
X256138Y162934D01*
X256513Y162892D01*
X256846Y162934D01*
X257179Y163142D01*
X257388Y163392D01*
X257429Y163642D01*
X257346Y163934D01*
X257054Y164142D01*
X256763Y164225D01*
X256388D01*
G01X256763D02*
X257013Y164350D01*
X257221Y164559D01*
X257304Y164809D01*
X257221Y165059D01*
X257013Y165267D01*
X256638Y165392D01*
X256263Y165350D01*
X255888Y165184D01*
G01X258779Y163934D02*
X259071Y164225D01*
X259321Y164392D01*
X259654Y164475D01*
X259946Y164392D01*
X260154Y164225D01*
X260321Y163975D01*
X260363Y163684D01*
X260321Y163434D01*
X260154Y163184D01*
X259904Y162975D01*
X259613Y162892D01*
X259279Y162975D01*
X258988Y163225D01*
X258821Y163600D01*
X258779Y164017D01*
X258863Y164559D01*
X258988Y164850D01*
X259196Y165142D01*
X259488Y165350D01*
X259779Y165392D01*
X260071Y165309D01*
X260279Y165100D01*
G01X263171Y162892D02*
Y165392D01*
X261629Y163600D01*
X263713D01*
G01X254267Y169292D02*
X254017Y169417D01*
X253725Y169500D01*
X253392D01*
X253017Y169375D01*
X252725Y169167D01*
X252517Y168917D01*
X252350Y168500D01*
X252308Y168125D01*
X252392Y167750D01*
X252517Y167500D01*
X252767Y167250D01*
X253058Y167083D01*
X253350Y167000D01*
X253642D01*
X253933Y167083D01*
X254183Y167208D01*
X254392Y167375D01*
G01X255533Y167500D02*
X255783Y167208D01*
X256117Y167042D01*
X256492Y167000D01*
X256825Y167042D01*
X257158Y167250D01*
X257367Y167500D01*
X257408Y167750D01*
X257325Y168042D01*
X257033Y168250D01*
X256742Y168333D01*
X256367D01*
G01X256742D02*
X256992Y168458D01*
X257200Y168667D01*
X257283Y168917D01*
X257200Y169167D01*
X256992Y169375D01*
X256617Y169500D01*
X256242Y169458D01*
X255867Y169292D01*
G01X258758Y168042D02*
X259050Y168333D01*
X259300Y168500D01*
X259633Y168583D01*
X259925Y168500D01*
X260133Y168333D01*
X260300Y168083D01*
X260342Y167792D01*
X260300Y167542D01*
X260133Y167292D01*
X259883Y167083D01*
X259592Y167000D01*
X259258Y167083D01*
X258967Y167333D01*
X258800Y167708D01*
X258758Y168125D01*
X258842Y168667D01*
X258967Y168958D01*
X259175Y169250D01*
X259467Y169458D01*
X259758Y169500D01*
X260050Y169417D01*
X260258Y169208D01*
G01X261733Y167500D02*
X261983Y167208D01*
X262317Y167042D01*
X262692Y167000D01*
X263025Y167042D01*
X263358Y167250D01*
X263567Y167500D01*
X263608Y167750D01*
X263525Y168042D01*
X263233Y168250D01*
X262942Y168333D01*
X262567D01*
G01X262942D02*
X263192Y168458D01*
X263400Y168667D01*
X263483Y168917D01*
X263400Y169167D01*
X263192Y169375D01*
X262817Y169500D01*
X262442Y169458D01*
X262067Y169292D01*
G01X258666Y233261D02*
Y235761D01*
X259707D01*
X260041Y235636D01*
X260249Y235469D01*
X260332Y235136D01*
X260249Y234803D01*
X259999Y234594D01*
X259707Y234469D01*
X258666D01*
G01X259707D02*
X260332Y233261D01*
G01X262516D02*
X262599Y233803D01*
X262724Y234261D01*
X262891Y234678D01*
X263099Y235136D01*
X263432Y235761D01*
X261766D01*
G01X265699D02*
X265366Y235678D01*
X265116Y235469D01*
X264949Y235219D01*
X264824Y234886D01*
X264782Y234511D01*
X264824Y234136D01*
X264949Y233803D01*
X265116Y233553D01*
X265366Y233344D01*
X265699Y233261D01*
X266032Y233344D01*
X266282Y233553D01*
X266449Y233803D01*
X266574Y234136D01*
X266616Y234511D01*
X266574Y234886D01*
X266449Y235219D01*
X266282Y235469D01*
X266032Y235678D01*
X265699Y235761D01*
G01X267882Y233636D02*
X268132Y233428D01*
X268424Y233303D01*
X268799Y233261D01*
X269174Y233344D01*
X269466Y233511D01*
X269674Y233803D01*
X269716Y234136D01*
X269632Y234469D01*
X269424Y234678D01*
X269132Y234844D01*
X268841Y234886D01*
X268549Y234844D01*
X268174Y234678D01*
X268299Y235761D01*
X269424D01*
G01X268849Y242761D02*
Y246761D01*
X261449D01*
G01X220500Y224850D02*
X220458Y224517D01*
X220292Y224225D01*
X220042Y223975D01*
X219750Y223808D01*
X219417Y223725D01*
X219083D01*
X218750Y223808D01*
X218458Y223975D01*
X218208Y224225D01*
X218042Y224517D01*
X218000Y224850D01*
X218042Y225183D01*
X218208Y225475D01*
X218458Y225725D01*
X218750Y225892D01*
X219083Y225975D01*
X219417D01*
X219750Y225892D01*
X220042Y225725D01*
X220292Y225475D01*
X220458Y225183D01*
X220500Y224850D01*
G01X219833Y225183D02*
X220500Y225683D01*
G01Y227950D02*
X218000D01*
X218500Y227450D01*
G01X220500D02*
Y228450D01*
G01Y231550D02*
X218000D01*
X219792Y230008D01*
Y232092D01*
G01X220208Y233442D02*
X220417Y233733D01*
X220500Y234067D01*
X220417Y234400D01*
X220167Y234692D01*
X219792Y234900D01*
X219417Y234983D01*
X218958D01*
X218583Y234900D01*
X218250Y234692D01*
X218083Y234442D01*
X218000Y234150D01*
X218083Y233817D01*
X218250Y233567D01*
X218500Y233400D01*
X218833Y233317D01*
X219125Y233400D01*
X219417Y233608D01*
X219583Y233858D01*
X219625Y234150D01*
X219542Y234483D01*
X219333Y234733D01*
X218958Y234983D01*
G01X266017Y250500D02*
Y253000D01*
X267058D01*
X267392Y252875D01*
X267600Y252708D01*
X267683Y252375D01*
X267600Y252042D01*
X267350Y251833D01*
X267058Y251708D01*
X266017D01*
G01X267058D02*
X267683Y250500D01*
G01X269867D02*
X269950Y251042D01*
X270075Y251500D01*
X270242Y251917D01*
X270450Y252375D01*
X270783Y253000D01*
X269117D01*
G01X273050D02*
X272717Y252917D01*
X272467Y252708D01*
X272300Y252458D01*
X272175Y252125D01*
X272133Y251750D01*
X272175Y251375D01*
X272300Y251042D01*
X272467Y250792D01*
X272717Y250583D01*
X273050Y250500D01*
X273383Y250583D01*
X273633Y250792D01*
X273800Y251042D01*
X273925Y251375D01*
X273967Y251750D01*
X273925Y252125D01*
X273800Y252458D01*
X273633Y252708D01*
X273383Y252917D01*
X273050Y253000D01*
G01X275442Y250792D02*
X275733Y250583D01*
X276067Y250500D01*
X276400Y250583D01*
X276692Y250833D01*
X276900Y251208D01*
X276983Y251583D01*
Y252042D01*
X276900Y252417D01*
X276692Y252750D01*
X276442Y252917D01*
X276150Y253000D01*
X275817Y252917D01*
X275567Y252750D01*
X275400Y252500D01*
X275317Y252167D01*
X275400Y251875D01*
X275608Y251583D01*
X275858Y251417D01*
X276150Y251375D01*
X276483Y251458D01*
X276733Y251667D01*
X276983Y252042D01*
G01X260416Y231453D02*
X260166Y231578D01*
X259874Y231661D01*
X259541D01*
X259166Y231536D01*
X258874Y231328D01*
X258666Y231078D01*
X258499Y230661D01*
X258457Y230286D01*
X258541Y229911D01*
X258666Y229661D01*
X258916Y229411D01*
X259207Y229244D01*
X259499Y229161D01*
X259791D01*
X260082Y229244D01*
X260332Y229369D01*
X260541Y229536D01*
G01X261682Y229661D02*
X261932Y229369D01*
X262266Y229203D01*
X262641Y229161D01*
X262974Y229203D01*
X263307Y229411D01*
X263516Y229661D01*
X263557Y229911D01*
X263474Y230203D01*
X263182Y230411D01*
X262891Y230494D01*
X262516D01*
G01X262891D02*
X263141Y230619D01*
X263349Y230828D01*
X263432Y231078D01*
X263349Y231328D01*
X263141Y231536D01*
X262766Y231661D01*
X262391Y231619D01*
X262016Y231453D01*
G01X265616Y229161D02*
X265699Y229703D01*
X265824Y230161D01*
X265991Y230578D01*
X266199Y231036D01*
X266532Y231661D01*
X264866D01*
G01X268799Y229161D02*
Y231661D01*
X268299Y231161D01*
G01Y229161D02*
X269299D01*
G01X258000Y262800D02*
X260500D01*
G01X258000Y261842D02*
Y263758D01*
G01X260500Y265067D02*
X258000D01*
Y266067D01*
X258125Y266400D01*
X258417Y266650D01*
X258750Y266733D01*
X259083Y266650D01*
X259333Y266442D01*
X259458Y266067D01*
Y265067D01*
G01X260500Y269000D02*
X258000D01*
X258500Y268500D01*
G01X260500D02*
Y269500D01*
G01X258417Y271308D02*
X258167Y271558D01*
X258042Y271850D01*
X258000Y272183D01*
X258083Y272600D01*
X258292Y272892D01*
X258542Y272975D01*
X258792Y272933D01*
X259000Y272767D01*
X259417Y271933D01*
X259708Y271558D01*
X260125Y271308D01*
X260500Y271225D01*
Y272975D01*
G01Y275117D02*
X259958Y275200D01*
X259500Y275325D01*
X259083Y275492D01*
X258625Y275700D01*
X258000Y276033D01*
Y274367D01*
G01X238275Y325000D02*
Y327500D01*
G01X240025D02*
Y325000D01*
G01Y326250D02*
X238275D01*
G01X241333Y325000D02*
Y327500D01*
X242167D01*
X242500Y327375D01*
X242750Y327208D01*
X242958Y326958D01*
X243125Y326667D01*
X243167Y326250D01*
X243125Y325833D01*
X242958Y325542D01*
X242750Y325292D01*
X242500Y325125D01*
X242167Y325000D01*
X241333D01*
G01X244433D02*
Y327500D01*
X245267D01*
X245600Y327375D01*
X245850Y327208D01*
X246058Y326958D01*
X246225Y326667D01*
X246267Y326250D01*
X246225Y325833D01*
X246058Y325542D01*
X245850Y325292D01*
X245600Y325125D01*
X245267Y325000D01*
X244433D01*
G01X247575Y325333D02*
X247908Y325125D01*
X248283Y325000D01*
X248617D01*
X248950Y325125D01*
X249200Y325333D01*
X249325Y325625D01*
X249242Y325917D01*
X249033Y326167D01*
X248658Y326333D01*
X248158Y326417D01*
X247867Y326583D01*
X247742Y326875D01*
X247825Y327167D01*
X248033Y327375D01*
X248325Y327500D01*
X248617D01*
X248908Y327417D01*
X249158Y327208D01*
G01X250508Y325000D02*
X251550Y327500D01*
X252592Y325000D01*
G01X252217Y325875D02*
X250883D01*
G01X253775Y325333D02*
X254108Y325125D01*
X254483Y325000D01*
X254817D01*
X255150Y325125D01*
X255400Y325333D01*
X255525Y325625D01*
X255442Y325917D01*
X255233Y326167D01*
X254858Y326333D01*
X254358Y326417D01*
X254067Y326583D01*
X253942Y326875D01*
X254025Y327167D01*
X254233Y327375D01*
X254525Y327500D01*
X254817D01*
X255108Y327417D01*
X255358Y327208D01*
G01X256958Y327083D02*
X257208Y327333D01*
X257500Y327458D01*
X257833Y327500D01*
X258250Y327417D01*
X258542Y327208D01*
X258625Y326958D01*
X258583Y326708D01*
X258417Y326500D01*
X257583Y326083D01*
X257208Y325792D01*
X256958Y325375D01*
X256875Y325000D01*
X258625D01*
G01X259933Y325375D02*
X260183Y325167D01*
X260475Y325042D01*
X260850Y325000D01*
X261225Y325083D01*
X261517Y325250D01*
X261725Y325542D01*
X261767Y325875D01*
X261683Y326208D01*
X261475Y326417D01*
X261183Y326583D01*
X260892Y326625D01*
X260600Y326583D01*
X260225Y326417D01*
X260350Y327500D01*
X261475D01*
G01X218336Y674248D02*
X223386D01*
Y772948D01*
X248036D01*
Y588548D01*
X223386D01*
Y647248D01*
X218336D01*
Y674248D01*
G01X218965Y590208D02*
X221465D01*
G01X218965Y589250D02*
Y591166D01*
G01X221465Y592475D02*
X218965D01*
Y593475D01*
X219090Y593808D01*
X219382Y594058D01*
X219715Y594141D01*
X220048Y594058D01*
X220298Y593850D01*
X220423Y593475D01*
Y592475D01*
G01X219382Y595616D02*
X219132Y595866D01*
X219007Y596158D01*
X218965Y596491D01*
X219048Y596908D01*
X219257Y597200D01*
X219507Y597283D01*
X219757Y597241D01*
X219965Y597075D01*
X220382Y596241D01*
X220673Y595866D01*
X221090Y595616D01*
X221465Y595533D01*
Y597283D01*
G01X221090Y598591D02*
X221298Y598841D01*
X221423Y599133D01*
X221465Y599508D01*
X221382Y599883D01*
X221215Y600175D01*
X220923Y600383D01*
X220590Y600425D01*
X220257Y600341D01*
X220048Y600133D01*
X219882Y599841D01*
X219840Y599550D01*
X219882Y599258D01*
X220048Y598883D01*
X218965Y599008D01*
Y600133D01*
G01X221465Y602525D02*
X220923Y602608D01*
X220465Y602733D01*
X220048Y602900D01*
X219590Y603108D01*
X218965Y603441D01*
Y601775D01*
G01X254267Y622292D02*
X254017Y622417D01*
X253725Y622500D01*
X253392D01*
X253017Y622375D01*
X252725Y622167D01*
X252517Y621917D01*
X252350Y621500D01*
X252308Y621125D01*
X252392Y620750D01*
X252517Y620500D01*
X252767Y620250D01*
X253058Y620083D01*
X253350Y620000D01*
X253642D01*
X253933Y620083D01*
X254183Y620208D01*
X254392Y620375D01*
G01X255658Y622083D02*
X255908Y622333D01*
X256200Y622458D01*
X256533Y622500D01*
X256950Y622417D01*
X257242Y622208D01*
X257325Y621958D01*
X257283Y621708D01*
X257117Y621500D01*
X256283Y621083D01*
X255908Y620792D01*
X255658Y620375D01*
X255575Y620000D01*
X257325D01*
G01X259550Y622500D02*
X259217Y622417D01*
X258967Y622208D01*
X258800Y621958D01*
X258675Y621625D01*
X258633Y621250D01*
X258675Y620875D01*
X258800Y620542D01*
X258967Y620292D01*
X259217Y620083D01*
X259550Y620000D01*
X259883Y620083D01*
X260133Y620292D01*
X260300Y620542D01*
X260425Y620875D01*
X260467Y621250D01*
X260425Y621625D01*
X260300Y621958D01*
X260133Y622208D01*
X259883Y622417D01*
X259550Y622500D01*
G01X262567Y620000D02*
X262650Y620542D01*
X262775Y621000D01*
X262942Y621417D01*
X263150Y621875D01*
X263483Y622500D01*
X261817D01*
G01X254267Y618292D02*
X254017Y618417D01*
X253725Y618500D01*
X253392D01*
X253017Y618375D01*
X252725Y618167D01*
X252517Y617917D01*
X252350Y617500D01*
X252308Y617125D01*
X252392Y616750D01*
X252517Y616500D01*
X252767Y616250D01*
X253058Y616083D01*
X253350Y616000D01*
X253642D01*
X253933Y616083D01*
X254183Y616208D01*
X254392Y616375D01*
G01X255658Y618083D02*
X255908Y618333D01*
X256200Y618458D01*
X256533Y618500D01*
X256950Y618417D01*
X257242Y618208D01*
X257325Y617958D01*
X257283Y617708D01*
X257117Y617500D01*
X256283Y617083D01*
X255908Y616792D01*
X255658Y616375D01*
X255575Y616000D01*
X257325D01*
G01X259550Y618500D02*
X259217Y618417D01*
X258967Y618208D01*
X258800Y617958D01*
X258675Y617625D01*
X258633Y617250D01*
X258675Y616875D01*
X258800Y616542D01*
X258967Y616292D01*
X259217Y616083D01*
X259550Y616000D01*
X259883Y616083D01*
X260133Y616292D01*
X260300Y616542D01*
X260425Y616875D01*
X260467Y617250D01*
X260425Y617625D01*
X260300Y617958D01*
X260133Y618208D01*
X259883Y618417D01*
X259550Y618500D01*
G01X262650Y616000D02*
X262942Y616042D01*
X263275Y616167D01*
X263483Y616375D01*
X263567Y616667D01*
X263483Y616958D01*
X263233Y617208D01*
X262858Y617333D01*
X262442D01*
X262192Y617417D01*
X261983Y617625D01*
X261900Y617917D01*
X262025Y618208D01*
X262317Y618417D01*
X262650Y618500D01*
X262983Y618417D01*
X263275Y618208D01*
X263400Y617917D01*
X263317Y617625D01*
X263108Y617417D01*
X262858Y617333D01*
X262442D01*
X262067Y617208D01*
X261817Y616958D01*
X261733Y616667D01*
X261817Y616375D01*
X262025Y616167D01*
X262358Y616042D01*
X262650Y616000D01*
G01X258666Y685517D02*
Y688017D01*
X259707D01*
X260041Y687892D01*
X260249Y687725D01*
X260332Y687392D01*
X260249Y687059D01*
X259999Y686850D01*
X259707Y686725D01*
X258666D01*
G01X259707D02*
X260332Y685517D01*
G01X263099D02*
Y688017D01*
X261557Y686225D01*
X263641D01*
G01X264907Y687600D02*
X265157Y687850D01*
X265449Y687975D01*
X265782Y688017D01*
X266199Y687934D01*
X266491Y687725D01*
X266574Y687475D01*
X266532Y687225D01*
X266366Y687017D01*
X265532Y686600D01*
X265157Y686309D01*
X264907Y685892D01*
X264824Y685517D01*
X266574D01*
G01X268091Y685809D02*
X268382Y685600D01*
X268716Y685517D01*
X269049Y685600D01*
X269341Y685850D01*
X269549Y686225D01*
X269632Y686600D01*
Y687059D01*
X269549Y687434D01*
X269341Y687767D01*
X269091Y687934D01*
X268799Y688017D01*
X268466Y687934D01*
X268216Y687767D01*
X268049Y687517D01*
X267966Y687184D01*
X268049Y686892D01*
X268257Y686600D01*
X268507Y686434D01*
X268799Y686392D01*
X269132Y686475D01*
X269382Y686684D01*
X269632Y687059D01*
G01X220500Y677900D02*
X220458Y677567D01*
X220292Y677275D01*
X220042Y677025D01*
X219750Y676858D01*
X219417Y676775D01*
X219083D01*
X218750Y676858D01*
X218458Y677025D01*
X218208Y677275D01*
X218042Y677567D01*
X218000Y677900D01*
X218042Y678233D01*
X218208Y678525D01*
X218458Y678775D01*
X218750Y678942D01*
X219083Y679025D01*
X219417D01*
X219750Y678942D01*
X220042Y678775D01*
X220292Y678525D01*
X220458Y678233D01*
X220500Y677900D01*
G01X219833Y678233D02*
X220500Y678733D01*
G01Y680917D02*
X219958Y681000D01*
X219500Y681125D01*
X219083Y681292D01*
X218625Y681500D01*
X218000Y681833D01*
Y680167D01*
G01X220500Y684017D02*
X219958Y684100D01*
X219500Y684225D01*
X219083Y684392D01*
X218625Y684600D01*
X218000Y684933D01*
Y683267D01*
G01X260416Y683709D02*
X260166Y683834D01*
X259874Y683917D01*
X259541D01*
X259166Y683792D01*
X258874Y683584D01*
X258666Y683334D01*
X258499Y682917D01*
X258457Y682542D01*
X258541Y682167D01*
X258666Y681917D01*
X258916Y681667D01*
X259207Y681500D01*
X259499Y681417D01*
X259791D01*
X260082Y681500D01*
X260332Y681625D01*
X260541Y681792D01*
G01X261807Y683500D02*
X262057Y683750D01*
X262349Y683875D01*
X262682Y683917D01*
X263099Y683834D01*
X263391Y683625D01*
X263474Y683375D01*
X263432Y683125D01*
X263266Y682917D01*
X262432Y682500D01*
X262057Y682209D01*
X261807Y681792D01*
X261724Y681417D01*
X263474D01*
G01X265699D02*
Y683917D01*
X265199Y683417D01*
G01Y681417D02*
X266199D01*
G01X267882Y681792D02*
X268132Y681584D01*
X268424Y681459D01*
X268799Y681417D01*
X269174Y681500D01*
X269466Y681667D01*
X269674Y681959D01*
X269716Y682292D01*
X269632Y682625D01*
X269424Y682834D01*
X269132Y683000D01*
X268841Y683042D01*
X268549Y683000D01*
X268174Y682834D01*
X268299Y683917D01*
X269424D01*
G01X268849Y695517D02*
Y699517D01*
X261449D01*
G01X260739Y732485D02*
X258239D01*
Y733526D01*
X258364Y733860D01*
X258531Y734068D01*
X258864Y734151D01*
X259197Y734068D01*
X259406Y733818D01*
X259531Y733526D01*
Y732485D01*
G01Y733526D02*
X260739Y734151D01*
G01Y736918D02*
X258239D01*
X260031Y735376D01*
Y737460D01*
G01X259697Y738726D02*
X259406Y739018D01*
X259239Y739268D01*
X259156Y739601D01*
X259239Y739893D01*
X259406Y740101D01*
X259656Y740268D01*
X259947Y740310D01*
X260197Y740268D01*
X260447Y740101D01*
X260656Y739851D01*
X260739Y739560D01*
X260656Y739226D01*
X260406Y738935D01*
X260031Y738768D01*
X259614Y738726D01*
X259072Y738810D01*
X258781Y738935D01*
X258489Y739143D01*
X258281Y739435D01*
X258239Y739726D01*
X258322Y740018D01*
X258531Y740226D01*
G01X260739Y742618D02*
X258239D01*
X258739Y742118D01*
G01X260739D02*
Y743118D01*
G01X266739Y741668D02*
X262739D01*
Y734268D01*
G01X260317Y717200D02*
Y719700D01*
X261358D01*
X261692Y719575D01*
X261900Y719408D01*
X261983Y719075D01*
X261900Y718742D01*
X261650Y718533D01*
X261358Y718408D01*
X260317D01*
G01X261358D02*
X261983Y717200D01*
G01X264750D02*
Y719700D01*
X263208Y717908D01*
X265292D01*
G01X266433Y717575D02*
X266683Y717367D01*
X266975Y717242D01*
X267350Y717200D01*
X267725Y717283D01*
X268017Y717450D01*
X268225Y717742D01*
X268267Y718075D01*
X268183Y718408D01*
X267975Y718617D01*
X267683Y718783D01*
X267392Y718825D01*
X267100Y718783D01*
X266725Y718617D01*
X266850Y719700D01*
X267975D01*
G01X270450Y717200D02*
X270742Y717242D01*
X271075Y717367D01*
X271283Y717575D01*
X271367Y717867D01*
X271283Y718158D01*
X271033Y718408D01*
X270658Y718533D01*
X270242D01*
X269992Y718617D01*
X269783Y718825D01*
X269700Y719117D01*
X269825Y719408D01*
X270117Y719617D01*
X270450Y719700D01*
X270783Y719617D01*
X271075Y719408D01*
X271200Y719117D01*
X271117Y718825D01*
X270908Y718617D01*
X270658Y718533D01*
X270242D01*
X269867Y718408D01*
X269617Y718158D01*
X269533Y717867D01*
X269617Y717575D01*
X269825Y717367D01*
X270158Y717242D01*
X270450Y717200D01*
G01X256000Y718150D02*
X258500D01*
G01X256000Y717192D02*
Y719108D01*
G01X258500Y720417D02*
X256000D01*
Y721417D01*
X256125Y721750D01*
X256417Y722000D01*
X256750Y722083D01*
X257083Y722000D01*
X257333Y721792D01*
X257458Y721417D01*
Y720417D01*
G01Y723558D02*
X257167Y723850D01*
X257000Y724100D01*
X256917Y724433D01*
X257000Y724725D01*
X257167Y724933D01*
X257417Y725100D01*
X257708Y725142D01*
X257958Y725100D01*
X258208Y724933D01*
X258417Y724683D01*
X258500Y724392D01*
X258417Y724058D01*
X258167Y723767D01*
X257792Y723600D01*
X257375Y723558D01*
X256833Y723642D01*
X256542Y723767D01*
X256250Y723975D01*
X256042Y724267D01*
X256000Y724558D01*
X256083Y724850D01*
X256292Y725058D01*
G01X258500Y727367D02*
X257958Y727450D01*
X257500Y727575D01*
X257083Y727742D01*
X256625Y727950D01*
X256000Y728283D01*
Y726617D01*
G01X253017Y712000D02*
Y714500D01*
X254058D01*
X254392Y714375D01*
X254600Y714208D01*
X254683Y713875D01*
X254600Y713542D01*
X254350Y713333D01*
X254058Y713208D01*
X253017D01*
G01X254058D02*
X254683Y712000D01*
G01X257450D02*
Y714500D01*
X255908Y712708D01*
X257992D01*
G01X259133Y712500D02*
X259383Y712208D01*
X259717Y712042D01*
X260092Y712000D01*
X260425Y712042D01*
X260758Y712250D01*
X260967Y712500D01*
X261008Y712750D01*
X260925Y713042D01*
X260633Y713250D01*
X260342Y713333D01*
X259967D01*
G01X260342D02*
X260592Y713458D01*
X260800Y713667D01*
X260883Y713917D01*
X260800Y714167D01*
X260592Y714375D01*
X260217Y714500D01*
X259842Y714458D01*
X259467Y714292D01*
G01X262233Y712500D02*
X262483Y712208D01*
X262817Y712042D01*
X263192Y712000D01*
X263525Y712042D01*
X263858Y712250D01*
X264067Y712500D01*
X264108Y712750D01*
X264025Y713042D01*
X263733Y713250D01*
X263442Y713333D01*
X263067D01*
G01X263442D02*
X263692Y713458D01*
X263900Y713667D01*
X263983Y713917D01*
X263900Y714167D01*
X263692Y714375D01*
X263317Y714500D01*
X262942Y714458D01*
X262567Y714292D01*
G01X239475Y782600D02*
Y785100D01*
G01X241225D02*
Y782600D01*
G01Y783850D02*
X239475D01*
G01X242533Y782600D02*
Y785100D01*
X243367D01*
X243700Y784975D01*
X243950Y784808D01*
X244158Y784558D01*
X244325Y784267D01*
X244367Y783850D01*
X244325Y783433D01*
X244158Y783142D01*
X243950Y782892D01*
X243700Y782725D01*
X243367Y782600D01*
X242533D01*
G01X245633D02*
Y785100D01*
X246467D01*
X246800Y784975D01*
X247050Y784808D01*
X247258Y784558D01*
X247425Y784267D01*
X247467Y783850D01*
X247425Y783433D01*
X247258Y783142D01*
X247050Y782892D01*
X246800Y782725D01*
X246467Y782600D01*
X245633D01*
G01X248775Y782933D02*
X249108Y782725D01*
X249483Y782600D01*
X249817D01*
X250150Y782725D01*
X250400Y782933D01*
X250525Y783225D01*
X250442Y783517D01*
X250233Y783767D01*
X249858Y783933D01*
X249358Y784017D01*
X249067Y784183D01*
X248942Y784475D01*
X249025Y784767D01*
X249233Y784975D01*
X249525Y785100D01*
X249817D01*
X250108Y785017D01*
X250358Y784808D01*
G01X251708Y782600D02*
X252750Y785100D01*
X253792Y782600D01*
G01X253417Y783475D02*
X252083D01*
G01X254975Y782933D02*
X255308Y782725D01*
X255683Y782600D01*
X256017D01*
X256350Y782725D01*
X256600Y782933D01*
X256725Y783225D01*
X256642Y783517D01*
X256433Y783767D01*
X256058Y783933D01*
X255558Y784017D01*
X255267Y784183D01*
X255142Y784475D01*
X255225Y784767D01*
X255433Y784975D01*
X255725Y785100D01*
X256017D01*
X256308Y785017D01*
X256558Y784808D01*
G01X258950Y782600D02*
Y785100D01*
X258450Y784600D01*
G01Y782600D02*
X259450D01*
G01X261133Y783100D02*
X261383Y782808D01*
X261717Y782642D01*
X262092Y782600D01*
X262425Y782642D01*
X262758Y782850D01*
X262967Y783100D01*
X263008Y783350D01*
X262925Y783642D01*
X262633Y783850D01*
X262342Y783933D01*
X261967D01*
G01X262342D02*
X262592Y784058D01*
X262800Y784267D01*
X262883Y784517D01*
X262800Y784767D01*
X262592Y784975D01*
X262217Y785100D01*
X261842Y785058D01*
X261467Y784892D01*
G01X227934Y946717D02*
X225434D01*
Y947758D01*
X225559Y948092D01*
X225726Y948300D01*
X226059Y948383D01*
X226392Y948300D01*
X226601Y948050D01*
X226726Y947758D01*
Y946717D01*
G01Y947758D02*
X227934Y948383D01*
G01Y950650D02*
X225434D01*
X225934Y950150D01*
G01X227934D02*
Y951150D01*
G01X227642Y953042D02*
X227851Y953333D01*
X227934Y953667D01*
X227851Y954000D01*
X227601Y954292D01*
X227226Y954500D01*
X226851Y954583D01*
X226392D01*
X226017Y954500D01*
X225684Y954292D01*
X225517Y954042D01*
X225434Y953750D01*
X225517Y953417D01*
X225684Y953167D01*
X225934Y953000D01*
X226267Y952917D01*
X226559Y953000D01*
X226851Y953208D01*
X227017Y953458D01*
X227059Y953750D01*
X226976Y954083D01*
X226767Y954333D01*
X226392Y954583D01*
G01X227642Y956142D02*
X227851Y956433D01*
X227934Y956767D01*
X227851Y957100D01*
X227601Y957392D01*
X227226Y957600D01*
X226851Y957683D01*
X226392D01*
X226017Y957600D01*
X225684Y957392D01*
X225517Y957142D01*
X225434Y956850D01*
X225517Y956517D01*
X225684Y956267D01*
X225934Y956100D01*
X226267Y956017D01*
X226559Y956100D01*
X226851Y956308D01*
X227017Y956558D01*
X227059Y956850D01*
X226976Y957183D01*
X226767Y957433D01*
X226392Y957683D01*
G01X218336Y1127004D02*
X223386D01*
Y1225704D01*
X248036D01*
Y1041304D01*
X223386D01*
Y1100004D01*
X218336D01*
Y1127004D01*
G01X255874Y1069519D02*
X255624Y1069644D01*
X255332Y1069727D01*
X254999D01*
X254624Y1069602D01*
X254332Y1069394D01*
X254124Y1069144D01*
X253957Y1068727D01*
X253915Y1068352D01*
X253999Y1067977D01*
X254124Y1067727D01*
X254374Y1067477D01*
X254665Y1067310D01*
X254957Y1067227D01*
X255249D01*
X255540Y1067310D01*
X255790Y1067435D01*
X255999Y1067602D01*
G01X257140D02*
X257390Y1067394D01*
X257682Y1067269D01*
X258057Y1067227D01*
X258432Y1067310D01*
X258724Y1067477D01*
X258932Y1067769D01*
X258974Y1068102D01*
X258890Y1068435D01*
X258682Y1068644D01*
X258390Y1068810D01*
X258099Y1068852D01*
X257807Y1068810D01*
X257432Y1068644D01*
X257557Y1069727D01*
X258682D01*
G01X260365Y1069310D02*
X260615Y1069560D01*
X260907Y1069685D01*
X261240Y1069727D01*
X261657Y1069644D01*
X261949Y1069435D01*
X262032Y1069185D01*
X261990Y1068935D01*
X261824Y1068727D01*
X260990Y1068310D01*
X260615Y1068019D01*
X260365Y1067602D01*
X260282Y1067227D01*
X262032D01*
G01X255895Y1073623D02*
X255645Y1073748D01*
X255353Y1073831D01*
X255020D01*
X254645Y1073706D01*
X254353Y1073498D01*
X254145Y1073248D01*
X253978Y1072831D01*
X253936Y1072456D01*
X254020Y1072081D01*
X254145Y1071831D01*
X254395Y1071581D01*
X254686Y1071414D01*
X254978Y1071331D01*
X255270D01*
X255561Y1071414D01*
X255811Y1071539D01*
X256020Y1071706D01*
G01X257161D02*
X257411Y1071498D01*
X257703Y1071373D01*
X258078Y1071331D01*
X258453Y1071414D01*
X258745Y1071581D01*
X258953Y1071873D01*
X258995Y1072206D01*
X258911Y1072539D01*
X258703Y1072748D01*
X258411Y1072914D01*
X258120Y1072956D01*
X257828Y1072914D01*
X257453Y1072748D01*
X257578Y1073831D01*
X258703D01*
G01X261178Y1071331D02*
Y1073831D01*
X260678Y1073331D01*
G01Y1071331D02*
X261678D01*
G01X253666Y1140773D02*
Y1143273D01*
X254707D01*
X255041Y1143148D01*
X255249Y1142981D01*
X255332Y1142648D01*
X255249Y1142315D01*
X254999Y1142106D01*
X254707Y1141981D01*
X253666D01*
G01X254707D02*
X255332Y1140773D01*
G01X257599D02*
Y1143273D01*
X257099Y1142773D01*
G01Y1140773D02*
X258099D01*
G01X259782Y1141148D02*
X260032Y1140940D01*
X260324Y1140815D01*
X260699Y1140773D01*
X261074Y1140856D01*
X261366Y1141023D01*
X261574Y1141315D01*
X261616Y1141648D01*
X261532Y1141981D01*
X261324Y1142190D01*
X261032Y1142356D01*
X260741Y1142398D01*
X260449Y1142356D01*
X260074Y1142190D01*
X260199Y1143273D01*
X261324D01*
G01X262882Y1141273D02*
X263132Y1140981D01*
X263466Y1140815D01*
X263841Y1140773D01*
X264174Y1140815D01*
X264507Y1141023D01*
X264716Y1141273D01*
X264757Y1141523D01*
X264674Y1141815D01*
X264382Y1142023D01*
X264091Y1142106D01*
X263716D01*
G01X264091D02*
X264341Y1142231D01*
X264549Y1142440D01*
X264632Y1142690D01*
X264549Y1142940D01*
X264341Y1143148D01*
X263966Y1143273D01*
X263591Y1143231D01*
X263216Y1143065D01*
G01X268849Y1148273D02*
Y1152273D01*
X261449D01*
G01X220500Y1132950D02*
X220458Y1132617D01*
X220292Y1132325D01*
X220042Y1132075D01*
X219750Y1131908D01*
X219417Y1131825D01*
X219083D01*
X218750Y1131908D01*
X218458Y1132075D01*
X218208Y1132325D01*
X218042Y1132617D01*
X218000Y1132950D01*
X218042Y1133283D01*
X218208Y1133575D01*
X218458Y1133825D01*
X218750Y1133992D01*
X219083Y1134075D01*
X219417D01*
X219750Y1133992D01*
X220042Y1133825D01*
X220292Y1133575D01*
X220458Y1133283D01*
X220500Y1132950D01*
G01X219833Y1133283D02*
X220500Y1133783D01*
G01X220125Y1135133D02*
X220333Y1135383D01*
X220458Y1135675D01*
X220500Y1136050D01*
X220417Y1136425D01*
X220250Y1136717D01*
X219958Y1136925D01*
X219625Y1136967D01*
X219292Y1136883D01*
X219083Y1136675D01*
X218917Y1136383D01*
X218875Y1136092D01*
X218917Y1135800D01*
X219083Y1135425D01*
X218000Y1135550D01*
Y1136675D01*
G01X258500Y1172900D02*
X261000D01*
G01X258500Y1171942D02*
Y1173858D01*
G01X261000Y1175167D02*
X258500D01*
Y1176167D01*
X258625Y1176500D01*
X258917Y1176750D01*
X259250Y1176833D01*
X259583Y1176750D01*
X259833Y1176542D01*
X259958Y1176167D01*
Y1175167D01*
G01X261000Y1179017D02*
X260458Y1179100D01*
X260000Y1179225D01*
X259583Y1179392D01*
X259125Y1179600D01*
X258500Y1179933D01*
Y1178267D01*
G01X255017Y1165000D02*
Y1167500D01*
X256058D01*
X256392Y1167375D01*
X256600Y1167208D01*
X256683Y1166875D01*
X256600Y1166542D01*
X256350Y1166333D01*
X256058Y1166208D01*
X255017D01*
G01X256058D02*
X256683Y1165000D01*
G01X258950D02*
Y1167500D01*
X258450Y1167000D01*
G01Y1165000D02*
X259450D01*
G01X261133Y1165375D02*
X261383Y1165167D01*
X261675Y1165042D01*
X262050Y1165000D01*
X262425Y1165083D01*
X262717Y1165250D01*
X262925Y1165542D01*
X262967Y1165875D01*
X262883Y1166208D01*
X262675Y1166417D01*
X262383Y1166583D01*
X262092Y1166625D01*
X261800Y1166583D01*
X261425Y1166417D01*
X261550Y1167500D01*
X262675D01*
G01X264233Y1165375D02*
X264483Y1165167D01*
X264775Y1165042D01*
X265150Y1165000D01*
X265525Y1165083D01*
X265817Y1165250D01*
X266025Y1165542D01*
X266067Y1165875D01*
X265983Y1166208D01*
X265775Y1166417D01*
X265483Y1166583D01*
X265192Y1166625D01*
X264900Y1166583D01*
X264525Y1166417D01*
X264650Y1167500D01*
X265775D01*
G01X256966Y1138965D02*
X256716Y1139090D01*
X256424Y1139173D01*
X256091D01*
X255716Y1139048D01*
X255424Y1138840D01*
X255216Y1138590D01*
X255049Y1138173D01*
X255007Y1137798D01*
X255091Y1137423D01*
X255216Y1137173D01*
X255466Y1136923D01*
X255757Y1136756D01*
X256049Y1136673D01*
X256341D01*
X256632Y1136756D01*
X256882Y1136881D01*
X257091Y1137048D01*
G01X258232D02*
X258482Y1136840D01*
X258774Y1136715D01*
X259149Y1136673D01*
X259524Y1136756D01*
X259816Y1136923D01*
X260024Y1137215D01*
X260066Y1137548D01*
X259982Y1137881D01*
X259774Y1138090D01*
X259482Y1138256D01*
X259191Y1138298D01*
X258899Y1138256D01*
X258524Y1138090D01*
X258649Y1139173D01*
X259774D01*
G01X261332Y1137048D02*
X261582Y1136840D01*
X261874Y1136715D01*
X262249Y1136673D01*
X262624Y1136756D01*
X262916Y1136923D01*
X263124Y1137215D01*
X263166Y1137548D01*
X263082Y1137881D01*
X262874Y1138090D01*
X262582Y1138256D01*
X262291Y1138298D01*
X261999Y1138256D01*
X261624Y1138090D01*
X261749Y1139173D01*
X262874D01*
G01X253890Y1184831D02*
Y1187331D01*
X254931D01*
X255265Y1187206D01*
X255473Y1187039D01*
X255556Y1186706D01*
X255473Y1186373D01*
X255223Y1186164D01*
X254931Y1186039D01*
X253890D01*
G01X254931D02*
X255556Y1184831D01*
G01X256906Y1185206D02*
X257156Y1184998D01*
X257448Y1184873D01*
X257823Y1184831D01*
X258198Y1184914D01*
X258490Y1185081D01*
X258698Y1185373D01*
X258740Y1185706D01*
X258656Y1186039D01*
X258448Y1186248D01*
X258156Y1186414D01*
X257865Y1186456D01*
X257573Y1186414D01*
X257198Y1186248D01*
X257323Y1187331D01*
X258448D01*
G01X260131Y1185873D02*
X260423Y1186164D01*
X260673Y1186331D01*
X261006Y1186414D01*
X261298Y1186331D01*
X261506Y1186164D01*
X261673Y1185914D01*
X261715Y1185623D01*
X261673Y1185373D01*
X261506Y1185123D01*
X261256Y1184914D01*
X260965Y1184831D01*
X260631Y1184914D01*
X260340Y1185164D01*
X260173Y1185539D01*
X260131Y1185956D01*
X260215Y1186498D01*
X260340Y1186789D01*
X260548Y1187081D01*
X260840Y1187289D01*
X261131Y1187331D01*
X261423Y1187248D01*
X261631Y1187039D01*
G01X263106Y1185206D02*
X263356Y1184998D01*
X263648Y1184873D01*
X264023Y1184831D01*
X264398Y1184914D01*
X264690Y1185081D01*
X264898Y1185373D01*
X264940Y1185706D01*
X264856Y1186039D01*
X264648Y1186248D01*
X264356Y1186414D01*
X264065Y1186456D01*
X263773Y1186414D01*
X263398Y1186248D01*
X263523Y1187331D01*
X264648D01*
G01X260594Y1204885D02*
X258094D01*
Y1205926D01*
X258219Y1206260D01*
X258386Y1206468D01*
X258719Y1206551D01*
X259052Y1206468D01*
X259261Y1206218D01*
X259386Y1205926D01*
Y1204885D01*
G01Y1205926D02*
X260594Y1206551D01*
G01X258511Y1208026D02*
X258261Y1208276D01*
X258136Y1208568D01*
X258094Y1208901D01*
X258177Y1209318D01*
X258386Y1209610D01*
X258636Y1209693D01*
X258886Y1209651D01*
X259094Y1209485D01*
X259511Y1208651D01*
X259802Y1208276D01*
X260219Y1208026D01*
X260594Y1207943D01*
Y1209693D01*
G01X260094Y1211001D02*
X260386Y1211251D01*
X260552Y1211585D01*
X260594Y1211960D01*
X260552Y1212293D01*
X260344Y1212626D01*
X260094Y1212835D01*
X259844Y1212876D01*
X259552Y1212793D01*
X259344Y1212501D01*
X259261Y1212210D01*
Y1211835D01*
G01Y1212210D02*
X259136Y1212460D01*
X258927Y1212668D01*
X258677Y1212751D01*
X258427Y1212668D01*
X258219Y1212460D01*
X258094Y1212085D01*
X258136Y1211710D01*
X258302Y1211335D01*
G01X258094Y1215018D02*
X258177Y1214685D01*
X258386Y1214435D01*
X258636Y1214268D01*
X258969Y1214143D01*
X259344Y1214101D01*
X259719Y1214143D01*
X260052Y1214268D01*
X260302Y1214435D01*
X260511Y1214685D01*
X260594Y1215018D01*
X260511Y1215351D01*
X260302Y1215601D01*
X260052Y1215768D01*
X259719Y1215893D01*
X259344Y1215935D01*
X258969Y1215893D01*
X258636Y1215768D01*
X258386Y1215601D01*
X258177Y1215351D01*
X258094Y1215018D01*
G01X265594Y1204885D02*
X263094D01*
Y1205926D01*
X263219Y1206260D01*
X263386Y1206468D01*
X263719Y1206551D01*
X264052Y1206468D01*
X264261Y1206218D01*
X264386Y1205926D01*
Y1204885D01*
G01Y1205926D02*
X265594Y1206551D01*
G01X263511Y1208026D02*
X263261Y1208276D01*
X263136Y1208568D01*
X263094Y1208901D01*
X263177Y1209318D01*
X263386Y1209610D01*
X263636Y1209693D01*
X263886Y1209651D01*
X264094Y1209485D01*
X264511Y1208651D01*
X264802Y1208276D01*
X265219Y1208026D01*
X265594Y1207943D01*
Y1209693D01*
G01X263511Y1211126D02*
X263261Y1211376D01*
X263136Y1211668D01*
X263094Y1212001D01*
X263177Y1212418D01*
X263386Y1212710D01*
X263636Y1212793D01*
X263886Y1212751D01*
X264094Y1212585D01*
X264511Y1211751D01*
X264802Y1211376D01*
X265219Y1211126D01*
X265594Y1211043D01*
Y1212793D01*
G01Y1215018D02*
X265552Y1215310D01*
X265427Y1215643D01*
X265219Y1215851D01*
X264927Y1215935D01*
X264636Y1215851D01*
X264386Y1215601D01*
X264261Y1215226D01*
Y1214810D01*
X264177Y1214560D01*
X263969Y1214351D01*
X263677Y1214268D01*
X263386Y1214393D01*
X263177Y1214685D01*
X263094Y1215018D01*
X263177Y1215351D01*
X263386Y1215643D01*
X263677Y1215768D01*
X263969Y1215685D01*
X264177Y1215476D01*
X264261Y1215226D01*
Y1214810D01*
X264386Y1214435D01*
X264636Y1214185D01*
X264927Y1214101D01*
X265219Y1214185D01*
X265427Y1214393D01*
X265552Y1214726D01*
X265594Y1215018D01*
G01X226061Y1234004D02*
Y1236504D01*
G01X227811D02*
Y1234004D01*
G01Y1235254D02*
X226061D01*
G01X229119Y1234004D02*
Y1236504D01*
X229953D01*
X230286Y1236379D01*
X230536Y1236212D01*
X230744Y1235962D01*
X230911Y1235671D01*
X230953Y1235254D01*
X230911Y1234837D01*
X230744Y1234546D01*
X230536Y1234296D01*
X230286Y1234129D01*
X229953Y1234004D01*
X229119D01*
G01X232219D02*
Y1236504D01*
X233053D01*
X233386Y1236379D01*
X233636Y1236212D01*
X233844Y1235962D01*
X234011Y1235671D01*
X234053Y1235254D01*
X234011Y1234837D01*
X233844Y1234546D01*
X233636Y1234296D01*
X233386Y1234129D01*
X233053Y1234004D01*
X232219D01*
G01X235361Y1234337D02*
X235694Y1234129D01*
X236069Y1234004D01*
X236403D01*
X236736Y1234129D01*
X236986Y1234337D01*
X237111Y1234629D01*
X237028Y1234921D01*
X236819Y1235171D01*
X236444Y1235337D01*
X235944Y1235421D01*
X235653Y1235587D01*
X235528Y1235879D01*
X235611Y1236171D01*
X235819Y1236379D01*
X236111Y1236504D01*
X236403D01*
X236694Y1236421D01*
X236944Y1236212D01*
G01X238294Y1234004D02*
X239336Y1236504D01*
X240378Y1234004D01*
G01X240003Y1234879D02*
X238669D01*
G01X241561Y1234337D02*
X241894Y1234129D01*
X242269Y1234004D01*
X242603D01*
X242936Y1234129D01*
X243186Y1234337D01*
X243311Y1234629D01*
X243228Y1234921D01*
X243019Y1235171D01*
X242644Y1235337D01*
X242144Y1235421D01*
X241853Y1235587D01*
X241728Y1235879D01*
X241811Y1236171D01*
X242019Y1236379D01*
X242311Y1236504D01*
X242603D01*
X242894Y1236421D01*
X243144Y1236212D01*
G01X245536Y1234004D02*
Y1236504D01*
X245036Y1236004D01*
G01Y1234004D02*
X246036D01*
G01X312488Y62355D02*
Y64855D01*
X313529D01*
X313863Y64730D01*
X314071Y64563D01*
X314154Y64230D01*
X314071Y63897D01*
X313821Y63688D01*
X313529Y63563D01*
X312488D01*
G01X313529D02*
X314154Y62355D01*
G01X315504Y62855D02*
X315754Y62563D01*
X316088Y62397D01*
X316463Y62355D01*
X316796Y62397D01*
X317129Y62605D01*
X317338Y62855D01*
X317379Y63105D01*
X317296Y63397D01*
X317004Y63605D01*
X316713Y63688D01*
X316338D01*
G01X316713D02*
X316963Y63813D01*
X317171Y64022D01*
X317254Y64272D01*
X317171Y64522D01*
X316963Y64730D01*
X316588Y64855D01*
X316213Y64813D01*
X315838Y64647D01*
G01X320021Y62355D02*
Y64855D01*
X318479Y63063D01*
X320563D01*
G01X312522Y57879D02*
Y60379D01*
X313563D01*
X313897Y60254D01*
X314105Y60087D01*
X314188Y59754D01*
X314105Y59421D01*
X313855Y59212D01*
X313563Y59087D01*
X312522D01*
G01X313563D02*
X314188Y57879D01*
G01X315538Y58379D02*
X315788Y58087D01*
X316122Y57921D01*
X316497Y57879D01*
X316830Y57921D01*
X317163Y58129D01*
X317372Y58379D01*
X317413Y58629D01*
X317330Y58921D01*
X317038Y59129D01*
X316747Y59212D01*
X316372D01*
G01X316747D02*
X316997Y59337D01*
X317205Y59546D01*
X317288Y59796D01*
X317205Y60046D01*
X316997Y60254D01*
X316622Y60379D01*
X316247Y60337D01*
X315872Y60171D01*
G01X318847Y58171D02*
X319138Y57962D01*
X319472Y57879D01*
X319805Y57962D01*
X320097Y58212D01*
X320305Y58587D01*
X320388Y58962D01*
Y59421D01*
X320305Y59796D01*
X320097Y60129D01*
X319847Y60296D01*
X319555Y60379D01*
X319222Y60296D01*
X318972Y60129D01*
X318805Y59879D01*
X318722Y59546D01*
X318805Y59254D01*
X319013Y58962D01*
X319263Y58796D01*
X319555Y58754D01*
X319888Y58837D01*
X320138Y59046D01*
X320388Y59421D01*
G01X313755Y70379D02*
Y66379D01*
X321155D01*
G01X301000Y66767D02*
X298500D01*
Y67808D01*
X298625Y68142D01*
X298792Y68350D01*
X299125Y68433D01*
X299458Y68350D01*
X299667Y68100D01*
X299792Y67808D01*
Y66767D01*
G01Y67808D02*
X301000Y68433D01*
G01Y71200D02*
X298500D01*
X300292Y69658D01*
Y71742D01*
G01X298917Y73008D02*
X298667Y73258D01*
X298542Y73550D01*
X298500Y73883D01*
X298583Y74300D01*
X298792Y74592D01*
X299042Y74675D01*
X299292Y74633D01*
X299500Y74467D01*
X299917Y73633D01*
X300208Y73258D01*
X300625Y73008D01*
X301000Y72925D01*
Y74675D01*
G01X304955Y66479D02*
X308955D01*
Y73879D01*
G01X321121Y70855D02*
Y74855D01*
X313721D01*
G01X310483Y91667D02*
Y89875D01*
X310650Y89500D01*
X310983Y89250D01*
X311400Y89167D01*
X311817Y89250D01*
X312150Y89500D01*
X312317Y89875D01*
Y91667D01*
G01X314500Y89167D02*
Y91667D01*
X314000Y91167D01*
G01Y89167D02*
X315000D01*
G01X317517D02*
X317600Y89709D01*
X317725Y90167D01*
X317892Y90584D01*
X318100Y91042D01*
X318433Y91667D01*
X316767D01*
G01X301020Y104348D02*
X300895Y104098D01*
X300812Y103806D01*
Y103473D01*
X300937Y103098D01*
X301145Y102806D01*
X301395Y102598D01*
X301812Y102431D01*
X302187Y102389D01*
X302562Y102473D01*
X302812Y102598D01*
X303062Y102848D01*
X303229Y103139D01*
X303312Y103431D01*
Y103723D01*
X303229Y104014D01*
X303104Y104264D01*
X302937Y104473D01*
G01X303312Y106531D02*
X300812D01*
X301312Y106031D01*
G01X303312D02*
Y107031D01*
G01Y109631D02*
X300812D01*
X301312Y109131D01*
G01X303312D02*
Y110131D01*
G01X305520Y103848D02*
X305395Y103598D01*
X305312Y103306D01*
Y102973D01*
X305437Y102598D01*
X305645Y102306D01*
X305895Y102098D01*
X306312Y101931D01*
X306687Y101889D01*
X307062Y101973D01*
X307312Y102098D01*
X307562Y102348D01*
X307729Y102639D01*
X307812Y102931D01*
Y103223D01*
X307729Y103514D01*
X307604Y103764D01*
X307437Y103973D01*
G01X307812Y106031D02*
X305312D01*
X305812Y105531D01*
G01X307812D02*
Y106531D01*
G01X305729Y108339D02*
X305479Y108589D01*
X305354Y108881D01*
X305312Y109214D01*
X305395Y109631D01*
X305604Y109923D01*
X305854Y110006D01*
X306104Y109964D01*
X306312Y109798D01*
X306729Y108964D01*
X307020Y108589D01*
X307437Y108339D01*
X307812Y108256D01*
Y110006D01*
G01X315334Y136467D02*
X312834D01*
Y137508D01*
X312959Y137842D01*
X313126Y138050D01*
X313459Y138133D01*
X313792Y138050D01*
X314001Y137800D01*
X314126Y137508D01*
Y136467D01*
G01Y137508D02*
X315334Y138133D01*
G01Y140400D02*
X312834D01*
X313334Y139900D01*
G01X315334D02*
Y140900D01*
G01X313251Y142708D02*
X313001Y142958D01*
X312876Y143250D01*
X312834Y143583D01*
X312917Y144000D01*
X313126Y144292D01*
X313376Y144375D01*
X313626Y144333D01*
X313834Y144167D01*
X314251Y143333D01*
X314542Y142958D01*
X314959Y142708D01*
X315334Y142625D01*
Y144375D01*
G01X315042Y145892D02*
X315251Y146183D01*
X315334Y146517D01*
X315251Y146850D01*
X315001Y147142D01*
X314626Y147350D01*
X314251Y147433D01*
X313792D01*
X313417Y147350D01*
X313084Y147142D01*
X312917Y146892D01*
X312834Y146600D01*
X312917Y146267D01*
X313084Y146017D01*
X313334Y145850D01*
X313667Y145767D01*
X313959Y145850D01*
X314251Y146058D01*
X314417Y146308D01*
X314459Y146600D01*
X314376Y146933D01*
X314167Y147183D01*
X313792Y147433D01*
G01X315334Y149617D02*
X314792Y149700D01*
X314334Y149825D01*
X313917Y149992D01*
X313459Y150200D01*
X312834Y150533D01*
Y148867D01*
G01X312370Y119941D02*
X316370D01*
Y127341D01*
G01X315000Y163483D02*
X312500D01*
Y164317D01*
X312625Y164650D01*
X312792Y164900D01*
X313042Y165108D01*
X313333Y165275D01*
X313750Y165317D01*
X314167Y165275D01*
X314458Y165108D01*
X314708Y164900D01*
X314875Y164650D01*
X315000Y164317D01*
Y163483D01*
G01X312917Y166708D02*
X312667Y166958D01*
X312542Y167250D01*
X312500Y167583D01*
X312583Y168000D01*
X312792Y168292D01*
X313042Y168375D01*
X313292Y168333D01*
X313500Y168167D01*
X313917Y167333D01*
X314208Y166958D01*
X314625Y166708D01*
X315000Y166625D01*
Y168375D01*
G01X313958Y169808D02*
X313667Y170100D01*
X313500Y170350D01*
X313417Y170683D01*
X313500Y170975D01*
X313667Y171183D01*
X313917Y171350D01*
X314208Y171392D01*
X314458Y171350D01*
X314708Y171183D01*
X314917Y170933D01*
X315000Y170642D01*
X314917Y170308D01*
X314667Y170017D01*
X314292Y169850D01*
X313875Y169808D01*
X313333Y169892D01*
X313042Y170017D01*
X312750Y170225D01*
X312542Y170517D01*
X312500Y170808D01*
X312583Y171100D01*
X312792Y171308D01*
G01X298817Y173500D02*
Y176000D01*
X299858D01*
X300192Y175875D01*
X300400Y175708D01*
X300483Y175375D01*
X300400Y175042D01*
X300150Y174833D01*
X299858Y174708D01*
X298817D01*
G01X299858D02*
X300483Y173500D01*
G01X302667D02*
X302750Y174042D01*
X302875Y174500D01*
X303042Y174917D01*
X303250Y175375D01*
X303583Y176000D01*
X301917D01*
G01X306350Y173500D02*
Y176000D01*
X304808Y174208D01*
X306892D01*
G01X308158Y175583D02*
X308408Y175833D01*
X308700Y175958D01*
X309033Y176000D01*
X309450Y175917D01*
X309742Y175708D01*
X309825Y175458D01*
X309783Y175208D01*
X309617Y175000D01*
X308783Y174583D01*
X308408Y174292D01*
X308158Y173875D01*
X308075Y173500D01*
X309825D01*
G01X302962Y181661D02*
Y177661D01*
X310362D01*
G01X305500Y183117D02*
X303000D01*
Y184158D01*
X303125Y184492D01*
X303292Y184700D01*
X303625Y184783D01*
X303958Y184700D01*
X304167Y184450D01*
X304292Y184158D01*
Y183117D01*
G01Y184158D02*
X305500Y184783D01*
G01Y186967D02*
X304958Y187050D01*
X304500Y187175D01*
X304083Y187342D01*
X303625Y187550D01*
X303000Y187883D01*
Y186217D01*
G01X305500Y190650D02*
X303000D01*
X304792Y189108D01*
Y191192D01*
G01X305500Y193750D02*
X303000D01*
X304792Y192208D01*
Y194292D01*
G01X306362Y182061D02*
X310362D01*
Y189461D01*
G01X298679Y201061D02*
Y203561D01*
X299720D01*
X300054Y203436D01*
X300262Y203269D01*
X300345Y202936D01*
X300262Y202603D01*
X300012Y202394D01*
X299720Y202269D01*
X298679D01*
G01X299720D02*
X300345Y201061D01*
G01X302529D02*
X302612Y201603D01*
X302737Y202061D01*
X302904Y202478D01*
X303112Y202936D01*
X303445Y203561D01*
X301779D01*
G01X304795Y201561D02*
X305045Y201269D01*
X305379Y201103D01*
X305754Y201061D01*
X306087Y201103D01*
X306420Y201311D01*
X306629Y201561D01*
X306670Y201811D01*
X306587Y202103D01*
X306295Y202311D01*
X306004Y202394D01*
X305629D01*
G01X306004D02*
X306254Y202519D01*
X306462Y202728D01*
X306545Y202978D01*
X306462Y203228D01*
X306254Y203436D01*
X305879Y203561D01*
X305504Y203519D01*
X305129Y203353D01*
G01X307895Y201436D02*
X308145Y201228D01*
X308437Y201103D01*
X308812Y201061D01*
X309187Y201144D01*
X309479Y201311D01*
X309687Y201603D01*
X309729Y201936D01*
X309645Y202269D01*
X309437Y202478D01*
X309145Y202644D01*
X308854Y202686D01*
X308562Y202644D01*
X308187Y202478D01*
X308312Y203561D01*
X309437D01*
G01X310962Y207061D02*
Y203061D01*
X318362D01*
G01X290879Y210561D02*
Y213061D01*
X291920D01*
X292254Y212936D01*
X292462Y212769D01*
X292545Y212436D01*
X292462Y212103D01*
X292212Y211894D01*
X291920Y211769D01*
X290879D01*
G01X291920D02*
X292545Y210561D01*
G01X294729D02*
X294812Y211103D01*
X294937Y211561D01*
X295104Y211978D01*
X295312Y212436D01*
X295645Y213061D01*
X293979D01*
G01X298412Y210561D02*
Y213061D01*
X296870Y211269D01*
X298954D01*
G01X300095Y211061D02*
X300345Y210769D01*
X300679Y210603D01*
X301054Y210561D01*
X301387Y210603D01*
X301720Y210811D01*
X301929Y211061D01*
X301970Y211311D01*
X301887Y211603D01*
X301595Y211811D01*
X301304Y211894D01*
X300929D01*
G01X301304D02*
X301554Y212019D01*
X301762Y212228D01*
X301845Y212478D01*
X301762Y212728D01*
X301554Y212936D01*
X301179Y213061D01*
X300804Y213019D01*
X300429Y212853D01*
G01X310562Y208561D02*
Y212561D01*
X303162D01*
G01X311850Y194000D02*
X311517Y194042D01*
X311225Y194208D01*
X310975Y194458D01*
X310808Y194750D01*
X310725Y195083D01*
Y195417D01*
X310808Y195750D01*
X310975Y196042D01*
X311225Y196292D01*
X311517Y196458D01*
X311850Y196500D01*
X312183Y196458D01*
X312475Y196292D01*
X312725Y196042D01*
X312892Y195750D01*
X312975Y195417D01*
Y195083D01*
X312892Y194750D01*
X312725Y194458D01*
X312475Y194208D01*
X312183Y194042D01*
X311850Y194000D01*
G01X312183Y194667D02*
X312683Y194000D01*
G01X314950D02*
Y196500D01*
X314450Y196000D01*
G01Y194000D02*
X315450D01*
G01X317133Y194375D02*
X317383Y194167D01*
X317675Y194042D01*
X318050Y194000D01*
X318425Y194083D01*
X318717Y194250D01*
X318925Y194542D01*
X318967Y194875D01*
X318883Y195208D01*
X318675Y195417D01*
X318383Y195583D01*
X318092Y195625D01*
X317800Y195583D01*
X317425Y195417D01*
X317550Y196500D01*
X318675D01*
G01X321067Y194000D02*
X321150Y194542D01*
X321275Y195000D01*
X321442Y195417D01*
X321650Y195875D01*
X321983Y196500D01*
X320317D01*
G01X318362Y176061D02*
X311362D01*
G01D02*
Y192161D01*
G01D02*
X318362D01*
G01X300429Y207453D02*
X300179Y207578D01*
X299887Y207661D01*
X299554D01*
X299179Y207536D01*
X298887Y207328D01*
X298679Y207078D01*
X298512Y206661D01*
X298470Y206286D01*
X298554Y205911D01*
X298679Y205661D01*
X298929Y205411D01*
X299220Y205244D01*
X299512Y205161D01*
X299804D01*
X300095Y205244D01*
X300345Y205369D01*
X300554Y205536D01*
G01X301695Y205661D02*
X301945Y205369D01*
X302279Y205203D01*
X302654Y205161D01*
X302987Y205203D01*
X303320Y205411D01*
X303529Y205661D01*
X303570Y205911D01*
X303487Y206203D01*
X303195Y206411D01*
X302904Y206494D01*
X302529D01*
G01X302904D02*
X303154Y206619D01*
X303362Y206828D01*
X303445Y207078D01*
X303362Y207328D01*
X303154Y207536D01*
X302779Y207661D01*
X302404Y207619D01*
X302029Y207453D01*
G01X305712Y205161D02*
X306004Y205203D01*
X306337Y205328D01*
X306545Y205536D01*
X306629Y205828D01*
X306545Y206119D01*
X306295Y206369D01*
X305920Y206494D01*
X305504D01*
X305254Y206578D01*
X305045Y206786D01*
X304962Y207078D01*
X305087Y207369D01*
X305379Y207578D01*
X305712Y207661D01*
X306045Y207578D01*
X306337Y207369D01*
X306462Y207078D01*
X306379Y206786D01*
X306170Y206578D01*
X305920Y206494D01*
X305504D01*
X305129Y206369D01*
X304879Y206119D01*
X304795Y205828D01*
X304879Y205536D01*
X305087Y205328D01*
X305420Y205203D01*
X305712Y205161D01*
G01X308020Y206203D02*
X308312Y206494D01*
X308562Y206661D01*
X308895Y206744D01*
X309187Y206661D01*
X309395Y206494D01*
X309562Y206244D01*
X309604Y205953D01*
X309562Y205703D01*
X309395Y205453D01*
X309145Y205244D01*
X308854Y205161D01*
X308520Y205244D01*
X308229Y205494D01*
X308062Y205869D01*
X308020Y206286D01*
X308104Y206828D01*
X308229Y207119D01*
X308437Y207411D01*
X308729Y207619D01*
X309020Y207661D01*
X309312Y207578D01*
X309520Y207369D01*
G01X314062Y250661D02*
Y258661D01*
X331662D01*
Y250661D01*
X314062D01*
G01X302767Y261792D02*
X302517Y261917D01*
X302225Y262000D01*
X301892D01*
X301517Y261875D01*
X301225Y261667D01*
X301017Y261417D01*
X300850Y261000D01*
X300808Y260625D01*
X300892Y260250D01*
X301017Y260000D01*
X301267Y259750D01*
X301558Y259583D01*
X301850Y259500D01*
X302142D01*
X302433Y259583D01*
X302683Y259708D01*
X302892Y259875D01*
G01X304033Y260000D02*
X304283Y259708D01*
X304617Y259542D01*
X304992Y259500D01*
X305325Y259542D01*
X305658Y259750D01*
X305867Y260000D01*
X305908Y260250D01*
X305825Y260542D01*
X305533Y260750D01*
X305242Y260833D01*
X304867D01*
G01X305242D02*
X305492Y260958D01*
X305700Y261167D01*
X305783Y261417D01*
X305700Y261667D01*
X305492Y261875D01*
X305117Y262000D01*
X304742Y261958D01*
X304367Y261792D01*
G01X308050Y259500D02*
X308342Y259542D01*
X308675Y259667D01*
X308883Y259875D01*
X308967Y260167D01*
X308883Y260458D01*
X308633Y260708D01*
X308258Y260833D01*
X307842D01*
X307592Y260917D01*
X307383Y261125D01*
X307300Y261417D01*
X307425Y261708D01*
X307717Y261917D01*
X308050Y262000D01*
X308383Y261917D01*
X308675Y261708D01*
X308800Y261417D01*
X308717Y261125D01*
X308508Y260917D01*
X308258Y260833D01*
X307842D01*
X307467Y260708D01*
X307217Y260458D01*
X307133Y260167D01*
X307217Y259875D01*
X307425Y259667D01*
X307758Y259542D01*
X308050Y259500D01*
G01X310358Y261583D02*
X310608Y261833D01*
X310900Y261958D01*
X311233Y262000D01*
X311650Y261917D01*
X311942Y261708D01*
X312025Y261458D01*
X311983Y261208D01*
X311817Y261000D01*
X310983Y260583D01*
X310608Y260292D01*
X310358Y259875D01*
X310275Y259500D01*
X312025D01*
G01X294000Y222850D02*
X293958Y222517D01*
X293792Y222225D01*
X293542Y221975D01*
X293250Y221808D01*
X292917Y221725D01*
X292583D01*
X292250Y221808D01*
X291958Y221975D01*
X291708Y222225D01*
X291542Y222517D01*
X291500Y222850D01*
X291542Y223183D01*
X291708Y223475D01*
X291958Y223725D01*
X292250Y223892D01*
X292583Y223975D01*
X292917D01*
X293250Y223892D01*
X293542Y223725D01*
X293792Y223475D01*
X293958Y223183D01*
X294000Y222850D01*
G01X293333Y223183D02*
X294000Y223683D01*
G01Y225950D02*
X291500D01*
X292000Y225450D01*
G01X294000D02*
Y226450D01*
G01X293625Y228133D02*
X293833Y228383D01*
X293958Y228675D01*
X294000Y229050D01*
X293917Y229425D01*
X293750Y229717D01*
X293458Y229925D01*
X293125Y229967D01*
X292792Y229883D01*
X292583Y229675D01*
X292417Y229383D01*
X292375Y229092D01*
X292417Y228800D01*
X292583Y228425D01*
X291500Y228550D01*
Y229675D01*
G01X294000Y232150D02*
X293958Y232442D01*
X293833Y232775D01*
X293625Y232983D01*
X293333Y233067D01*
X293042Y232983D01*
X292792Y232733D01*
X292667Y232358D01*
Y231942D01*
X292583Y231692D01*
X292375Y231483D01*
X292083Y231400D01*
X291792Y231525D01*
X291583Y231817D01*
X291500Y232150D01*
X291583Y232483D01*
X291792Y232775D01*
X292083Y232900D01*
X292375Y232817D01*
X292583Y232608D01*
X292667Y232358D01*
Y231942D01*
X292792Y231567D01*
X293042Y231317D01*
X293333Y231233D01*
X293625Y231317D01*
X293833Y231525D01*
X293958Y231858D01*
X294000Y232150D01*
G01X296062Y230061D02*
X315262D01*
Y241261D01*
X296062D01*
Y230061D01*
X296462D01*
G01X296162Y237661D02*
X298262Y235861D01*
X296162Y233661D01*
G01X292629Y216953D02*
X292379Y217078D01*
X292087Y217161D01*
X291754D01*
X291379Y217036D01*
X291087Y216828D01*
X290879Y216578D01*
X290712Y216161D01*
X290670Y215786D01*
X290754Y215411D01*
X290879Y215161D01*
X291129Y214911D01*
X291420Y214744D01*
X291712Y214661D01*
X292004D01*
X292295Y214744D01*
X292545Y214869D01*
X292754Y215036D01*
G01X293895Y215161D02*
X294145Y214869D01*
X294479Y214703D01*
X294854Y214661D01*
X295187Y214703D01*
X295520Y214911D01*
X295729Y215161D01*
X295770Y215411D01*
X295687Y215703D01*
X295395Y215911D01*
X295104Y215994D01*
X294729D01*
G01X295104D02*
X295354Y216119D01*
X295562Y216328D01*
X295645Y216578D01*
X295562Y216828D01*
X295354Y217036D01*
X294979Y217161D01*
X294604Y217119D01*
X294229Y216953D01*
G01X297912Y214661D02*
X298204Y214703D01*
X298537Y214828D01*
X298745Y215036D01*
X298829Y215328D01*
X298745Y215619D01*
X298495Y215869D01*
X298120Y215994D01*
X297704D01*
X297454Y216078D01*
X297245Y216286D01*
X297162Y216578D01*
X297287Y216869D01*
X297579Y217078D01*
X297912Y217161D01*
X298245Y217078D01*
X298537Y216869D01*
X298662Y216578D01*
X298579Y216286D01*
X298370Y216078D01*
X298120Y215994D01*
X297704D01*
X297329Y215869D01*
X297079Y215619D01*
X296995Y215328D01*
X297079Y215036D01*
X297287Y214828D01*
X297620Y214703D01*
X297912Y214661D01*
G01X300929D02*
X301012Y215203D01*
X301137Y215661D01*
X301304Y216078D01*
X301512Y216536D01*
X301845Y217161D01*
X300179D01*
G01X308958Y356500D02*
Y359000D01*
X310542D01*
G01X309958Y357792D02*
X308958D01*
G01X312017Y359000D02*
Y356500D01*
X313683D01*
G01X316783D02*
X315117D01*
Y359000D01*
X316783D01*
G01X316117Y357792D02*
X315117D01*
G01X318133Y356500D02*
Y359000D01*
X318967D01*
X319300Y358875D01*
X319550Y358708D01*
X319758Y358458D01*
X319925Y358167D01*
X319967Y357750D01*
X319925Y357333D01*
X319758Y357042D01*
X319550Y356792D01*
X319300Y356625D01*
X318967Y356500D01*
X318133D01*
G01X322150D02*
Y359000D01*
X321650Y358500D01*
G01Y356500D02*
X322650D01*
G01X324333Y356875D02*
X324583Y356667D01*
X324875Y356542D01*
X325250Y356500D01*
X325625Y356583D01*
X325917Y356750D01*
X326125Y357042D01*
X326167Y357375D01*
X326083Y357708D01*
X325875Y357917D01*
X325583Y358083D01*
X325292Y358125D01*
X325000Y358083D01*
X324625Y357917D01*
X324750Y359000D01*
X325875D01*
G01X314104Y366054D02*
Y377254D01*
X322904D01*
Y366054D01*
X314104D01*
G01X298653Y496142D02*
Y510142D01*
G01X285653Y496142D02*
X298653D01*
G01X285653Y510142D02*
Y496142D01*
G01X312888Y496105D02*
Y510105D01*
G01X299888Y496105D02*
X312888D01*
G01X299888Y510105D02*
Y496105D01*
G01X303026Y529378D02*
Y531878D01*
X304067D01*
X304401Y531753D01*
X304609Y531586D01*
X304692Y531253D01*
X304609Y530920D01*
X304359Y530711D01*
X304067Y530586D01*
X303026D01*
G01X304067D02*
X304692Y529378D01*
G01X306042Y529753D02*
X306292Y529545D01*
X306584Y529420D01*
X306959Y529378D01*
X307334Y529461D01*
X307626Y529628D01*
X307834Y529920D01*
X307876Y530253D01*
X307792Y530586D01*
X307584Y530795D01*
X307292Y530961D01*
X307001Y531003D01*
X306709Y530961D01*
X306334Y530795D01*
X306459Y531878D01*
X307584D01*
G01X310059Y529378D02*
Y531878D01*
X309559Y531378D01*
G01Y529378D02*
X310559D01*
G01X313159Y531878D02*
X312826Y531795D01*
X312576Y531586D01*
X312409Y531336D01*
X312284Y531003D01*
X312242Y530628D01*
X312284Y530253D01*
X312409Y529920D01*
X312576Y529670D01*
X312826Y529461D01*
X313159Y529378D01*
X313492Y529461D01*
X313742Y529670D01*
X313909Y529920D01*
X314034Y530253D01*
X314076Y530628D01*
X314034Y531003D01*
X313909Y531336D01*
X313742Y531586D01*
X313492Y531795D01*
X313159Y531878D01*
G01X312209Y510878D02*
Y514878D01*
X304809D01*
G01X288517Y529200D02*
Y531700D01*
X289558D01*
X289892Y531575D01*
X290100Y531408D01*
X290183Y531075D01*
X290100Y530742D01*
X289850Y530533D01*
X289558Y530408D01*
X288517D01*
G01X289558D02*
X290183Y529200D01*
G01X291533Y529575D02*
X291783Y529367D01*
X292075Y529242D01*
X292450Y529200D01*
X292825Y529283D01*
X293117Y529450D01*
X293325Y529742D01*
X293367Y530075D01*
X293283Y530408D01*
X293075Y530617D01*
X292783Y530783D01*
X292492Y530825D01*
X292200Y530783D01*
X291825Y530617D01*
X291950Y531700D01*
X293075D01*
G01X295550D02*
X295217Y531617D01*
X294967Y531408D01*
X294800Y531158D01*
X294675Y530825D01*
X294633Y530450D01*
X294675Y530075D01*
X294800Y529742D01*
X294967Y529492D01*
X295217Y529283D01*
X295550Y529200D01*
X295883Y529283D01*
X296133Y529492D01*
X296300Y529742D01*
X296425Y530075D01*
X296467Y530450D01*
X296425Y530825D01*
X296300Y531158D01*
X296133Y531408D01*
X295883Y531617D01*
X295550Y531700D01*
G01X298650Y529200D02*
X298942Y529242D01*
X299275Y529367D01*
X299483Y529575D01*
X299567Y529867D01*
X299483Y530158D01*
X299233Y530408D01*
X298858Y530533D01*
X298442D01*
X298192Y530617D01*
X297983Y530825D01*
X297900Y531117D01*
X298025Y531408D01*
X298317Y531617D01*
X298650Y531700D01*
X298983Y531617D01*
X299275Y531408D01*
X299400Y531117D01*
X299317Y530825D01*
X299108Y530617D01*
X298858Y530533D01*
X298442D01*
X298067Y530408D01*
X297817Y530158D01*
X297733Y529867D01*
X297817Y529575D01*
X298025Y529367D01*
X298358Y529242D01*
X298650Y529200D01*
G01X297982Y510874D02*
Y514874D01*
X290582D01*
G01X289350Y523500D02*
X289017Y523542D01*
X288725Y523708D01*
X288475Y523958D01*
X288308Y524250D01*
X288225Y524583D01*
Y524917D01*
X288308Y525250D01*
X288475Y525542D01*
X288725Y525792D01*
X289017Y525958D01*
X289350Y526000D01*
X289683Y525958D01*
X289975Y525792D01*
X290225Y525542D01*
X290392Y525250D01*
X290475Y524917D01*
Y524583D01*
X290392Y524250D01*
X290225Y523958D01*
X289975Y523708D01*
X289683Y523542D01*
X289350Y523500D01*
G01X289683Y524167D02*
X290183Y523500D01*
G01X291658Y525583D02*
X291908Y525833D01*
X292200Y525958D01*
X292533Y526000D01*
X292950Y525917D01*
X293242Y525708D01*
X293325Y525458D01*
X293283Y525208D01*
X293117Y525000D01*
X292283Y524583D01*
X291908Y524292D01*
X291658Y523875D01*
X291575Y523500D01*
X293325D01*
G01X295467D02*
X295550Y524042D01*
X295675Y524500D01*
X295842Y524917D01*
X296050Y525375D01*
X296383Y526000D01*
X294717D01*
G01X298567Y523500D02*
X298650Y524042D01*
X298775Y524500D01*
X298942Y524917D01*
X299150Y525375D01*
X299483Y526000D01*
X297817D01*
G01X298653Y510142D02*
X285653D01*
G01X303850Y523500D02*
X303517Y523542D01*
X303225Y523708D01*
X302975Y523958D01*
X302808Y524250D01*
X302725Y524583D01*
Y524917D01*
X302808Y525250D01*
X302975Y525542D01*
X303225Y525792D01*
X303517Y525958D01*
X303850Y526000D01*
X304183Y525958D01*
X304475Y525792D01*
X304725Y525542D01*
X304892Y525250D01*
X304975Y524917D01*
Y524583D01*
X304892Y524250D01*
X304725Y523958D01*
X304475Y523708D01*
X304183Y523542D01*
X303850Y523500D01*
G01X304183Y524167D02*
X304683Y523500D01*
G01X306158Y525583D02*
X306408Y525833D01*
X306700Y525958D01*
X307033Y526000D01*
X307450Y525917D01*
X307742Y525708D01*
X307825Y525458D01*
X307783Y525208D01*
X307617Y525000D01*
X306783Y524583D01*
X306408Y524292D01*
X306158Y523875D01*
X306075Y523500D01*
X307825D01*
G01X310550D02*
Y526000D01*
X309008Y524208D01*
X311092D01*
G01X313150Y523500D02*
Y526000D01*
X312650Y525500D01*
G01Y523500D02*
X313650D01*
G01X312888Y510105D02*
X299888D01*
G01X298917Y626000D02*
Y628500D01*
X299958D01*
X300292Y628375D01*
X300500Y628208D01*
X300583Y627875D01*
X300500Y627542D01*
X300250Y627333D01*
X299958Y627208D01*
X298917D01*
G01X299958D02*
X300583Y626000D01*
G01X303350D02*
Y628500D01*
X301808Y626708D01*
X303892D01*
G01X305158Y627042D02*
X305450Y627333D01*
X305700Y627500D01*
X306033Y627583D01*
X306325Y627500D01*
X306533Y627333D01*
X306700Y627083D01*
X306742Y626792D01*
X306700Y626542D01*
X306533Y626292D01*
X306283Y626083D01*
X305992Y626000D01*
X305658Y626083D01*
X305367Y626333D01*
X305200Y626708D01*
X305158Y627125D01*
X305242Y627667D01*
X305367Y627958D01*
X305575Y628250D01*
X305867Y628458D01*
X306158Y628500D01*
X306450Y628417D01*
X306658Y628208D01*
G01X308258Y627042D02*
X308550Y627333D01*
X308800Y627500D01*
X309133Y627583D01*
X309425Y627500D01*
X309633Y627333D01*
X309800Y627083D01*
X309842Y626792D01*
X309800Y626542D01*
X309633Y626292D01*
X309383Y626083D01*
X309092Y626000D01*
X308758Y626083D01*
X308467Y626333D01*
X308300Y626708D01*
X308258Y627125D01*
X308342Y627667D01*
X308467Y627958D01*
X308675Y628250D01*
X308967Y628458D01*
X309258Y628500D01*
X309550Y628417D01*
X309758Y628208D01*
G01X303062Y634417D02*
Y630417D01*
X310462D01*
G01X304400Y636617D02*
X301900D01*
Y637658D01*
X302025Y637992D01*
X302192Y638200D01*
X302525Y638283D01*
X302858Y638200D01*
X303067Y637950D01*
X303192Y637658D01*
Y636617D01*
G01Y637658D02*
X304400Y638283D01*
G01Y641050D02*
X301900D01*
X303692Y639508D01*
Y641592D01*
G01X303358Y642858D02*
X303067Y643150D01*
X302900Y643400D01*
X302817Y643733D01*
X302900Y644025D01*
X303067Y644233D01*
X303317Y644400D01*
X303608Y644442D01*
X303858Y644400D01*
X304108Y644233D01*
X304317Y643983D01*
X304400Y643692D01*
X304317Y643358D01*
X304067Y643067D01*
X303692Y642900D01*
X303275Y642858D01*
X302733Y642942D01*
X302442Y643067D01*
X302150Y643275D01*
X301942Y643567D01*
X301900Y643858D01*
X301983Y644150D01*
X302192Y644358D01*
G01X304400Y646750D02*
X304358Y647042D01*
X304233Y647375D01*
X304025Y647583D01*
X303733Y647667D01*
X303442Y647583D01*
X303192Y647333D01*
X303067Y646958D01*
Y646542D01*
X302983Y646292D01*
X302775Y646083D01*
X302483Y646000D01*
X302192Y646125D01*
X301983Y646417D01*
X301900Y646750D01*
X301983Y647083D01*
X302192Y647375D01*
X302483Y647500D01*
X302775Y647417D01*
X302983Y647208D01*
X303067Y646958D01*
Y646542D01*
X303192Y646167D01*
X303442Y645917D01*
X303733Y645833D01*
X304025Y645917D01*
X304233Y646125D01*
X304358Y646458D01*
X304400Y646750D01*
G01X306262Y634817D02*
X310262D01*
Y642217D01*
G01X316000Y618983D02*
X313500D01*
Y619817D01*
X313625Y620150D01*
X313792Y620400D01*
X314042Y620608D01*
X314333Y620775D01*
X314750Y620817D01*
X315167Y620775D01*
X315458Y620608D01*
X315708Y620400D01*
X315875Y620150D01*
X316000Y619817D01*
Y618983D01*
G01Y623000D02*
X313500D01*
X314000Y622500D01*
G01X316000D02*
Y623500D01*
G01Y626600D02*
X313500D01*
X315292Y625058D01*
Y627142D01*
G01X311362Y644917D02*
X318362D01*
G01X311362Y628817D02*
Y644917D01*
G01X318362Y628817D02*
X311362D01*
G01X298679Y653217D02*
Y655717D01*
X299720D01*
X300054Y655592D01*
X300262Y655425D01*
X300345Y655092D01*
X300262Y654759D01*
X300012Y654550D01*
X299720Y654425D01*
X298679D01*
G01X299720D02*
X300345Y653217D01*
G01X303112D02*
Y655717D01*
X301570Y653925D01*
X303654D01*
G01X304795Y653592D02*
X305045Y653384D01*
X305337Y653259D01*
X305712Y653217D01*
X306087Y653300D01*
X306379Y653467D01*
X306587Y653759D01*
X306629Y654092D01*
X306545Y654425D01*
X306337Y654634D01*
X306045Y654800D01*
X305754Y654842D01*
X305462Y654800D01*
X305087Y654634D01*
X305212Y655717D01*
X306337D01*
G01X308104Y653509D02*
X308395Y653300D01*
X308729Y653217D01*
X309062Y653300D01*
X309354Y653550D01*
X309562Y653925D01*
X309645Y654300D01*
Y654759D01*
X309562Y655134D01*
X309354Y655467D01*
X309104Y655634D01*
X308812Y655717D01*
X308479Y655634D01*
X308229Y655467D01*
X308062Y655217D01*
X307979Y654884D01*
X308062Y654592D01*
X308270Y654300D01*
X308520Y654134D01*
X308812Y654092D01*
X309145Y654175D01*
X309395Y654384D01*
X309645Y654759D01*
G01X310962Y659717D02*
Y655717D01*
X318362D01*
G01X290879Y661817D02*
Y664317D01*
X291920D01*
X292254Y664192D01*
X292462Y664025D01*
X292545Y663692D01*
X292462Y663359D01*
X292212Y663150D01*
X291920Y663025D01*
X290879D01*
G01X291920D02*
X292545Y661817D01*
G01X295312D02*
Y664317D01*
X293770Y662525D01*
X295854D01*
G01X297120Y662859D02*
X297412Y663150D01*
X297662Y663317D01*
X297995Y663400D01*
X298287Y663317D01*
X298495Y663150D01*
X298662Y662900D01*
X298704Y662609D01*
X298662Y662359D01*
X298495Y662109D01*
X298245Y661900D01*
X297954Y661817D01*
X297620Y661900D01*
X297329Y662150D01*
X297162Y662525D01*
X297120Y662942D01*
X297204Y663484D01*
X297329Y663775D01*
X297537Y664067D01*
X297829Y664275D01*
X298120Y664317D01*
X298412Y664234D01*
X298620Y664025D01*
G01X300929Y661817D02*
X301012Y662359D01*
X301137Y662817D01*
X301304Y663234D01*
X301512Y663692D01*
X301845Y664317D01*
X300179D01*
G01X310562Y661317D02*
Y665317D01*
X303162D01*
G01X294000Y675900D02*
X293958Y675567D01*
X293792Y675275D01*
X293542Y675025D01*
X293250Y674858D01*
X292917Y674775D01*
X292583D01*
X292250Y674858D01*
X291958Y675025D01*
X291708Y675275D01*
X291542Y675567D01*
X291500Y675900D01*
X291542Y676233D01*
X291708Y676525D01*
X291958Y676775D01*
X292250Y676942D01*
X292583Y677025D01*
X292917D01*
X293250Y676942D01*
X293542Y676775D01*
X293792Y676525D01*
X293958Y676233D01*
X294000Y675900D01*
G01X293333Y676233D02*
X294000Y676733D01*
G01Y679000D02*
X293958Y679292D01*
X293833Y679625D01*
X293625Y679833D01*
X293333Y679917D01*
X293042Y679833D01*
X292792Y679583D01*
X292667Y679208D01*
Y678792D01*
X292583Y678542D01*
X292375Y678333D01*
X292083Y678250D01*
X291792Y678375D01*
X291583Y678667D01*
X291500Y679000D01*
X291583Y679333D01*
X291792Y679625D01*
X292083Y679750D01*
X292375Y679667D01*
X292583Y679458D01*
X292667Y679208D01*
Y678792D01*
X292792Y678417D01*
X293042Y678167D01*
X293333Y678083D01*
X293625Y678167D01*
X293833Y678375D01*
X293958Y678708D01*
X294000Y679000D01*
G01X292958Y681308D02*
X292667Y681600D01*
X292500Y681850D01*
X292417Y682183D01*
X292500Y682475D01*
X292667Y682683D01*
X292917Y682850D01*
X293208Y682892D01*
X293458Y682850D01*
X293708Y682683D01*
X293917Y682433D01*
X294000Y682142D01*
X293917Y681808D01*
X293667Y681517D01*
X293292Y681350D01*
X292875Y681308D01*
X292333Y681392D01*
X292042Y681517D01*
X291750Y681725D01*
X291542Y682017D01*
X291500Y682308D01*
X291583Y682600D01*
X291792Y682808D01*
G01X296162Y690417D02*
X298262Y688617D01*
X296162Y686417D01*
G01X296062Y682817D02*
X315262D01*
Y694017D01*
X296062D01*
Y682817D01*
X296462D01*
G01X292629Y668209D02*
X292379Y668334D01*
X292087Y668417D01*
X291754D01*
X291379Y668292D01*
X291087Y668084D01*
X290879Y667834D01*
X290712Y667417D01*
X290670Y667042D01*
X290754Y666667D01*
X290879Y666417D01*
X291129Y666167D01*
X291420Y666000D01*
X291712Y665917D01*
X292004D01*
X292295Y666000D01*
X292545Y666125D01*
X292754Y666292D01*
G01X294020Y668000D02*
X294270Y668250D01*
X294562Y668375D01*
X294895Y668417D01*
X295312Y668334D01*
X295604Y668125D01*
X295687Y667875D01*
X295645Y667625D01*
X295479Y667417D01*
X294645Y667000D01*
X294270Y666709D01*
X294020Y666292D01*
X293937Y665917D01*
X295687D01*
G01X296995Y666417D02*
X297245Y666125D01*
X297579Y665959D01*
X297954Y665917D01*
X298287Y665959D01*
X298620Y666167D01*
X298829Y666417D01*
X298870Y666667D01*
X298787Y666959D01*
X298495Y667167D01*
X298204Y667250D01*
X297829D01*
G01X298204D02*
X298454Y667375D01*
X298662Y667584D01*
X298745Y667834D01*
X298662Y668084D01*
X298454Y668292D01*
X298079Y668417D01*
X297704Y668375D01*
X297329Y668209D01*
G01X301012Y665917D02*
Y668417D01*
X300512Y667917D01*
G01Y665917D02*
X301512D01*
G01X300429Y659709D02*
X300179Y659834D01*
X299887Y659917D01*
X299554D01*
X299179Y659792D01*
X298887Y659584D01*
X298679Y659334D01*
X298512Y658917D01*
X298470Y658542D01*
X298554Y658167D01*
X298679Y657917D01*
X298929Y657667D01*
X299220Y657500D01*
X299512Y657417D01*
X299804D01*
X300095Y657500D01*
X300345Y657625D01*
X300554Y657792D01*
G01X301820Y659500D02*
X302070Y659750D01*
X302362Y659875D01*
X302695Y659917D01*
X303112Y659834D01*
X303404Y659625D01*
X303487Y659375D01*
X303445Y659125D01*
X303279Y658917D01*
X302445Y658500D01*
X302070Y658209D01*
X301820Y657792D01*
X301737Y657417D01*
X303487D01*
G01X304795Y657917D02*
X305045Y657625D01*
X305379Y657459D01*
X305754Y657417D01*
X306087Y657459D01*
X306420Y657667D01*
X306629Y657917D01*
X306670Y658167D01*
X306587Y658459D01*
X306295Y658667D01*
X306004Y658750D01*
X305629D01*
G01X306004D02*
X306254Y658875D01*
X306462Y659084D01*
X306545Y659334D01*
X306462Y659584D01*
X306254Y659792D01*
X305879Y659917D01*
X305504Y659875D01*
X305129Y659709D01*
G01X308812Y659917D02*
X308479Y659834D01*
X308229Y659625D01*
X308062Y659375D01*
X307937Y659042D01*
X307895Y658667D01*
X307937Y658292D01*
X308062Y657959D01*
X308229Y657709D01*
X308479Y657500D01*
X308812Y657417D01*
X309145Y657500D01*
X309395Y657709D01*
X309562Y657959D01*
X309687Y658292D01*
X309729Y658667D01*
X309687Y659042D01*
X309562Y659375D01*
X309395Y659625D01*
X309145Y659834D01*
X308812Y659917D01*
G01X272570Y716099D02*
Y712099D01*
X279970D01*
G01X314062Y703417D02*
Y711417D01*
X331662D01*
Y703417D01*
X314062D01*
G01X284593Y722935D02*
X284551Y722602D01*
X284385Y722310D01*
X284135Y722060D01*
X283843Y721893D01*
X283510Y721810D01*
X283176D01*
X282843Y721893D01*
X282551Y722060D01*
X282301Y722310D01*
X282135Y722602D01*
X282093Y722935D01*
X282135Y723268D01*
X282301Y723560D01*
X282551Y723810D01*
X282843Y723977D01*
X283176Y724060D01*
X283510D01*
X283843Y723977D01*
X284135Y723810D01*
X284385Y723560D01*
X284551Y723268D01*
X284593Y722935D01*
G01X283926Y723268D02*
X284593Y723768D01*
G01X282510Y725243D02*
X282260Y725493D01*
X282135Y725785D01*
X282093Y726118D01*
X282176Y726535D01*
X282385Y726827D01*
X282635Y726910D01*
X282885Y726868D01*
X283093Y726702D01*
X283510Y725868D01*
X283801Y725493D01*
X284218Y725243D01*
X284593Y725160D01*
Y726910D01*
G01X283551Y728343D02*
X283260Y728635D01*
X283093Y728885D01*
X283010Y729218D01*
X283093Y729510D01*
X283260Y729718D01*
X283510Y729885D01*
X283801Y729927D01*
X284051Y729885D01*
X284301Y729718D01*
X284510Y729468D01*
X284593Y729177D01*
X284510Y728843D01*
X284260Y728552D01*
X283885Y728385D01*
X283468Y728343D01*
X282926Y728427D01*
X282635Y728552D01*
X282343Y728760D01*
X282135Y729052D01*
X282093Y729343D01*
X282176Y729635D01*
X282385Y729843D01*
G01X284218Y731318D02*
X284426Y731568D01*
X284551Y731860D01*
X284593Y732235D01*
X284510Y732610D01*
X284343Y732902D01*
X284051Y733110D01*
X283718Y733152D01*
X283385Y733068D01*
X283176Y732860D01*
X283010Y732568D01*
X282968Y732277D01*
X283010Y731985D01*
X283176Y731610D01*
X282093Y731735D01*
Y732860D01*
G01X267593Y735585D02*
Y721585D01*
G01X280593Y735585D02*
X267593D01*
G01X280593Y721585D02*
Y735585D01*
G01X267593Y721585D02*
X280593D01*
G01X284597Y737855D02*
X284555Y737522D01*
X284389Y737230D01*
X284139Y736980D01*
X283847Y736813D01*
X283514Y736730D01*
X283180D01*
X282847Y736813D01*
X282555Y736980D01*
X282305Y737230D01*
X282139Y737522D01*
X282097Y737855D01*
X282139Y738188D01*
X282305Y738480D01*
X282555Y738730D01*
X282847Y738897D01*
X283180Y738980D01*
X283514D01*
X283847Y738897D01*
X284139Y738730D01*
X284389Y738480D01*
X284555Y738188D01*
X284597Y737855D01*
G01X283930Y738188D02*
X284597Y738688D01*
G01X282514Y740163D02*
X282264Y740413D01*
X282139Y740705D01*
X282097Y741038D01*
X282180Y741455D01*
X282389Y741747D01*
X282639Y741830D01*
X282889Y741788D01*
X283097Y741622D01*
X283514Y740788D01*
X283805Y740413D01*
X284222Y740163D01*
X284597Y740080D01*
Y741830D01*
G01X282514Y743263D02*
X282264Y743513D01*
X282139Y743805D01*
X282097Y744138D01*
X282180Y744555D01*
X282389Y744847D01*
X282639Y744930D01*
X282889Y744888D01*
X283097Y744722D01*
X283514Y743888D01*
X283805Y743513D01*
X284222Y743263D01*
X284597Y743180D01*
Y744930D01*
G01X284305Y746447D02*
X284514Y746738D01*
X284597Y747072D01*
X284514Y747405D01*
X284264Y747697D01*
X283889Y747905D01*
X283514Y747988D01*
X283055D01*
X282680Y747905D01*
X282347Y747697D01*
X282180Y747447D01*
X282097Y747155D01*
X282180Y746822D01*
X282347Y746572D01*
X282597Y746405D01*
X282930Y746322D01*
X283222Y746405D01*
X283514Y746613D01*
X283680Y746863D01*
X283722Y747155D01*
X283639Y747488D01*
X283430Y747738D01*
X283055Y747988D01*
G01X267597Y750505D02*
Y736505D01*
G01X280597D02*
Y750505D01*
G01X267597Y736505D02*
X280597D01*
G01X303267Y714292D02*
X303017Y714417D01*
X302725Y714500D01*
X302392D01*
X302017Y714375D01*
X301725Y714167D01*
X301517Y713917D01*
X301350Y713500D01*
X301308Y713125D01*
X301392Y712750D01*
X301517Y712500D01*
X301767Y712250D01*
X302058Y712083D01*
X302350Y712000D01*
X302642D01*
X302933Y712083D01*
X303183Y712208D01*
X303392Y712375D01*
G01X304658Y714083D02*
X304908Y714333D01*
X305200Y714458D01*
X305533Y714500D01*
X305950Y714417D01*
X306242Y714208D01*
X306325Y713958D01*
X306283Y713708D01*
X306117Y713500D01*
X305283Y713083D01*
X304908Y712792D01*
X304658Y712375D01*
X304575Y712000D01*
X306325D01*
G01X307758Y714083D02*
X308008Y714333D01*
X308300Y714458D01*
X308633Y714500D01*
X309050Y714417D01*
X309342Y714208D01*
X309425Y713958D01*
X309383Y713708D01*
X309217Y713500D01*
X308383Y713083D01*
X308008Y712792D01*
X307758Y712375D01*
X307675Y712000D01*
X309425D01*
G01X311650D02*
X311942Y712042D01*
X312275Y712167D01*
X312483Y712375D01*
X312567Y712667D01*
X312483Y712958D01*
X312233Y713208D01*
X311858Y713333D01*
X311442D01*
X311192Y713417D01*
X310983Y713625D01*
X310900Y713917D01*
X311025Y714208D01*
X311317Y714417D01*
X311650Y714500D01*
X311983Y714417D01*
X312275Y714208D01*
X312400Y713917D01*
X312317Y713625D01*
X312108Y713417D01*
X311858Y713333D01*
X311442D01*
X311067Y713208D01*
X310817Y712958D01*
X310733Y712667D01*
X310817Y712375D01*
X311025Y712167D01*
X311358Y712042D01*
X311650Y712000D01*
G01X280597Y750505D02*
X267597D01*
G01X313508Y834667D02*
Y837167D01*
X315092D01*
G01X314508Y835959D02*
X313508D01*
G01X316567Y837167D02*
Y834667D01*
X318233D01*
G01X321333D02*
X319667D01*
Y837167D01*
X321333D01*
G01X320667Y835959D02*
X319667D01*
G01X322683Y834667D02*
Y837167D01*
X323517D01*
X323850Y837042D01*
X324100Y836875D01*
X324308Y836625D01*
X324475Y836334D01*
X324517Y835917D01*
X324475Y835500D01*
X324308Y835209D01*
X324100Y834959D01*
X323850Y834792D01*
X323517Y834667D01*
X322683D01*
G01X325783Y835167D02*
X326033Y834875D01*
X326367Y834709D01*
X326742Y834667D01*
X327075Y834709D01*
X327408Y834917D01*
X327617Y835167D01*
X327658Y835417D01*
X327575Y835709D01*
X327283Y835917D01*
X326992Y836000D01*
X326617D01*
G01X326992D02*
X327242Y836125D01*
X327450Y836334D01*
X327533Y836584D01*
X327450Y836834D01*
X327242Y837042D01*
X326867Y837167D01*
X326492Y837125D01*
X326117Y836959D01*
G01X314104Y818809D02*
Y830009D01*
X322904D01*
Y818809D01*
X314104D01*
G01X311211Y948364D02*
X308711D01*
Y949405D01*
X308836Y949739D01*
X309003Y949947D01*
X309336Y950030D01*
X309669Y949947D01*
X309878Y949697D01*
X310003Y949405D01*
Y948364D01*
G01Y949405D02*
X311211Y950030D01*
G01X309128Y951505D02*
X308878Y951755D01*
X308753Y952047D01*
X308711Y952380D01*
X308794Y952797D01*
X309003Y953089D01*
X309253Y953172D01*
X309503Y953130D01*
X309711Y952964D01*
X310128Y952130D01*
X310419Y951755D01*
X310836Y951505D01*
X311211Y951422D01*
Y953172D01*
G01Y955397D02*
X308711D01*
X309211Y954897D01*
G01X311211D02*
Y955897D01*
G01Y958414D02*
X310669Y958497D01*
X310211Y958622D01*
X309794Y958789D01*
X309336Y958997D01*
X308711Y959330D01*
Y957664D01*
G01X316000Y1075033D02*
X313500D01*
Y1075867D01*
X313625Y1076200D01*
X313792Y1076450D01*
X314042Y1076658D01*
X314333Y1076825D01*
X314750Y1076867D01*
X315167Y1076825D01*
X315458Y1076658D01*
X315708Y1076450D01*
X315875Y1076200D01*
X316000Y1075867D01*
Y1075033D01*
G01X313917Y1078258D02*
X313667Y1078508D01*
X313542Y1078800D01*
X313500Y1079133D01*
X313583Y1079550D01*
X313792Y1079842D01*
X314042Y1079925D01*
X314292Y1079883D01*
X314500Y1079717D01*
X314917Y1078883D01*
X315208Y1078508D01*
X315625Y1078258D01*
X316000Y1078175D01*
Y1079925D01*
G01X311362Y1081573D02*
Y1097673D01*
G01X318362Y1081573D02*
X311362D01*
G01X298679Y1106073D02*
Y1108573D01*
X299720D01*
X300054Y1108448D01*
X300262Y1108281D01*
X300345Y1107948D01*
X300262Y1107615D01*
X300012Y1107406D01*
X299720Y1107281D01*
X298679D01*
G01X299720D02*
X300345Y1106073D01*
G01X302612D02*
Y1108573D01*
X302112Y1108073D01*
G01Y1106073D02*
X303112D01*
G01X305712D02*
X306004Y1106115D01*
X306337Y1106240D01*
X306545Y1106448D01*
X306629Y1106740D01*
X306545Y1107031D01*
X306295Y1107281D01*
X305920Y1107406D01*
X305504D01*
X305254Y1107490D01*
X305045Y1107698D01*
X304962Y1107990D01*
X305087Y1108281D01*
X305379Y1108490D01*
X305712Y1108573D01*
X306045Y1108490D01*
X306337Y1108281D01*
X306462Y1107990D01*
X306379Y1107698D01*
X306170Y1107490D01*
X305920Y1107406D01*
X305504D01*
X305129Y1107281D01*
X304879Y1107031D01*
X304795Y1106740D01*
X304879Y1106448D01*
X305087Y1106240D01*
X305420Y1106115D01*
X305712Y1106073D01*
G01X307895Y1106573D02*
X308145Y1106281D01*
X308479Y1106115D01*
X308854Y1106073D01*
X309187Y1106115D01*
X309520Y1106323D01*
X309729Y1106573D01*
X309770Y1106823D01*
X309687Y1107115D01*
X309395Y1107323D01*
X309104Y1107406D01*
X308729D01*
G01X309104D02*
X309354Y1107531D01*
X309562Y1107740D01*
X309645Y1107990D01*
X309562Y1108240D01*
X309354Y1108448D01*
X308979Y1108573D01*
X308604Y1108531D01*
X308229Y1108365D01*
G01X310962Y1112573D02*
Y1108573D01*
X318362D01*
G01X290817Y1087000D02*
Y1089500D01*
X291858D01*
X292192Y1089375D01*
X292400Y1089208D01*
X292483Y1088875D01*
X292400Y1088542D01*
X292150Y1088333D01*
X291858Y1088208D01*
X290817D01*
G01X291858D02*
X292483Y1087000D01*
G01X294750D02*
Y1089500D01*
X294250Y1089000D01*
G01Y1087000D02*
X295250D01*
G01X297142Y1087292D02*
X297433Y1087083D01*
X297767Y1087000D01*
X298100Y1087083D01*
X298392Y1087333D01*
X298600Y1087708D01*
X298683Y1088083D01*
Y1088542D01*
X298600Y1088917D01*
X298392Y1089250D01*
X298142Y1089417D01*
X297850Y1089500D01*
X297517Y1089417D01*
X297267Y1089250D01*
X297100Y1089000D01*
X297017Y1088667D01*
X297100Y1088375D01*
X297308Y1088083D01*
X297558Y1087917D01*
X297850Y1087875D01*
X298183Y1087958D01*
X298433Y1088167D01*
X298683Y1088542D01*
G01X300950Y1089500D02*
X300617Y1089417D01*
X300367Y1089208D01*
X300200Y1088958D01*
X300075Y1088625D01*
X300033Y1088250D01*
X300075Y1087875D01*
X300200Y1087542D01*
X300367Y1087292D01*
X300617Y1087083D01*
X300950Y1087000D01*
X301283Y1087083D01*
X301533Y1087292D01*
X301700Y1087542D01*
X301825Y1087875D01*
X301867Y1088250D01*
X301825Y1088625D01*
X301700Y1088958D01*
X301533Y1089208D01*
X301283Y1089417D01*
X300950Y1089500D01*
G01X302962Y1087173D02*
Y1083173D01*
X310362D01*
G01X291379Y1114573D02*
Y1117073D01*
X292420D01*
X292754Y1116948D01*
X292962Y1116781D01*
X293045Y1116448D01*
X292962Y1116115D01*
X292712Y1115906D01*
X292420Y1115781D01*
X291379D01*
G01X292420D02*
X293045Y1114573D01*
G01X295312D02*
Y1117073D01*
X294812Y1116573D01*
G01Y1114573D02*
X295812D01*
G01X297704Y1114865D02*
X297995Y1114656D01*
X298329Y1114573D01*
X298662Y1114656D01*
X298954Y1114906D01*
X299162Y1115281D01*
X299245Y1115656D01*
Y1116115D01*
X299162Y1116490D01*
X298954Y1116823D01*
X298704Y1116990D01*
X298412Y1117073D01*
X298079Y1116990D01*
X297829Y1116823D01*
X297662Y1116573D01*
X297579Y1116240D01*
X297662Y1115948D01*
X297870Y1115656D01*
X298120Y1115490D01*
X298412Y1115448D01*
X298745Y1115531D01*
X298995Y1115740D01*
X299245Y1116115D01*
G01X301512Y1114573D02*
Y1117073D01*
X301012Y1116573D01*
G01Y1114573D02*
X302012D01*
G01X310562Y1114073D02*
Y1118073D01*
X303162D01*
G01X305400Y1090617D02*
X302900D01*
Y1091658D01*
X303025Y1091992D01*
X303192Y1092200D01*
X303525Y1092283D01*
X303858Y1092200D01*
X304067Y1091950D01*
X304192Y1091658D01*
Y1090617D01*
G01Y1091658D02*
X305400Y1092283D01*
G01Y1094550D02*
X302900D01*
X303400Y1094050D01*
G01X305400D02*
Y1095050D01*
G01X305108Y1096942D02*
X305317Y1097233D01*
X305400Y1097567D01*
X305317Y1097900D01*
X305067Y1098192D01*
X304692Y1098400D01*
X304317Y1098483D01*
X303858D01*
X303483Y1098400D01*
X303150Y1098192D01*
X302983Y1097942D01*
X302900Y1097650D01*
X302983Y1097317D01*
X303150Y1097067D01*
X303400Y1096900D01*
X303733Y1096817D01*
X304025Y1096900D01*
X304317Y1097108D01*
X304483Y1097358D01*
X304525Y1097650D01*
X304442Y1097983D01*
X304233Y1098233D01*
X303858Y1098483D01*
G01X303317Y1099958D02*
X303067Y1100208D01*
X302942Y1100500D01*
X302900Y1100833D01*
X302983Y1101250D01*
X303192Y1101542D01*
X303442Y1101625D01*
X303692Y1101583D01*
X303900Y1101417D01*
X304317Y1100583D01*
X304608Y1100208D01*
X305025Y1099958D01*
X305400Y1099875D01*
Y1101625D01*
G01X306262Y1087573D02*
X310262D01*
Y1094973D01*
G01X311362Y1097673D02*
X318362D01*
G01X294679Y1120965D02*
X294429Y1121090D01*
X294137Y1121173D01*
X293804D01*
X293429Y1121048D01*
X293137Y1120840D01*
X292929Y1120590D01*
X292762Y1120173D01*
X292720Y1119798D01*
X292804Y1119423D01*
X292929Y1119173D01*
X293179Y1118923D01*
X293470Y1118756D01*
X293762Y1118673D01*
X294054D01*
X294345Y1118756D01*
X294595Y1118881D01*
X294804Y1119048D01*
G01X296779Y1118673D02*
X296862Y1119215D01*
X296987Y1119673D01*
X297154Y1120090D01*
X297362Y1120548D01*
X297695Y1121173D01*
X296029D01*
G01X299045Y1119048D02*
X299295Y1118840D01*
X299587Y1118715D01*
X299962Y1118673D01*
X300337Y1118756D01*
X300629Y1118923D01*
X300837Y1119215D01*
X300879Y1119548D01*
X300795Y1119881D01*
X300587Y1120090D01*
X300295Y1120256D01*
X300004Y1120298D01*
X299712Y1120256D01*
X299337Y1120090D01*
X299462Y1121173D01*
X300587D01*
G01X301979Y1112565D02*
X301729Y1112690D01*
X301437Y1112773D01*
X301104D01*
X300729Y1112648D01*
X300437Y1112440D01*
X300229Y1112190D01*
X300062Y1111773D01*
X300020Y1111398D01*
X300104Y1111023D01*
X300229Y1110773D01*
X300479Y1110523D01*
X300770Y1110356D01*
X301062Y1110273D01*
X301354D01*
X301645Y1110356D01*
X301895Y1110481D01*
X302104Y1110648D01*
G01X304079Y1110273D02*
X304162Y1110815D01*
X304287Y1111273D01*
X304454Y1111690D01*
X304662Y1112148D01*
X304995Y1112773D01*
X303329D01*
G01X307762Y1110273D02*
Y1112773D01*
X306220Y1110981D01*
X308304D01*
G01X273017Y1148000D02*
Y1150500D01*
X274058D01*
X274392Y1150375D01*
X274600Y1150208D01*
X274683Y1149875D01*
X274600Y1149542D01*
X274350Y1149333D01*
X274058Y1149208D01*
X273017D01*
G01X274058D02*
X274683Y1148000D01*
G01X276033Y1148375D02*
X276283Y1148167D01*
X276575Y1148042D01*
X276950Y1148000D01*
X277325Y1148083D01*
X277617Y1148250D01*
X277825Y1148542D01*
X277867Y1148875D01*
X277783Y1149208D01*
X277575Y1149417D01*
X277283Y1149583D01*
X276992Y1149625D01*
X276700Y1149583D01*
X276325Y1149417D01*
X276450Y1150500D01*
X277575D01*
G01X279133Y1148375D02*
X279383Y1148167D01*
X279675Y1148042D01*
X280050Y1148000D01*
X280425Y1148083D01*
X280717Y1148250D01*
X280925Y1148542D01*
X280967Y1148875D01*
X280883Y1149208D01*
X280675Y1149417D01*
X280383Y1149583D01*
X280092Y1149625D01*
X279800Y1149583D01*
X279425Y1149417D01*
X279550Y1150500D01*
X280675D01*
G01X283067Y1148000D02*
X283150Y1148542D01*
X283275Y1149000D01*
X283442Y1149417D01*
X283650Y1149875D01*
X283983Y1150500D01*
X282317D01*
G01X273126Y1160233D02*
Y1156233D01*
X280526D01*
G01X314602Y1173376D02*
Y1175876D01*
X315643D01*
X315977Y1175751D01*
X316185Y1175584D01*
X316268Y1175251D01*
X316185Y1174918D01*
X315935Y1174709D01*
X315643Y1174584D01*
X314602D01*
G01X315643D02*
X316268Y1173376D01*
G01X318535D02*
Y1175876D01*
X318035Y1175376D01*
G01Y1173376D02*
X319035D01*
G01X321552D02*
X321635Y1173918D01*
X321760Y1174376D01*
X321927Y1174793D01*
X322135Y1175251D01*
X322468Y1175876D01*
X320802D01*
G01X324027Y1173668D02*
X324318Y1173459D01*
X324652Y1173376D01*
X324985Y1173459D01*
X325277Y1173709D01*
X325485Y1174084D01*
X325568Y1174459D01*
Y1174918D01*
X325485Y1175293D01*
X325277Y1175626D01*
X325027Y1175793D01*
X324735Y1175876D01*
X324402Y1175793D01*
X324152Y1175626D01*
X323985Y1175376D01*
X323902Y1175043D01*
X323985Y1174751D01*
X324193Y1174459D01*
X324443Y1174293D01*
X324735Y1174251D01*
X325068Y1174334D01*
X325318Y1174543D01*
X325568Y1174918D01*
G01X314062Y1156173D02*
Y1164173D01*
X331662D01*
Y1156173D01*
X314062D01*
G01X284500Y1169350D02*
X284458Y1169017D01*
X284292Y1168725D01*
X284042Y1168475D01*
X283750Y1168308D01*
X283417Y1168225D01*
X283083D01*
X282750Y1168308D01*
X282458Y1168475D01*
X282208Y1168725D01*
X282042Y1169017D01*
X282000Y1169350D01*
X282042Y1169683D01*
X282208Y1169975D01*
X282458Y1170225D01*
X282750Y1170392D01*
X283083Y1170475D01*
X283417D01*
X283750Y1170392D01*
X284042Y1170225D01*
X284292Y1169975D01*
X284458Y1169683D01*
X284500Y1169350D01*
G01X283833Y1169683D02*
X284500Y1170183D01*
G01X282417Y1171658D02*
X282167Y1171908D01*
X282042Y1172200D01*
X282000Y1172533D01*
X282083Y1172950D01*
X282292Y1173242D01*
X282542Y1173325D01*
X282792Y1173283D01*
X283000Y1173117D01*
X283417Y1172283D01*
X283708Y1171908D01*
X284125Y1171658D01*
X284500Y1171575D01*
Y1173325D01*
G01Y1175550D02*
X284458Y1175842D01*
X284333Y1176175D01*
X284125Y1176383D01*
X283833Y1176467D01*
X283542Y1176383D01*
X283292Y1176133D01*
X283167Y1175758D01*
Y1175342D01*
X283083Y1175092D01*
X282875Y1174883D01*
X282583Y1174800D01*
X282292Y1174925D01*
X282083Y1175217D01*
X282000Y1175550D01*
X282083Y1175883D01*
X282292Y1176175D01*
X282583Y1176300D01*
X282875Y1176217D01*
X283083Y1176008D01*
X283167Y1175758D01*
Y1175342D01*
X283292Y1174967D01*
X283542Y1174717D01*
X283833Y1174633D01*
X284125Y1174717D01*
X284333Y1174925D01*
X284458Y1175258D01*
X284500Y1175550D01*
G01X284208Y1177942D02*
X284417Y1178233D01*
X284500Y1178567D01*
X284417Y1178900D01*
X284167Y1179192D01*
X283792Y1179400D01*
X283417Y1179483D01*
X282958D01*
X282583Y1179400D01*
X282250Y1179192D01*
X282083Y1178942D01*
X282000Y1178650D01*
X282083Y1178317D01*
X282250Y1178067D01*
X282500Y1177900D01*
X282833Y1177817D01*
X283125Y1177900D01*
X283417Y1178108D01*
X283583Y1178358D01*
X283625Y1178650D01*
X283542Y1178983D01*
X283333Y1179233D01*
X282958Y1179483D01*
G01X267555Y1181092D02*
Y1167092D01*
G01X280555D02*
Y1181092D01*
G01X267555Y1167092D02*
X280555D01*
G01X303426Y1170773D02*
X303176Y1170898D01*
X302884Y1170981D01*
X302551D01*
X302176Y1170856D01*
X301884Y1170648D01*
X301676Y1170398D01*
X301509Y1169981D01*
X301467Y1169606D01*
X301551Y1169231D01*
X301676Y1168981D01*
X301926Y1168731D01*
X302217Y1168564D01*
X302509Y1168481D01*
X302801D01*
X303092Y1168564D01*
X303342Y1168689D01*
X303551Y1168856D01*
G01X305526Y1168481D02*
X305609Y1169023D01*
X305734Y1169481D01*
X305901Y1169898D01*
X306109Y1170356D01*
X306442Y1170981D01*
X304776D01*
G01X308709Y1168481D02*
Y1170981D01*
X308209Y1170481D01*
G01Y1168481D02*
X309209D01*
G01X294000Y1137400D02*
X293958Y1137067D01*
X293792Y1136775D01*
X293542Y1136525D01*
X293250Y1136358D01*
X292917Y1136275D01*
X292583D01*
X292250Y1136358D01*
X291958Y1136525D01*
X291708Y1136775D01*
X291542Y1137067D01*
X291500Y1137400D01*
X291542Y1137733D01*
X291708Y1138025D01*
X291958Y1138275D01*
X292250Y1138442D01*
X292583Y1138525D01*
X292917D01*
X293250Y1138442D01*
X293542Y1138275D01*
X293792Y1138025D01*
X293958Y1137733D01*
X294000Y1137400D01*
G01X293333Y1137733D02*
X294000Y1138233D01*
G01Y1140500D02*
X291500D01*
X292000Y1140000D01*
G01X294000D02*
Y1141000D01*
G01Y1144100D02*
X291500D01*
X293292Y1142558D01*
Y1144642D01*
G01X296162Y1143173D02*
X298262Y1141373D01*
X296162Y1139173D01*
G01X296062Y1135573D02*
X315262D01*
Y1146773D01*
X296062D01*
Y1135573D01*
X296462D01*
G01X272696Y1188220D02*
Y1184220D01*
X280096D01*
G01X280555Y1181092D02*
X267555D01*
G01X269350Y1205500D02*
X269017Y1205542D01*
X268725Y1205708D01*
X268475Y1205958D01*
X268308Y1206250D01*
X268225Y1206583D01*
Y1206917D01*
X268308Y1207250D01*
X268475Y1207542D01*
X268725Y1207792D01*
X269017Y1207958D01*
X269350Y1208000D01*
X269683Y1207958D01*
X269975Y1207792D01*
X270225Y1207542D01*
X270392Y1207250D01*
X270475Y1206917D01*
Y1206583D01*
X270392Y1206250D01*
X270225Y1205958D01*
X269975Y1205708D01*
X269683Y1205542D01*
X269350Y1205500D01*
G01X269683Y1206167D02*
X270183Y1205500D01*
G01X271658Y1207583D02*
X271908Y1207833D01*
X272200Y1207958D01*
X272533Y1208000D01*
X272950Y1207917D01*
X273242Y1207708D01*
X273325Y1207458D01*
X273283Y1207208D01*
X273117Y1207000D01*
X272283Y1206583D01*
X271908Y1206292D01*
X271658Y1205875D01*
X271575Y1205500D01*
X273325D01*
G01X274633Y1205875D02*
X274883Y1205667D01*
X275175Y1205542D01*
X275550Y1205500D01*
X275925Y1205583D01*
X276217Y1205750D01*
X276425Y1206042D01*
X276467Y1206375D01*
X276383Y1206708D01*
X276175Y1206917D01*
X275883Y1207083D01*
X275592Y1207125D01*
X275300Y1207083D01*
X274925Y1206917D01*
X275050Y1208000D01*
X276175D01*
G01X277733Y1206000D02*
X277983Y1205708D01*
X278317Y1205542D01*
X278692Y1205500D01*
X279025Y1205542D01*
X279358Y1205750D01*
X279567Y1206000D01*
X279608Y1206250D01*
X279525Y1206542D01*
X279233Y1206750D01*
X278942Y1206833D01*
X278567D01*
G01X278942D02*
X279192Y1206958D01*
X279400Y1207167D01*
X279483Y1207417D01*
X279400Y1207667D01*
X279192Y1207875D01*
X278817Y1208000D01*
X278442Y1207958D01*
X278067Y1207792D01*
G01X267715Y1203474D02*
Y1189474D01*
G01X280715Y1203474D02*
X267715D01*
G01X280715Y1189474D02*
Y1203474D01*
G01X267715Y1189474D02*
X280715D01*
G01X314104Y1271565D02*
Y1282765D01*
X322904D01*
Y1271565D01*
X314104D01*
G01X313676Y1291179D02*
Y1293679D01*
X314717D01*
X315051Y1293554D01*
X315259Y1293387D01*
X315342Y1293054D01*
X315259Y1292721D01*
X315009Y1292512D01*
X314717Y1292387D01*
X313676D01*
G01X314717D02*
X315342Y1291179D01*
G01X316776Y1293679D02*
Y1291179D01*
X318442D01*
G01X321542D02*
X319876D01*
Y1293679D01*
X321542D01*
G01X320876Y1292471D02*
X319876D01*
G01X322892Y1291179D02*
Y1293679D01*
X323726D01*
X324059Y1293554D01*
X324309Y1293387D01*
X324517Y1293137D01*
X324684Y1292846D01*
X324726Y1292429D01*
X324684Y1292012D01*
X324517Y1291721D01*
X324309Y1291471D01*
X324059Y1291304D01*
X323726Y1291179D01*
X322892D01*
G01X326117Y1293262D02*
X326367Y1293512D01*
X326659Y1293637D01*
X326992Y1293679D01*
X327409Y1293596D01*
X327701Y1293387D01*
X327784Y1293137D01*
X327742Y1292887D01*
X327576Y1292679D01*
X326742Y1292262D01*
X326367Y1291971D01*
X326117Y1291554D01*
X326034Y1291179D01*
X327784D01*
G01X329926D02*
X330009Y1291721D01*
X330134Y1292179D01*
X330301Y1292596D01*
X330509Y1293054D01*
X330842Y1293679D01*
X329176D01*
G01X322846Y57845D02*
Y60345D01*
X323887D01*
X324221Y60220D01*
X324429Y60053D01*
X324512Y59720D01*
X324429Y59387D01*
X324179Y59178D01*
X323887Y59053D01*
X322846D01*
G01X323887D02*
X324512Y57845D01*
G01X325862Y58220D02*
X326112Y58012D01*
X326404Y57887D01*
X326779Y57845D01*
X327154Y57928D01*
X327446Y58095D01*
X327654Y58387D01*
X327696Y58720D01*
X327612Y59053D01*
X327404Y59262D01*
X327112Y59428D01*
X326821Y59470D01*
X326529Y59428D01*
X326154Y59262D01*
X326279Y60345D01*
X327404D01*
G01X329879Y57845D02*
Y60345D01*
X329379Y59845D01*
G01Y57845D02*
X330379D01*
G01X324079Y70345D02*
Y66345D01*
X331479D01*
G01X322846Y62345D02*
Y64845D01*
X323887D01*
X324221Y64720D01*
X324429Y64553D01*
X324512Y64220D01*
X324429Y63887D01*
X324179Y63678D01*
X323887Y63553D01*
X322846D01*
G01X323887D02*
X324512Y62345D01*
G01X325987Y63387D02*
X326279Y63678D01*
X326529Y63845D01*
X326862Y63928D01*
X327154Y63845D01*
X327362Y63678D01*
X327529Y63428D01*
X327571Y63137D01*
X327529Y62887D01*
X327362Y62637D01*
X327112Y62428D01*
X326821Y62345D01*
X326487Y62428D01*
X326196Y62678D01*
X326029Y63053D01*
X325987Y63470D01*
X326071Y64012D01*
X326196Y64303D01*
X326404Y64595D01*
X326696Y64803D01*
X326987Y64845D01*
X327279Y64762D01*
X327487Y64553D01*
G01X328962Y62845D02*
X329212Y62553D01*
X329546Y62387D01*
X329921Y62345D01*
X330254Y62387D01*
X330587Y62595D01*
X330796Y62845D01*
X330837Y63095D01*
X330754Y63387D01*
X330462Y63595D01*
X330171Y63678D01*
X329796D01*
G01X330171D02*
X330421Y63803D01*
X330629Y64012D01*
X330712Y64262D01*
X330629Y64512D01*
X330421Y64720D01*
X330046Y64845D01*
X329671Y64803D01*
X329296Y64637D01*
G01X348921Y71695D02*
Y61695D01*
G01D02*
X335521D01*
G01D02*
Y71695D01*
G01X337817Y55292D02*
X337567Y55417D01*
X337275Y55500D01*
X336942D01*
X336567Y55375D01*
X336275Y55167D01*
X336067Y54917D01*
X335900Y54500D01*
X335858Y54125D01*
X335942Y53750D01*
X336067Y53500D01*
X336317Y53250D01*
X336608Y53083D01*
X336900Y53000D01*
X337192D01*
X337483Y53083D01*
X337733Y53208D01*
X337942Y53375D01*
G01X340000Y53000D02*
Y55500D01*
X339500Y55000D01*
G01Y53000D02*
X340500D01*
G01X342183Y53375D02*
X342433Y53167D01*
X342725Y53042D01*
X343100Y53000D01*
X343475Y53083D01*
X343767Y53250D01*
X343975Y53542D01*
X344017Y53875D01*
X343933Y54208D01*
X343725Y54417D01*
X343433Y54583D01*
X343142Y54625D01*
X342850Y54583D01*
X342475Y54417D01*
X342600Y55500D01*
X343725D01*
G01X360662Y89187D02*
X358162D01*
Y90228D01*
X358287Y90562D01*
X358454Y90770D01*
X358787Y90853D01*
X359120Y90770D01*
X359329Y90520D01*
X359454Y90228D01*
Y89187D01*
G01Y90228D02*
X360662Y90853D01*
G01X360370Y92412D02*
X360579Y92703D01*
X360662Y93037D01*
X360579Y93370D01*
X360329Y93662D01*
X359954Y93870D01*
X359579Y93953D01*
X359120D01*
X358745Y93870D01*
X358412Y93662D01*
X358245Y93412D01*
X358162Y93120D01*
X358245Y92787D01*
X358412Y92537D01*
X358662Y92370D01*
X358995Y92287D01*
X359287Y92370D01*
X359579Y92578D01*
X359745Y92828D01*
X359787Y93120D01*
X359704Y93453D01*
X359495Y93703D01*
X359120Y93953D01*
G01X360662Y96220D02*
X360620Y96512D01*
X360495Y96845D01*
X360287Y97053D01*
X359995Y97137D01*
X359704Y97053D01*
X359454Y96803D01*
X359329Y96428D01*
Y96012D01*
X359245Y95762D01*
X359037Y95553D01*
X358745Y95470D01*
X358454Y95595D01*
X358245Y95887D01*
X358162Y96220D01*
X358245Y96553D01*
X358454Y96845D01*
X358745Y96970D01*
X359037Y96887D01*
X359245Y96678D01*
X359329Y96428D01*
Y96012D01*
X359454Y95637D01*
X359704Y95387D01*
X359995Y95303D01*
X360287Y95387D01*
X360495Y95595D01*
X360620Y95928D01*
X360662Y96220D01*
G01X360162Y98403D02*
X360454Y98653D01*
X360620Y98987D01*
X360662Y99362D01*
X360620Y99695D01*
X360412Y100028D01*
X360162Y100237D01*
X359912Y100278D01*
X359620Y100195D01*
X359412Y99903D01*
X359329Y99612D01*
Y99237D01*
G01Y99612D02*
X359204Y99862D01*
X358995Y100070D01*
X358745Y100153D01*
X358495Y100070D01*
X358287Y99862D01*
X358162Y99487D01*
X358204Y99112D01*
X358370Y98737D01*
G01X360500Y75517D02*
X358000D01*
Y76558D01*
X358125Y76892D01*
X358292Y77100D01*
X358625Y77183D01*
X358958Y77100D01*
X359167Y76850D01*
X359292Y76558D01*
Y75517D01*
G01Y76558D02*
X360500Y77183D01*
G01X360208Y78742D02*
X360417Y79033D01*
X360500Y79367D01*
X360417Y79700D01*
X360167Y79992D01*
X359792Y80200D01*
X359417Y80283D01*
X358958D01*
X358583Y80200D01*
X358250Y79992D01*
X358083Y79742D01*
X358000Y79450D01*
X358083Y79117D01*
X358250Y78867D01*
X358500Y78700D01*
X358833Y78617D01*
X359125Y78700D01*
X359417Y78908D01*
X359583Y79158D01*
X359625Y79450D01*
X359542Y79783D01*
X359333Y80033D01*
X358958Y80283D01*
G01X360500Y82550D02*
X360458Y82842D01*
X360333Y83175D01*
X360125Y83383D01*
X359833Y83467D01*
X359542Y83383D01*
X359292Y83133D01*
X359167Y82758D01*
Y82342D01*
X359083Y82092D01*
X358875Y81883D01*
X358583Y81800D01*
X358292Y81925D01*
X358083Y82217D01*
X358000Y82550D01*
X358083Y82883D01*
X358292Y83175D01*
X358583Y83300D01*
X358875Y83217D01*
X359083Y83008D01*
X359167Y82758D01*
Y82342D01*
X359292Y81967D01*
X359542Y81717D01*
X359833Y81633D01*
X360125Y81717D01*
X360333Y81925D01*
X360458Y82258D01*
X360500Y82550D01*
G01Y86150D02*
X358000D01*
X359792Y84608D01*
Y86692D01*
G01X331479Y70845D02*
Y74845D01*
X324079D01*
G01X340983Y76500D02*
Y74708D01*
X341150Y74333D01*
X341483Y74083D01*
X341900Y74000D01*
X342317Y74083D01*
X342650Y74333D01*
X342817Y74708D01*
Y76500D01*
G01X344208Y76083D02*
X344458Y76333D01*
X344750Y76458D01*
X345083Y76500D01*
X345500Y76417D01*
X345792Y76208D01*
X345875Y75958D01*
X345833Y75708D01*
X345667Y75500D01*
X344833Y75083D01*
X344458Y74792D01*
X344208Y74375D01*
X344125Y74000D01*
X345875D01*
G01X348100D02*
X348392Y74042D01*
X348725Y74167D01*
X348933Y74375D01*
X349017Y74667D01*
X348933Y74958D01*
X348683Y75208D01*
X348308Y75333D01*
X347892D01*
X347642Y75417D01*
X347433Y75625D01*
X347350Y75917D01*
X347475Y76208D01*
X347767Y76417D01*
X348100Y76500D01*
X348433Y76417D01*
X348725Y76208D01*
X348850Y75917D01*
X348767Y75625D01*
X348558Y75417D01*
X348308Y75333D01*
X347892D01*
X347517Y75208D01*
X347267Y74958D01*
X347183Y74667D01*
X347267Y74375D01*
X347475Y74167D01*
X347808Y74042D01*
X348100Y74000D01*
G01X335521Y71695D02*
X348921D01*
G01X322271Y101765D02*
X325421Y98615D01*
X322271Y95465D01*
G01Y83115D02*
Y104115D01*
X353921D01*
Y93115D01*
X322271D01*
G01X342549Y221492D02*
X347599D01*
Y320192D01*
X372249D01*
Y135792D01*
X347599D01*
Y194492D01*
X342549D01*
Y221492D01*
G01X333579Y162961D02*
Y165461D01*
X334620D01*
X334954Y165336D01*
X335162Y165169D01*
X335245Y164836D01*
X335162Y164503D01*
X334912Y164294D01*
X334620Y164169D01*
X333579D01*
G01X334620D02*
X335245Y162961D01*
G01X337429D02*
X337512Y163503D01*
X337637Y163961D01*
X337804Y164378D01*
X338012Y164836D01*
X338345Y165461D01*
X336679D01*
G01X339695Y163461D02*
X339945Y163169D01*
X340279Y163003D01*
X340654Y162961D01*
X340987Y163003D01*
X341320Y163211D01*
X341529Y163461D01*
X341570Y163711D01*
X341487Y164003D01*
X341195Y164211D01*
X340904Y164294D01*
X340529D01*
G01X340904D02*
X341154Y164419D01*
X341362Y164628D01*
X341445Y164878D01*
X341362Y165128D01*
X341154Y165336D01*
X340779Y165461D01*
X340404Y165419D01*
X340029Y165253D01*
G01X343004Y163253D02*
X343295Y163044D01*
X343629Y162961D01*
X343962Y163044D01*
X344254Y163294D01*
X344462Y163669D01*
X344545Y164044D01*
Y164503D01*
X344462Y164878D01*
X344254Y165211D01*
X344004Y165378D01*
X343712Y165461D01*
X343379Y165378D01*
X343129Y165211D01*
X342962Y164961D01*
X342879Y164628D01*
X342962Y164336D01*
X343170Y164044D01*
X343420Y163878D01*
X343712Y163836D01*
X344045Y163919D01*
X344295Y164128D01*
X344545Y164503D01*
G01X319500Y163517D02*
X317000D01*
Y164558D01*
X317125Y164892D01*
X317292Y165100D01*
X317625Y165183D01*
X317958Y165100D01*
X318167Y164850D01*
X318292Y164558D01*
Y163517D01*
G01Y164558D02*
X319500Y165183D01*
G01Y167367D02*
X318958Y167450D01*
X318500Y167575D01*
X318083Y167742D01*
X317625Y167950D01*
X317000Y168283D01*
Y166617D01*
G01X319500Y171050D02*
X317000D01*
X318792Y169508D01*
Y171592D01*
G01X319125Y172733D02*
X319333Y172983D01*
X319458Y173275D01*
X319500Y173650D01*
X319417Y174025D01*
X319250Y174317D01*
X318958Y174525D01*
X318625Y174567D01*
X318292Y174483D01*
X318083Y174275D01*
X317917Y173983D01*
X317875Y173692D01*
X317917Y173400D01*
X318083Y173025D01*
X317000Y173150D01*
Y174275D01*
G01X324740Y136597D02*
X322240D01*
Y137638D01*
X322365Y137972D01*
X322532Y138180D01*
X322865Y138263D01*
X323198Y138180D01*
X323407Y137930D01*
X323532Y137638D01*
Y136597D01*
G01Y137638D02*
X324740Y138263D01*
G01Y140530D02*
X322240D01*
X322740Y140030D01*
G01X324740D02*
Y141030D01*
G01X322657Y142838D02*
X322407Y143088D01*
X322282Y143380D01*
X322240Y143713D01*
X322323Y144130D01*
X322532Y144422D01*
X322782Y144505D01*
X323032Y144463D01*
X323240Y144297D01*
X323657Y143463D01*
X323948Y143088D01*
X324365Y142838D01*
X324740Y142755D01*
Y144505D01*
G01X324448Y146022D02*
X324657Y146313D01*
X324740Y146647D01*
X324657Y146980D01*
X324407Y147272D01*
X324032Y147480D01*
X323657Y147563D01*
X323198D01*
X322823Y147480D01*
X322490Y147272D01*
X322323Y147022D01*
X322240Y146730D01*
X322323Y146397D01*
X322490Y146147D01*
X322740Y145980D01*
X323073Y145897D01*
X323365Y145980D01*
X323657Y146188D01*
X323823Y146438D01*
X323865Y146730D01*
X323782Y147063D01*
X323573Y147313D01*
X323198Y147563D01*
G01X324740Y149830D02*
X324698Y150122D01*
X324573Y150455D01*
X324365Y150663D01*
X324073Y150747D01*
X323782Y150663D01*
X323532Y150413D01*
X323407Y150038D01*
Y149622D01*
X323323Y149372D01*
X323115Y149163D01*
X322823Y149080D01*
X322532Y149205D01*
X322323Y149497D01*
X322240Y149830D01*
X322323Y150163D01*
X322532Y150455D01*
X322823Y150580D01*
X323115Y150497D01*
X323323Y150288D01*
X323407Y150038D01*
Y149622D01*
X323532Y149247D01*
X323782Y148997D01*
X324073Y148913D01*
X324365Y148997D01*
X324573Y149205D01*
X324698Y149538D01*
X324740Y149830D01*
G01X321813Y119922D02*
X325813D01*
Y127322D01*
G01X329334Y136567D02*
X326834D01*
Y137608D01*
X326959Y137942D01*
X327126Y138150D01*
X327459Y138233D01*
X327792Y138150D01*
X328001Y137900D01*
X328126Y137608D01*
Y136567D01*
G01Y137608D02*
X329334Y138233D01*
G01X328834Y139583D02*
X329126Y139833D01*
X329292Y140167D01*
X329334Y140542D01*
X329292Y140875D01*
X329084Y141208D01*
X328834Y141417D01*
X328584Y141458D01*
X328292Y141375D01*
X328084Y141083D01*
X328001Y140792D01*
Y140417D01*
G01Y140792D02*
X327876Y141042D01*
X327667Y141250D01*
X327417Y141333D01*
X327167Y141250D01*
X326959Y141042D01*
X326834Y140667D01*
X326876Y140292D01*
X327042Y139917D01*
G01X326834Y143600D02*
X326917Y143267D01*
X327126Y143017D01*
X327376Y142850D01*
X327709Y142725D01*
X328084Y142683D01*
X328459Y142725D01*
X328792Y142850D01*
X329042Y143017D01*
X329251Y143267D01*
X329334Y143600D01*
X329251Y143933D01*
X329042Y144183D01*
X328792Y144350D01*
X328459Y144475D01*
X328084Y144517D01*
X327709Y144475D01*
X327376Y144350D01*
X327126Y144183D01*
X326917Y143933D01*
X326834Y143600D01*
G01X326321Y119899D02*
X330321D01*
Y127299D01*
G01X337834Y136567D02*
X335334D01*
Y137608D01*
X335459Y137942D01*
X335626Y138150D01*
X335959Y138233D01*
X336292Y138150D01*
X336501Y137900D01*
X336626Y137608D01*
Y136567D01*
G01Y137608D02*
X337834Y138233D01*
G01Y141000D02*
X335334D01*
X337126Y139458D01*
Y141542D01*
G01X337834Y144100D02*
X335334D01*
X337126Y142558D01*
Y144642D01*
G01X339721Y127355D02*
X335721D01*
Y119955D01*
G01X319834Y136567D02*
X317334D01*
Y137608D01*
X317459Y137942D01*
X317626Y138150D01*
X317959Y138233D01*
X318292Y138150D01*
X318501Y137900D01*
X318626Y137608D01*
Y136567D01*
G01Y137608D02*
X319834Y138233D01*
G01X319459Y139583D02*
X319667Y139833D01*
X319792Y140125D01*
X319834Y140500D01*
X319751Y140875D01*
X319584Y141167D01*
X319292Y141375D01*
X318959Y141417D01*
X318626Y141333D01*
X318417Y141125D01*
X318251Y140833D01*
X318209Y140542D01*
X318251Y140250D01*
X318417Y139875D01*
X317334Y140000D01*
Y141125D01*
G01X318792Y142808D02*
X318501Y143100D01*
X318334Y143350D01*
X318251Y143683D01*
X318334Y143975D01*
X318501Y144183D01*
X318751Y144350D01*
X319042Y144392D01*
X319292Y144350D01*
X319542Y144183D01*
X319751Y143933D01*
X319834Y143642D01*
X319751Y143308D01*
X319501Y143017D01*
X319126Y142850D01*
X318709Y142808D01*
X318167Y142892D01*
X317876Y143017D01*
X317584Y143225D01*
X317376Y143517D01*
X317334Y143808D01*
X317417Y144100D01*
X317626Y144308D01*
G01X316909Y119943D02*
X320909D01*
Y127343D01*
G01X333834Y136567D02*
X331334D01*
Y137608D01*
X331459Y137942D01*
X331626Y138150D01*
X331959Y138233D01*
X332292Y138150D01*
X332501Y137900D01*
X332626Y137608D01*
Y136567D01*
G01Y137608D02*
X333834Y138233D01*
G01X332792Y139708D02*
X332501Y140000D01*
X332334Y140250D01*
X332251Y140583D01*
X332334Y140875D01*
X332501Y141083D01*
X332751Y141250D01*
X333042Y141292D01*
X333292Y141250D01*
X333542Y141083D01*
X333751Y140833D01*
X333834Y140542D01*
X333751Y140208D01*
X333501Y139917D01*
X333126Y139750D01*
X332709Y139708D01*
X332167Y139792D01*
X331876Y139917D01*
X331584Y140125D01*
X331376Y140417D01*
X331334Y140708D01*
X331417Y141000D01*
X331626Y141208D01*
G01X333834Y144100D02*
X331334D01*
X333126Y142558D01*
Y144642D01*
G01X331021Y119955D02*
X335021D01*
Y127355D01*
G01X342762Y174461D02*
Y178461D01*
X335362D01*
G01X323362Y183361D02*
X319362D01*
Y175961D01*
G01X333617Y171000D02*
Y173500D01*
X334658D01*
X334992Y173375D01*
X335200Y173208D01*
X335283Y172875D01*
X335200Y172542D01*
X334950Y172333D01*
X334658Y172208D01*
X333617D01*
G01X334658D02*
X335283Y171000D01*
G01X337467D02*
X337550Y171542D01*
X337675Y172000D01*
X337842Y172417D01*
X338050Y172875D01*
X338383Y173500D01*
X336717D01*
G01X341150Y171000D02*
Y173500D01*
X339608Y171708D01*
X341692D01*
G01X343750Y173500D02*
X343417Y173417D01*
X343167Y173208D01*
X343000Y172958D01*
X342875Y172625D01*
X342833Y172250D01*
X342875Y171875D01*
X343000Y171542D01*
X343167Y171292D01*
X343417Y171083D01*
X343750Y171000D01*
X344083Y171083D01*
X344333Y171292D01*
X344500Y171542D01*
X344625Y171875D01*
X344667Y172250D01*
X344625Y172625D01*
X344500Y172958D01*
X344333Y173208D01*
X344083Y173417D01*
X343750Y173500D01*
G01X335262Y193161D02*
Y189161D01*
X342662D01*
G01X333617Y167000D02*
Y169500D01*
X334658D01*
X334992Y169375D01*
X335200Y169208D01*
X335283Y168875D01*
X335200Y168542D01*
X334950Y168333D01*
X334658Y168208D01*
X333617D01*
G01X334658D02*
X335283Y167000D01*
G01X337467D02*
X337550Y167542D01*
X337675Y168000D01*
X337842Y168417D01*
X338050Y168875D01*
X338383Y169500D01*
X336717D01*
G01X339733Y167500D02*
X339983Y167208D01*
X340317Y167042D01*
X340692Y167000D01*
X341025Y167042D01*
X341358Y167250D01*
X341567Y167500D01*
X341608Y167750D01*
X341525Y168042D01*
X341233Y168250D01*
X340942Y168333D01*
X340567D01*
G01X340942D02*
X341192Y168458D01*
X341400Y168667D01*
X341483Y168917D01*
X341400Y169167D01*
X341192Y169375D01*
X340817Y169500D01*
X340442Y169458D01*
X340067Y169292D01*
G01X342958Y168042D02*
X343250Y168333D01*
X343500Y168500D01*
X343833Y168583D01*
X344125Y168500D01*
X344333Y168333D01*
X344500Y168083D01*
X344542Y167792D01*
X344500Y167542D01*
X344333Y167292D01*
X344083Y167083D01*
X343792Y167000D01*
X343458Y167083D01*
X343167Y167333D01*
X343000Y167708D01*
X342958Y168125D01*
X343042Y168667D01*
X343167Y168958D01*
X343375Y169250D01*
X343667Y169458D01*
X343958Y169500D01*
X344250Y169417D01*
X344458Y169208D01*
G01X342662Y179161D02*
Y183161D01*
X335262D01*
G01X323162Y197861D02*
Y184461D01*
G01D02*
X334562D01*
G01D02*
Y197861D01*
G01D02*
X323162D01*
G01X318362Y192161D02*
Y176061D01*
G01X340662Y223261D02*
X321462D01*
Y212061D01*
X340662D01*
Y223261D01*
X340262D01*
G01X342500Y256017D02*
X340000D01*
Y257058D01*
X340125Y257392D01*
X340292Y257600D01*
X340625Y257683D01*
X340958Y257600D01*
X341167Y257350D01*
X341292Y257058D01*
Y256017D01*
G01Y257058D02*
X342500Y257683D01*
G01Y259867D02*
X341958Y259950D01*
X341500Y260075D01*
X341083Y260242D01*
X340625Y260450D01*
X340000Y260783D01*
Y259117D01*
G01X340417Y262258D02*
X340167Y262508D01*
X340042Y262800D01*
X340000Y263133D01*
X340083Y263550D01*
X340292Y263842D01*
X340542Y263925D01*
X340792Y263883D01*
X341000Y263717D01*
X341417Y262883D01*
X341708Y262508D01*
X342125Y262258D01*
X342500Y262175D01*
Y263925D01*
G01Y266067D02*
X341958Y266150D01*
X341500Y266275D01*
X341083Y266442D01*
X340625Y266650D01*
X340000Y266983D01*
Y265317D01*
G01X337862Y253961D02*
X345862D01*
Y236361D01*
X337862D01*
Y253961D01*
G01X324062Y236161D02*
X318562D01*
G01D02*
Y244161D01*
G01D02*
X324062D01*
G01X330662D02*
X336162D01*
G01D02*
Y236161D01*
G01D02*
X330662D01*
G01X344500Y224850D02*
X344458Y224517D01*
X344292Y224225D01*
X344042Y223975D01*
X343750Y223808D01*
X343417Y223725D01*
X343083D01*
X342750Y223808D01*
X342458Y223975D01*
X342208Y224225D01*
X342042Y224517D01*
X342000Y224850D01*
X342042Y225183D01*
X342208Y225475D01*
X342458Y225725D01*
X342750Y225892D01*
X343083Y225975D01*
X343417D01*
X343750Y225892D01*
X344042Y225725D01*
X344292Y225475D01*
X344458Y225183D01*
X344500Y224850D01*
G01X343833Y225183D02*
X344500Y225683D01*
G01Y227950D02*
X342000D01*
X342500Y227450D01*
G01X344500D02*
Y228450D01*
G01X344125Y230133D02*
X344333Y230383D01*
X344458Y230675D01*
X344500Y231050D01*
X344417Y231425D01*
X344250Y231717D01*
X343958Y231925D01*
X343625Y231967D01*
X343292Y231883D01*
X343083Y231675D01*
X342917Y231383D01*
X342875Y231092D01*
X342917Y230800D01*
X343083Y230425D01*
X342000Y230550D01*
Y231675D01*
G01X344125Y233233D02*
X344333Y233483D01*
X344458Y233775D01*
X344500Y234150D01*
X344417Y234525D01*
X344250Y234817D01*
X343958Y235025D01*
X343625Y235067D01*
X343292Y234983D01*
X343083Y234775D01*
X342917Y234483D01*
X342875Y234192D01*
X342917Y233900D01*
X343083Y233525D01*
X342000Y233650D01*
Y234775D01*
G01X340562Y215661D02*
X338462Y217461D01*
X340562Y219661D01*
G01X319517Y272000D02*
Y274500D01*
X320558D01*
X320892Y274375D01*
X321100Y274208D01*
X321183Y273875D01*
X321100Y273542D01*
X320850Y273333D01*
X320558Y273208D01*
X319517D01*
G01X320558D02*
X321183Y272000D01*
G01X323367D02*
X323450Y272542D01*
X323575Y273000D01*
X323742Y273417D01*
X323950Y273875D01*
X324283Y274500D01*
X322617D01*
G01X325758Y274083D02*
X326008Y274333D01*
X326300Y274458D01*
X326633Y274500D01*
X327050Y274417D01*
X327342Y274208D01*
X327425Y273958D01*
X327383Y273708D01*
X327217Y273500D01*
X326383Y273083D01*
X326008Y272792D01*
X325758Y272375D01*
X325675Y272000D01*
X327425D01*
G01X328942Y272292D02*
X329233Y272083D01*
X329567Y272000D01*
X329900Y272083D01*
X330192Y272333D01*
X330400Y272708D01*
X330483Y273083D01*
Y273542D01*
X330400Y273917D01*
X330192Y274250D01*
X329942Y274417D01*
X329650Y274500D01*
X329317Y274417D01*
X329067Y274250D01*
X328900Y274000D01*
X328817Y273667D01*
X328900Y273375D01*
X329108Y273083D01*
X329358Y272917D01*
X329650Y272875D01*
X329983Y272958D01*
X330233Y273167D01*
X330483Y273542D01*
G01X335708Y281267D02*
X335583Y281017D01*
X335500Y280725D01*
Y280392D01*
X335625Y280017D01*
X335833Y279725D01*
X336083Y279517D01*
X336500Y279350D01*
X336875Y279308D01*
X337250Y279392D01*
X337500Y279517D01*
X337750Y279767D01*
X337917Y280058D01*
X338000Y280350D01*
Y280642D01*
X337917Y280933D01*
X337792Y281183D01*
X337625Y281392D01*
G01X337500Y282533D02*
X337792Y282783D01*
X337958Y283117D01*
X338000Y283492D01*
X337958Y283825D01*
X337750Y284158D01*
X337500Y284367D01*
X337250Y284408D01*
X336958Y284325D01*
X336750Y284033D01*
X336667Y283742D01*
Y283367D01*
G01Y283742D02*
X336542Y283992D01*
X336333Y284200D01*
X336083Y284283D01*
X335833Y284200D01*
X335625Y283992D01*
X335500Y283617D01*
X335542Y283242D01*
X335708Y282867D01*
G01X338000Y286550D02*
X337958Y286842D01*
X337833Y287175D01*
X337625Y287383D01*
X337333Y287467D01*
X337042Y287383D01*
X336792Y287133D01*
X336667Y286758D01*
Y286342D01*
X336583Y286092D01*
X336375Y285883D01*
X336083Y285800D01*
X335792Y285925D01*
X335583Y286217D01*
X335500Y286550D01*
X335583Y286883D01*
X335792Y287175D01*
X336083Y287300D01*
X336375Y287217D01*
X336583Y287008D01*
X336667Y286758D01*
Y286342D01*
X336792Y285967D01*
X337042Y285717D01*
X337333Y285633D01*
X337625Y285717D01*
X337833Y285925D01*
X337958Y286258D01*
X338000Y286550D01*
G01X337500Y288733D02*
X337792Y288983D01*
X337958Y289317D01*
X338000Y289692D01*
X337958Y290025D01*
X337750Y290358D01*
X337500Y290567D01*
X337250Y290608D01*
X336958Y290525D01*
X336750Y290233D01*
X336667Y289942D01*
Y289567D01*
G01Y289942D02*
X336542Y290192D01*
X336333Y290400D01*
X336083Y290483D01*
X335833Y290400D01*
X335625Y290192D01*
X335500Y289817D01*
X335542Y289442D01*
X335708Y289067D01*
G01X321267Y266292D02*
X321017Y266417D01*
X320725Y266500D01*
X320392D01*
X320017Y266375D01*
X319725Y266167D01*
X319517Y265917D01*
X319350Y265500D01*
X319308Y265125D01*
X319392Y264750D01*
X319517Y264500D01*
X319767Y264250D01*
X320058Y264083D01*
X320350Y264000D01*
X320642D01*
X320933Y264083D01*
X321183Y264208D01*
X321392Y264375D01*
G01X322533Y264500D02*
X322783Y264208D01*
X323117Y264042D01*
X323492Y264000D01*
X323825Y264042D01*
X324158Y264250D01*
X324367Y264500D01*
X324408Y264750D01*
X324325Y265042D01*
X324033Y265250D01*
X323742Y265333D01*
X323367D01*
G01X323742D02*
X323992Y265458D01*
X324200Y265667D01*
X324283Y265917D01*
X324200Y266167D01*
X323992Y266375D01*
X323617Y266500D01*
X323242Y266458D01*
X322867Y266292D01*
G01X326467Y264000D02*
X326550Y264542D01*
X326675Y265000D01*
X326842Y265417D01*
X327050Y265875D01*
X327383Y266500D01*
X325717D01*
G01X328942Y264292D02*
X329233Y264083D01*
X329567Y264000D01*
X329900Y264083D01*
X330192Y264333D01*
X330400Y264708D01*
X330483Y265083D01*
Y265542D01*
X330400Y265917D01*
X330192Y266250D01*
X329942Y266417D01*
X329650Y266500D01*
X329317Y266417D01*
X329067Y266250D01*
X328900Y266000D01*
X328817Y265667D01*
X328900Y265375D01*
X329108Y265083D01*
X329358Y264917D01*
X329650Y264875D01*
X329983Y264958D01*
X330233Y265167D01*
X330483Y265542D01*
G01X321129Y270453D02*
X320879Y270578D01*
X320587Y270661D01*
X320254D01*
X319879Y270536D01*
X319587Y270328D01*
X319379Y270078D01*
X319212Y269661D01*
X319170Y269286D01*
X319254Y268911D01*
X319379Y268661D01*
X319629Y268411D01*
X319920Y268244D01*
X320212Y268161D01*
X320504D01*
X320795Y268244D01*
X321045Y268369D01*
X321254Y268536D01*
G01X322395Y268661D02*
X322645Y268369D01*
X322979Y268203D01*
X323354Y268161D01*
X323687Y268203D01*
X324020Y268411D01*
X324229Y268661D01*
X324270Y268911D01*
X324187Y269203D01*
X323895Y269411D01*
X323604Y269494D01*
X323229D01*
G01X323604D02*
X323854Y269619D01*
X324062Y269828D01*
X324145Y270078D01*
X324062Y270328D01*
X323854Y270536D01*
X323479Y270661D01*
X323104Y270619D01*
X322729Y270453D01*
G01X326329Y268161D02*
X326412Y268703D01*
X326537Y269161D01*
X326704Y269578D01*
X326912Y270036D01*
X327245Y270661D01*
X325579D01*
G01X329512Y268161D02*
X329804Y268203D01*
X330137Y268328D01*
X330345Y268536D01*
X330429Y268828D01*
X330345Y269119D01*
X330095Y269369D01*
X329720Y269494D01*
X329304D01*
X329054Y269578D01*
X328845Y269786D01*
X328762Y270078D01*
X328887Y270369D01*
X329179Y270578D01*
X329512Y270661D01*
X329845Y270578D01*
X330137Y270369D01*
X330262Y270078D01*
X330179Y269786D01*
X329970Y269578D01*
X329720Y269494D01*
X329304D01*
X328929Y269369D01*
X328679Y269119D01*
X328595Y268828D01*
X328679Y268536D01*
X328887Y268328D01*
X329220Y268203D01*
X329512Y268161D01*
G01X338208Y294767D02*
X338083Y294517D01*
X338000Y294225D01*
Y293892D01*
X338125Y293517D01*
X338333Y293225D01*
X338583Y293017D01*
X339000Y292850D01*
X339375Y292808D01*
X339750Y292892D01*
X340000Y293017D01*
X340250Y293267D01*
X340417Y293558D01*
X340500Y293850D01*
Y294142D01*
X340417Y294433D01*
X340292Y294683D01*
X340125Y294892D01*
G01X340000Y296033D02*
X340292Y296283D01*
X340458Y296617D01*
X340500Y296992D01*
X340458Y297325D01*
X340250Y297658D01*
X340000Y297867D01*
X339750Y297908D01*
X339458Y297825D01*
X339250Y297533D01*
X339167Y297242D01*
Y296867D01*
G01Y297242D02*
X339042Y297492D01*
X338833Y297700D01*
X338583Y297783D01*
X338333Y297700D01*
X338125Y297492D01*
X338000Y297117D01*
X338042Y296742D01*
X338208Y296367D01*
G01X340500Y300050D02*
X340458Y300342D01*
X340333Y300675D01*
X340125Y300883D01*
X339833Y300967D01*
X339542Y300883D01*
X339292Y300633D01*
X339167Y300258D01*
Y299842D01*
X339083Y299592D01*
X338875Y299383D01*
X338583Y299300D01*
X338292Y299425D01*
X338083Y299717D01*
X338000Y300050D01*
X338083Y300383D01*
X338292Y300675D01*
X338583Y300800D01*
X338875Y300717D01*
X339083Y300508D01*
X339167Y300258D01*
Y299842D01*
X339292Y299467D01*
X339542Y299217D01*
X339833Y299133D01*
X340125Y299217D01*
X340333Y299425D01*
X340458Y299758D01*
X340500Y300050D01*
G01X340125Y302233D02*
X340333Y302483D01*
X340458Y302775D01*
X340500Y303150D01*
X340417Y303525D01*
X340250Y303817D01*
X339958Y304025D01*
X339625Y304067D01*
X339292Y303983D01*
X339083Y303775D01*
X338917Y303483D01*
X338875Y303192D01*
X338917Y302900D01*
X339083Y302525D01*
X338000Y302650D01*
Y303775D01*
G01X322333Y511434D02*
X319833D01*
Y512475D01*
X319958Y512809D01*
X320125Y513017D01*
X320458Y513100D01*
X320791Y513017D01*
X321000Y512767D01*
X321125Y512475D01*
Y511434D01*
G01Y512475D02*
X322333Y513100D01*
G01X320250Y514575D02*
X320000Y514825D01*
X319875Y515117D01*
X319833Y515450D01*
X319916Y515867D01*
X320125Y516159D01*
X320375Y516242D01*
X320625Y516200D01*
X320833Y516034D01*
X321250Y515200D01*
X321541Y514825D01*
X321958Y514575D01*
X322333Y514492D01*
Y516242D01*
G01X322041Y517759D02*
X322250Y518050D01*
X322333Y518384D01*
X322250Y518717D01*
X322000Y519009D01*
X321625Y519217D01*
X321250Y519300D01*
X320791D01*
X320416Y519217D01*
X320083Y519009D01*
X319916Y518759D01*
X319833Y518467D01*
X319916Y518134D01*
X320083Y517884D01*
X320333Y517717D01*
X320666Y517634D01*
X320958Y517717D01*
X321250Y517925D01*
X321416Y518175D01*
X321458Y518467D01*
X321375Y518800D01*
X321166Y519050D01*
X320791Y519300D01*
G01X320250Y520775D02*
X320000Y521025D01*
X319875Y521317D01*
X319833Y521650D01*
X319916Y522067D01*
X320125Y522359D01*
X320375Y522442D01*
X320625Y522400D01*
X320833Y522234D01*
X321250Y521400D01*
X321541Y521025D01*
X321958Y520775D01*
X322333Y520692D01*
Y522442D01*
G01X317724Y511632D02*
X315224D01*
Y512673D01*
X315349Y513007D01*
X315516Y513215D01*
X315849Y513298D01*
X316182Y513215D01*
X316391Y512965D01*
X316516Y512673D01*
Y511632D01*
G01Y512673D02*
X317724Y513298D01*
G01X315641Y514773D02*
X315391Y515023D01*
X315266Y515315D01*
X315224Y515648D01*
X315307Y516065D01*
X315516Y516357D01*
X315766Y516440D01*
X316016Y516398D01*
X316224Y516232D01*
X316641Y515398D01*
X316932Y515023D01*
X317349Y514773D01*
X317724Y514690D01*
Y516440D01*
G01Y518665D02*
X317682Y518957D01*
X317557Y519290D01*
X317349Y519498D01*
X317057Y519582D01*
X316766Y519498D01*
X316516Y519248D01*
X316391Y518873D01*
Y518457D01*
X316307Y518207D01*
X316099Y517998D01*
X315807Y517915D01*
X315516Y518040D01*
X315307Y518332D01*
X315224Y518665D01*
X315307Y518998D01*
X315516Y519290D01*
X315807Y519415D01*
X316099Y519332D01*
X316307Y519123D01*
X316391Y518873D01*
Y518457D01*
X316516Y518082D01*
X316766Y517832D01*
X317057Y517748D01*
X317349Y517832D01*
X317557Y518040D01*
X317682Y518373D01*
X317724Y518665D01*
G01X317432Y521057D02*
X317641Y521348D01*
X317724Y521682D01*
X317641Y522015D01*
X317391Y522307D01*
X317016Y522515D01*
X316641Y522598D01*
X316182D01*
X315807Y522515D01*
X315474Y522307D01*
X315307Y522057D01*
X315224Y521765D01*
X315307Y521432D01*
X315474Y521182D01*
X315724Y521015D01*
X316057Y520932D01*
X316349Y521015D01*
X316641Y521223D01*
X316807Y521473D01*
X316849Y521765D01*
X316766Y522098D01*
X316557Y522348D01*
X316182Y522598D01*
G01X342549Y674248D02*
X347599D01*
Y772948D01*
X372249D01*
Y588548D01*
X347599D01*
Y647248D01*
X342549D01*
Y674248D01*
G01X330979Y614517D02*
Y617017D01*
X332020D01*
X332354Y616892D01*
X332562Y616725D01*
X332645Y616392D01*
X332562Y616059D01*
X332312Y615850D01*
X332020Y615725D01*
X330979D01*
G01X332020D02*
X332645Y614517D01*
G01X335412D02*
Y617017D01*
X333870Y615225D01*
X335954D01*
G01X337220Y615559D02*
X337512Y615850D01*
X337762Y616017D01*
X338095Y616100D01*
X338387Y616017D01*
X338595Y615850D01*
X338762Y615600D01*
X338804Y615309D01*
X338762Y615059D01*
X338595Y614809D01*
X338345Y614600D01*
X338054Y614517D01*
X337720Y614600D01*
X337429Y614850D01*
X337262Y615225D01*
X337220Y615642D01*
X337304Y616184D01*
X337429Y616475D01*
X337637Y616767D01*
X337929Y616975D01*
X338220Y617017D01*
X338512Y616934D01*
X338720Y616725D01*
G01X341112Y617017D02*
X340779Y616934D01*
X340529Y616725D01*
X340362Y616475D01*
X340237Y616142D01*
X340195Y615767D01*
X340237Y615392D01*
X340362Y615059D01*
X340529Y614809D01*
X340779Y614600D01*
X341112Y614517D01*
X341445Y614600D01*
X341695Y614809D01*
X341862Y615059D01*
X341987Y615392D01*
X342029Y615767D01*
X341987Y616142D01*
X341862Y616475D01*
X341695Y616725D01*
X341445Y616934D01*
X341112Y617017D01*
G01X342662Y632017D02*
Y636017D01*
X335262D01*
G01X331117Y610600D02*
Y613100D01*
X332158D01*
X332492Y612975D01*
X332700Y612808D01*
X332783Y612475D01*
X332700Y612142D01*
X332450Y611933D01*
X332158Y611808D01*
X331117D01*
G01X332158D02*
X332783Y610600D01*
G01X335550D02*
Y613100D01*
X334008Y611308D01*
X336092D01*
G01X337358Y611642D02*
X337650Y611933D01*
X337900Y612100D01*
X338233Y612183D01*
X338525Y612100D01*
X338733Y611933D01*
X338900Y611683D01*
X338942Y611392D01*
X338900Y611142D01*
X338733Y610892D01*
X338483Y610683D01*
X338192Y610600D01*
X337858Y610683D01*
X337567Y610933D01*
X337400Y611308D01*
X337358Y611725D01*
X337442Y612267D01*
X337567Y612558D01*
X337775Y612850D01*
X338067Y613058D01*
X338358Y613100D01*
X338650Y613017D01*
X338858Y612808D01*
G01X340333Y611100D02*
X340583Y610808D01*
X340917Y610642D01*
X341292Y610600D01*
X341625Y610642D01*
X341958Y610850D01*
X342167Y611100D01*
X342208Y611350D01*
X342125Y611642D01*
X341833Y611850D01*
X341542Y611933D01*
X341167D01*
G01X341542D02*
X341792Y612058D01*
X342000Y612267D01*
X342083Y612517D01*
X342000Y612767D01*
X341792Y612975D01*
X341417Y613100D01*
X341042Y613058D01*
X340667Y612892D01*
G01X331732Y631429D02*
Y627429D01*
X339132D01*
G01X331117Y618100D02*
Y620600D01*
X332158D01*
X332492Y620475D01*
X332700Y620308D01*
X332783Y619975D01*
X332700Y619642D01*
X332450Y619433D01*
X332158Y619308D01*
X331117D01*
G01X332158D02*
X332783Y618100D01*
G01X335550D02*
Y620600D01*
X334008Y618808D01*
X336092D01*
G01X337358Y619142D02*
X337650Y619433D01*
X337900Y619600D01*
X338233Y619683D01*
X338525Y619600D01*
X338733Y619433D01*
X338900Y619183D01*
X338942Y618892D01*
X338900Y618642D01*
X338733Y618392D01*
X338483Y618183D01*
X338192Y618100D01*
X337858Y618183D01*
X337567Y618433D01*
X337400Y618808D01*
X337358Y619225D01*
X337442Y619767D01*
X337567Y620058D01*
X337775Y620350D01*
X338067Y620558D01*
X338358Y620600D01*
X338650Y620517D01*
X338858Y620308D01*
G01X341750Y618100D02*
Y620600D01*
X340208Y618808D01*
X342292D01*
G01X335262Y646017D02*
Y642017D01*
X342662D01*
G01X320900Y616017D02*
X318400D01*
Y617058D01*
X318525Y617392D01*
X318692Y617600D01*
X319025Y617683D01*
X319358Y617600D01*
X319567Y617350D01*
X319692Y617058D01*
Y616017D01*
G01Y617058D02*
X320900Y617683D01*
G01Y620450D02*
X318400D01*
X320192Y618908D01*
Y620992D01*
G01X319858Y622258D02*
X319567Y622550D01*
X319400Y622800D01*
X319317Y623133D01*
X319400Y623425D01*
X319567Y623633D01*
X319817Y623800D01*
X320108Y623842D01*
X320358Y623800D01*
X320608Y623633D01*
X320817Y623383D01*
X320900Y623092D01*
X320817Y622758D01*
X320567Y622467D01*
X320192Y622300D01*
X319775Y622258D01*
X319233Y622342D01*
X318942Y622467D01*
X318650Y622675D01*
X318442Y622967D01*
X318400Y623258D01*
X318483Y623550D01*
X318692Y623758D01*
G01X320608Y625442D02*
X320817Y625733D01*
X320900Y626067D01*
X320817Y626400D01*
X320567Y626692D01*
X320192Y626900D01*
X319817Y626983D01*
X319358D01*
X318983Y626900D01*
X318650Y626692D01*
X318483Y626442D01*
X318400Y626150D01*
X318483Y625817D01*
X318650Y625567D01*
X318900Y625400D01*
X319233Y625317D01*
X319525Y625400D01*
X319817Y625608D01*
X319983Y625858D01*
X320025Y626150D01*
X319942Y626483D01*
X319733Y626733D01*
X319358Y626983D01*
G01X323262Y636117D02*
X319262D01*
Y628717D01*
G01X323400Y624500D02*
X323067Y624542D01*
X322775Y624708D01*
X322525Y624958D01*
X322358Y625250D01*
X322275Y625583D01*
Y625917D01*
X322358Y626250D01*
X322525Y626542D01*
X322775Y626792D01*
X323067Y626958D01*
X323400Y627000D01*
X323733Y626958D01*
X324025Y626792D01*
X324275Y626542D01*
X324442Y626250D01*
X324525Y625917D01*
Y625583D01*
X324442Y625250D01*
X324275Y624958D01*
X324025Y624708D01*
X323733Y624542D01*
X323400Y624500D01*
G01X323733Y625167D02*
X324233Y624500D01*
G01X326500D02*
X326792Y624542D01*
X327125Y624667D01*
X327333Y624875D01*
X327417Y625167D01*
X327333Y625458D01*
X327083Y625708D01*
X326708Y625833D01*
X326292D01*
X326042Y625917D01*
X325833Y626125D01*
X325750Y626417D01*
X325875Y626708D01*
X326167Y626917D01*
X326500Y627000D01*
X326833Y626917D01*
X327125Y626708D01*
X327250Y626417D01*
X327167Y626125D01*
X326958Y625917D01*
X326708Y625833D01*
X326292D01*
X325917Y625708D01*
X325667Y625458D01*
X325583Y625167D01*
X325667Y624875D01*
X325875Y624667D01*
X326208Y624542D01*
X326500Y624500D01*
G01X328683Y624875D02*
X328933Y624667D01*
X329225Y624542D01*
X329600Y624500D01*
X329975Y624583D01*
X330267Y624750D01*
X330475Y625042D01*
X330517Y625375D01*
X330433Y625708D01*
X330225Y625917D01*
X329933Y626083D01*
X329642Y626125D01*
X329350Y626083D01*
X328975Y625917D01*
X329100Y627000D01*
X330225D01*
G01X334562Y637217D02*
Y650617D01*
G01X323162Y637217D02*
X334562D01*
G01X323162Y650617D02*
Y637217D01*
G01X318362Y644917D02*
Y628817D01*
G01X337862Y706717D02*
X345862D01*
Y689117D01*
X337862D01*
Y706717D01*
G01X334562Y650617D02*
X323162D01*
G01X336162Y688917D02*
X330662D01*
G01X336162Y696917D02*
Y688917D01*
G01X318562D02*
Y696917D01*
G01X324062Y688917D02*
X318562D01*
G01X344500Y677900D02*
X344458Y677567D01*
X344292Y677275D01*
X344042Y677025D01*
X343750Y676858D01*
X343417Y676775D01*
X343083D01*
X342750Y676858D01*
X342458Y677025D01*
X342208Y677275D01*
X342042Y677567D01*
X342000Y677900D01*
X342042Y678233D01*
X342208Y678525D01*
X342458Y678775D01*
X342750Y678942D01*
X343083Y679025D01*
X343417D01*
X343750Y678942D01*
X344042Y678775D01*
X344292Y678525D01*
X344458Y678233D01*
X344500Y677900D01*
G01X343833Y678233D02*
X344500Y678733D01*
G01Y681000D02*
X344458Y681292D01*
X344333Y681625D01*
X344125Y681833D01*
X343833Y681917D01*
X343542Y681833D01*
X343292Y681583D01*
X343167Y681208D01*
Y680792D01*
X343083Y680542D01*
X342875Y680333D01*
X342583Y680250D01*
X342292Y680375D01*
X342083Y680667D01*
X342000Y681000D01*
X342083Y681333D01*
X342292Y681625D01*
X342583Y681750D01*
X342875Y681667D01*
X343083Y681458D01*
X343167Y681208D01*
Y680792D01*
X343292Y680417D01*
X343542Y680167D01*
X343833Y680083D01*
X344125Y680167D01*
X344333Y680375D01*
X344458Y680708D01*
X344500Y681000D01*
G01X344000Y683183D02*
X344292Y683433D01*
X344458Y683767D01*
X344500Y684142D01*
X344458Y684475D01*
X344250Y684808D01*
X344000Y685017D01*
X343750Y685058D01*
X343458Y684975D01*
X343250Y684683D01*
X343167Y684392D01*
Y684017D01*
G01Y684392D02*
X343042Y684642D01*
X342833Y684850D01*
X342583Y684933D01*
X342333Y684850D01*
X342125Y684642D01*
X342000Y684267D01*
X342042Y683892D01*
X342208Y683517D01*
G01X340562Y668417D02*
X338462Y670217D01*
X340562Y672417D01*
G01X340662Y676017D02*
X321462D01*
Y664817D01*
X340662D01*
Y676017D01*
X340262D01*
G01X343000Y708517D02*
X340500D01*
Y709558D01*
X340625Y709892D01*
X340792Y710100D01*
X341125Y710183D01*
X341458Y710100D01*
X341667Y709850D01*
X341792Y709558D01*
Y708517D01*
G01Y709558D02*
X343000Y710183D01*
G01Y712950D02*
X340500D01*
X342292Y711408D01*
Y713492D01*
G01X342625Y714633D02*
X342833Y714883D01*
X342958Y715175D01*
X343000Y715550D01*
X342917Y715925D01*
X342750Y716217D01*
X342458Y716425D01*
X342125Y716467D01*
X341792Y716383D01*
X341583Y716175D01*
X341417Y715883D01*
X341375Y715592D01*
X341417Y715300D01*
X341583Y714925D01*
X340500Y715050D01*
Y716175D01*
G01X343000Y718650D02*
X340500D01*
X341000Y718150D01*
G01X343000D02*
Y719150D01*
G01X320017Y723500D02*
Y726000D01*
X321058D01*
X321392Y725875D01*
X321600Y725708D01*
X321683Y725375D01*
X321600Y725042D01*
X321350Y724833D01*
X321058Y724708D01*
X320017D01*
G01X321058D02*
X321683Y723500D01*
G01X324450D02*
Y726000D01*
X322908Y724208D01*
X324992D01*
G01X326133Y723875D02*
X326383Y723667D01*
X326675Y723542D01*
X327050Y723500D01*
X327425Y723583D01*
X327717Y723750D01*
X327925Y724042D01*
X327967Y724375D01*
X327883Y724708D01*
X327675Y724917D01*
X327383Y725083D01*
X327092Y725125D01*
X326800Y725083D01*
X326425Y724917D01*
X326550Y726000D01*
X327675D01*
G01X329233Y724000D02*
X329483Y723708D01*
X329817Y723542D01*
X330192Y723500D01*
X330525Y723542D01*
X330858Y723750D01*
X331067Y724000D01*
X331108Y724250D01*
X331025Y724542D01*
X330733Y724750D01*
X330442Y724833D01*
X330067D01*
G01X330442D02*
X330692Y724958D01*
X330900Y725167D01*
X330983Y725417D01*
X330900Y725667D01*
X330692Y725875D01*
X330317Y726000D01*
X329942Y725958D01*
X329567Y725792D01*
G01X334870Y733684D02*
X334745Y733434D01*
X334662Y733142D01*
Y732809D01*
X334787Y732434D01*
X334995Y732142D01*
X335245Y731934D01*
X335662Y731767D01*
X336037Y731725D01*
X336412Y731809D01*
X336662Y731934D01*
X336912Y732184D01*
X337079Y732475D01*
X337162Y732767D01*
Y733059D01*
X337079Y733350D01*
X336954Y733600D01*
X336787Y733809D01*
G01X335079Y735075D02*
X334829Y735325D01*
X334704Y735617D01*
X334662Y735950D01*
X334745Y736367D01*
X334954Y736659D01*
X335204Y736742D01*
X335454Y736700D01*
X335662Y736534D01*
X336079Y735700D01*
X336370Y735325D01*
X336787Y735075D01*
X337162Y734992D01*
Y736742D01*
G01X335079Y738175D02*
X334829Y738425D01*
X334704Y738717D01*
X334662Y739050D01*
X334745Y739467D01*
X334954Y739759D01*
X335204Y739842D01*
X335454Y739800D01*
X335662Y739634D01*
X336079Y738800D01*
X336370Y738425D01*
X336787Y738175D01*
X337162Y738092D01*
Y739842D01*
G01Y741984D02*
X336620Y742067D01*
X336162Y742192D01*
X335745Y742359D01*
X335287Y742567D01*
X334662Y742900D01*
Y741234D01*
G01X321767Y718292D02*
X321517Y718417D01*
X321225Y718500D01*
X320892D01*
X320517Y718375D01*
X320225Y718167D01*
X320017Y717917D01*
X319850Y717500D01*
X319808Y717125D01*
X319892Y716750D01*
X320017Y716500D01*
X320267Y716250D01*
X320558Y716083D01*
X320850Y716000D01*
X321142D01*
X321433Y716083D01*
X321683Y716208D01*
X321892Y716375D01*
G01X323158Y718083D02*
X323408Y718333D01*
X323700Y718458D01*
X324033Y718500D01*
X324450Y718417D01*
X324742Y718208D01*
X324825Y717958D01*
X324783Y717708D01*
X324617Y717500D01*
X323783Y717083D01*
X323408Y716792D01*
X323158Y716375D01*
X323075Y716000D01*
X324825D01*
G01X326258Y718083D02*
X326508Y718333D01*
X326800Y718458D01*
X327133Y718500D01*
X327550Y718417D01*
X327842Y718208D01*
X327925Y717958D01*
X327883Y717708D01*
X327717Y717500D01*
X326883Y717083D01*
X326508Y716792D01*
X326258Y716375D01*
X326175Y716000D01*
X327925D01*
G01X329233Y716500D02*
X329483Y716208D01*
X329817Y716042D01*
X330192Y716000D01*
X330525Y716042D01*
X330858Y716250D01*
X331067Y716500D01*
X331108Y716750D01*
X331025Y717042D01*
X330733Y717250D01*
X330442Y717333D01*
X330067D01*
G01X330442D02*
X330692Y717458D01*
X330900Y717667D01*
X330983Y717917D01*
X330900Y718167D01*
X330692Y718375D01*
X330317Y718500D01*
X329942Y718458D01*
X329567Y718292D01*
G01X330662Y696917D02*
X336162D01*
G01X318562D02*
X324062D01*
G01X337708Y745767D02*
X337583Y745517D01*
X337500Y745225D01*
Y744892D01*
X337625Y744517D01*
X337833Y744225D01*
X338083Y744017D01*
X338500Y743850D01*
X338875Y743808D01*
X339250Y743892D01*
X339500Y744017D01*
X339750Y744267D01*
X339917Y744558D01*
X340000Y744850D01*
Y745142D01*
X339917Y745433D01*
X339792Y745683D01*
X339625Y745892D01*
G01X337917Y747158D02*
X337667Y747408D01*
X337542Y747700D01*
X337500Y748033D01*
X337583Y748450D01*
X337792Y748742D01*
X338042Y748825D01*
X338292Y748783D01*
X338500Y748617D01*
X338917Y747783D01*
X339208Y747408D01*
X339625Y747158D01*
X340000Y747075D01*
Y748825D01*
G01X337917Y750258D02*
X337667Y750508D01*
X337542Y750800D01*
X337500Y751133D01*
X337583Y751550D01*
X337792Y751842D01*
X338042Y751925D01*
X338292Y751883D01*
X338500Y751717D01*
X338917Y750883D01*
X339208Y750508D01*
X339625Y750258D01*
X340000Y750175D01*
Y751925D01*
G01X339708Y753442D02*
X339917Y753733D01*
X340000Y754067D01*
X339917Y754400D01*
X339667Y754692D01*
X339292Y754900D01*
X338917Y754983D01*
X338458D01*
X338083Y754900D01*
X337750Y754692D01*
X337583Y754442D01*
X337500Y754150D01*
X337583Y753817D01*
X337750Y753567D01*
X338000Y753400D01*
X338333Y753317D01*
X338625Y753400D01*
X338917Y753608D01*
X339083Y753858D01*
X339125Y754150D01*
X339042Y754483D01*
X338833Y754733D01*
X338458Y754983D01*
G01X321629Y722209D02*
X321379Y722334D01*
X321087Y722417D01*
X320754D01*
X320379Y722292D01*
X320087Y722084D01*
X319879Y721834D01*
X319712Y721417D01*
X319670Y721042D01*
X319754Y720667D01*
X319879Y720417D01*
X320129Y720167D01*
X320420Y720000D01*
X320712Y719917D01*
X321004D01*
X321295Y720000D01*
X321545Y720125D01*
X321754Y720292D01*
G01X323020Y722000D02*
X323270Y722250D01*
X323562Y722375D01*
X323895Y722417D01*
X324312Y722334D01*
X324604Y722125D01*
X324687Y721875D01*
X324645Y721625D01*
X324479Y721417D01*
X323645Y721000D01*
X323270Y720709D01*
X323020Y720292D01*
X322937Y719917D01*
X324687D01*
G01X326120Y722000D02*
X326370Y722250D01*
X326662Y722375D01*
X326995Y722417D01*
X327412Y722334D01*
X327704Y722125D01*
X327787Y721875D01*
X327745Y721625D01*
X327579Y721417D01*
X326745Y721000D01*
X326370Y720709D01*
X326120Y720292D01*
X326037Y719917D01*
X327787D01*
G01X329220Y722000D02*
X329470Y722250D01*
X329762Y722375D01*
X330095Y722417D01*
X330512Y722334D01*
X330804Y722125D01*
X330887Y721875D01*
X330845Y721625D01*
X330679Y721417D01*
X329845Y721000D01*
X329470Y720709D01*
X329220Y720292D01*
X329137Y719917D01*
X330887D01*
G01X348275Y782000D02*
Y784500D01*
G01X350025D02*
Y782000D01*
G01Y783250D02*
X348275D01*
G01X351333Y782000D02*
Y784500D01*
X352167D01*
X352500Y784375D01*
X352750Y784208D01*
X352958Y783958D01*
X353125Y783667D01*
X353167Y783250D01*
X353125Y782833D01*
X352958Y782542D01*
X352750Y782292D01*
X352500Y782125D01*
X352167Y782000D01*
X351333D01*
G01X354433D02*
Y784500D01*
X355267D01*
X355600Y784375D01*
X355850Y784208D01*
X356058Y783958D01*
X356225Y783667D01*
X356267Y783250D01*
X356225Y782833D01*
X356058Y782542D01*
X355850Y782292D01*
X355600Y782125D01*
X355267Y782000D01*
X354433D01*
G01X357575Y782333D02*
X357908Y782125D01*
X358283Y782000D01*
X358617D01*
X358950Y782125D01*
X359200Y782333D01*
X359325Y782625D01*
X359242Y782917D01*
X359033Y783167D01*
X358658Y783333D01*
X358158Y783417D01*
X357867Y783583D01*
X357742Y783875D01*
X357825Y784167D01*
X358033Y784375D01*
X358325Y784500D01*
X358617D01*
X358908Y784417D01*
X359158Y784208D01*
G01X360508Y782000D02*
X361550Y784500D01*
X362592Y782000D01*
G01X362217Y782875D02*
X360883D01*
G01X363775Y782333D02*
X364108Y782125D01*
X364483Y782000D01*
X364817D01*
X365150Y782125D01*
X365400Y782333D01*
X365525Y782625D01*
X365442Y782917D01*
X365233Y783167D01*
X364858Y783333D01*
X364358Y783417D01*
X364067Y783583D01*
X363942Y783875D01*
X364025Y784167D01*
X364233Y784375D01*
X364525Y784500D01*
X364817D01*
X365108Y784417D01*
X365358Y784208D01*
G01X367750Y782000D02*
Y784500D01*
X367250Y784000D01*
G01Y782000D02*
X368250D01*
G01X371350D02*
Y784500D01*
X369808Y782708D01*
X371892D01*
G01X327363Y947772D02*
X324863D01*
Y948813D01*
X324988Y949147D01*
X325155Y949355D01*
X325488Y949438D01*
X325821Y949355D01*
X326030Y949105D01*
X326155Y948813D01*
Y947772D01*
G01Y948813D02*
X327363Y949438D01*
G01X325280Y950913D02*
X325030Y951163D01*
X324905Y951455D01*
X324863Y951788D01*
X324946Y952205D01*
X325155Y952497D01*
X325405Y952580D01*
X325655Y952538D01*
X325863Y952372D01*
X326280Y951538D01*
X326571Y951163D01*
X326988Y950913D01*
X327363Y950830D01*
Y952580D01*
G01Y954805D02*
X324863D01*
X325363Y954305D01*
G01X327363D02*
Y955305D01*
G01Y957905D02*
X327321Y958197D01*
X327196Y958530D01*
X326988Y958738D01*
X326696Y958822D01*
X326405Y958738D01*
X326155Y958488D01*
X326030Y958113D01*
Y957697D01*
X325946Y957447D01*
X325738Y957238D01*
X325446Y957155D01*
X325155Y957280D01*
X324946Y957572D01*
X324863Y957905D01*
X324946Y958238D01*
X325155Y958530D01*
X325446Y958655D01*
X325738Y958572D01*
X325946Y958363D01*
X326030Y958113D01*
Y957697D01*
X326155Y957322D01*
X326405Y957072D01*
X326696Y956988D01*
X326988Y957072D01*
X327196Y957280D01*
X327321Y957613D01*
X327363Y957905D01*
G01X342549Y1127004D02*
X347599D01*
Y1225704D01*
X372249D01*
Y1041304D01*
X347599D01*
Y1100004D01*
X342549D01*
Y1127004D01*
G01X334579Y1072773D02*
Y1075273D01*
X335620D01*
X335954Y1075148D01*
X336162Y1074981D01*
X336245Y1074648D01*
X336162Y1074315D01*
X335912Y1074106D01*
X335620Y1073981D01*
X334579D01*
G01X335620D02*
X336245Y1072773D01*
G01X338512D02*
Y1075273D01*
X338012Y1074773D01*
G01Y1072773D02*
X339012D01*
G01X341612D02*
X341904Y1072815D01*
X342237Y1072940D01*
X342445Y1073148D01*
X342529Y1073440D01*
X342445Y1073731D01*
X342195Y1073981D01*
X341820Y1074106D01*
X341404D01*
X341154Y1074190D01*
X340945Y1074398D01*
X340862Y1074690D01*
X340987Y1074981D01*
X341279Y1075190D01*
X341612Y1075273D01*
X341945Y1075190D01*
X342237Y1074981D01*
X342362Y1074690D01*
X342279Y1074398D01*
X342070Y1074190D01*
X341820Y1074106D01*
X341404D01*
X341029Y1073981D01*
X340779Y1073731D01*
X340695Y1073440D01*
X340779Y1073148D01*
X340987Y1072940D01*
X341320Y1072815D01*
X341612Y1072773D01*
G01X345212D02*
Y1075273D01*
X343670Y1073481D01*
X345754D01*
G01X334717Y1068900D02*
Y1071400D01*
X335758D01*
X336092Y1071275D01*
X336300Y1071108D01*
X336383Y1070775D01*
X336300Y1070442D01*
X336050Y1070233D01*
X335758Y1070108D01*
X334717D01*
G01X335758D02*
X336383Y1068900D01*
G01X338650D02*
Y1071400D01*
X338150Y1070900D01*
G01Y1068900D02*
X339150D01*
G01X341750D02*
X342042Y1068942D01*
X342375Y1069067D01*
X342583Y1069275D01*
X342667Y1069567D01*
X342583Y1069858D01*
X342333Y1070108D01*
X341958Y1070233D01*
X341542D01*
X341292Y1070317D01*
X341083Y1070525D01*
X341000Y1070817D01*
X341125Y1071108D01*
X341417Y1071317D01*
X341750Y1071400D01*
X342083Y1071317D01*
X342375Y1071108D01*
X342500Y1070817D01*
X342417Y1070525D01*
X342208Y1070317D01*
X341958Y1070233D01*
X341542D01*
X341167Y1070108D01*
X340917Y1069858D01*
X340833Y1069567D01*
X340917Y1069275D01*
X341125Y1069067D01*
X341458Y1068942D01*
X341750Y1068900D01*
G01X344767D02*
X344850Y1069442D01*
X344975Y1069900D01*
X345142Y1070317D01*
X345350Y1070775D01*
X345683Y1071400D01*
X344017D01*
G01X342762Y1080073D02*
Y1084073D01*
X335362D01*
G01X334717Y1076600D02*
Y1079100D01*
X335758D01*
X336092Y1078975D01*
X336300Y1078808D01*
X336383Y1078475D01*
X336300Y1078142D01*
X336050Y1077933D01*
X335758Y1077808D01*
X334717D01*
G01X335758D02*
X336383Y1076600D01*
G01X338650D02*
Y1079100D01*
X338150Y1078600D01*
G01Y1076600D02*
X339150D01*
G01X341750D02*
X342042Y1076642D01*
X342375Y1076767D01*
X342583Y1076975D01*
X342667Y1077267D01*
X342583Y1077558D01*
X342333Y1077808D01*
X341958Y1077933D01*
X341542D01*
X341292Y1078017D01*
X341083Y1078225D01*
X341000Y1078517D01*
X341125Y1078808D01*
X341417Y1079017D01*
X341750Y1079100D01*
X342083Y1079017D01*
X342375Y1078808D01*
X342500Y1078517D01*
X342417Y1078225D01*
X342208Y1078017D01*
X341958Y1077933D01*
X341542D01*
X341167Y1077808D01*
X340917Y1077558D01*
X340833Y1077267D01*
X340917Y1076975D01*
X341125Y1076767D01*
X341458Y1076642D01*
X341750Y1076600D01*
G01X344142Y1076892D02*
X344433Y1076683D01*
X344767Y1076600D01*
X345100Y1076683D01*
X345392Y1076933D01*
X345600Y1077308D01*
X345683Y1077683D01*
Y1078142D01*
X345600Y1078517D01*
X345392Y1078850D01*
X345142Y1079017D01*
X344850Y1079100D01*
X344517Y1079017D01*
X344267Y1078850D01*
X344100Y1078600D01*
X344017Y1078267D01*
X344100Y1077975D01*
X344308Y1077683D01*
X344558Y1077517D01*
X344850Y1077475D01*
X345183Y1077558D01*
X345433Y1077767D01*
X345683Y1078142D01*
G01X321900Y1069017D02*
X319400D01*
Y1070058D01*
X319525Y1070392D01*
X319692Y1070600D01*
X320025Y1070683D01*
X320358Y1070600D01*
X320567Y1070350D01*
X320692Y1070058D01*
Y1069017D01*
G01Y1070058D02*
X321900Y1070683D01*
G01Y1072950D02*
X319400D01*
X319900Y1072450D01*
G01X321900D02*
Y1073450D01*
G01X321608Y1075342D02*
X321817Y1075633D01*
X321900Y1075967D01*
X321817Y1076300D01*
X321567Y1076592D01*
X321192Y1076800D01*
X320817Y1076883D01*
X320358D01*
X319983Y1076800D01*
X319650Y1076592D01*
X319483Y1076342D01*
X319400Y1076050D01*
X319483Y1075717D01*
X319650Y1075467D01*
X319900Y1075300D01*
X320233Y1075217D01*
X320525Y1075300D01*
X320817Y1075508D01*
X320983Y1075758D01*
X321025Y1076050D01*
X320942Y1076383D01*
X320733Y1076633D01*
X320358Y1076883D01*
G01X321400Y1078233D02*
X321692Y1078483D01*
X321858Y1078817D01*
X321900Y1079192D01*
X321858Y1079525D01*
X321650Y1079858D01*
X321400Y1080067D01*
X321150Y1080108D01*
X320858Y1080025D01*
X320650Y1079733D01*
X320567Y1079442D01*
Y1079067D01*
G01Y1079442D02*
X320442Y1079692D01*
X320233Y1079900D01*
X319983Y1079983D01*
X319733Y1079900D01*
X319525Y1079692D01*
X319400Y1079317D01*
X319442Y1078942D01*
X319608Y1078567D01*
G01X323262Y1088873D02*
X319262D01*
Y1081473D01*
G01X325900Y1079000D02*
X325567Y1079042D01*
X325275Y1079208D01*
X325025Y1079458D01*
X324858Y1079750D01*
X324775Y1080083D01*
Y1080417D01*
X324858Y1080750D01*
X325025Y1081042D01*
X325275Y1081292D01*
X325567Y1081458D01*
X325900Y1081500D01*
X326233Y1081458D01*
X326525Y1081292D01*
X326775Y1081042D01*
X326942Y1080750D01*
X327025Y1080417D01*
Y1080083D01*
X326942Y1079750D01*
X326775Y1079458D01*
X326525Y1079208D01*
X326233Y1079042D01*
X325900Y1079000D01*
G01X326233Y1079667D02*
X326733Y1079000D01*
G01X329000D02*
Y1081500D01*
X328500Y1081000D01*
G01Y1079000D02*
X329500D01*
G01X331183Y1079500D02*
X331433Y1079208D01*
X331767Y1079042D01*
X332142Y1079000D01*
X332475Y1079042D01*
X332808Y1079250D01*
X333017Y1079500D01*
X333058Y1079750D01*
X332975Y1080042D01*
X332683Y1080250D01*
X332392Y1080333D01*
X332017D01*
G01X332392D02*
X332642Y1080458D01*
X332850Y1080667D01*
X332933Y1080917D01*
X332850Y1081167D01*
X332642Y1081375D01*
X332267Y1081500D01*
X331892Y1081458D01*
X331517Y1081292D01*
G01X318362Y1097673D02*
Y1081573D01*
G01X342762Y1084773D02*
Y1088773D01*
X335362D01*
G01Y1098773D02*
Y1094773D01*
X342762D01*
G01X334562Y1103373D02*
X323162D01*
G01X334562Y1089973D02*
Y1103373D01*
G01X323162Y1089973D02*
X334562D01*
G01X323162Y1103373D02*
Y1089973D01*
G01X344500Y1130900D02*
X344458Y1130567D01*
X344292Y1130275D01*
X344042Y1130025D01*
X343750Y1129858D01*
X343417Y1129775D01*
X343083D01*
X342750Y1129858D01*
X342458Y1130025D01*
X342208Y1130275D01*
X342042Y1130567D01*
X342000Y1130900D01*
X342042Y1131233D01*
X342208Y1131525D01*
X342458Y1131775D01*
X342750Y1131942D01*
X343083Y1132025D01*
X343417D01*
X343750Y1131942D01*
X344042Y1131775D01*
X344292Y1131525D01*
X344458Y1131233D01*
X344500Y1130900D01*
G01X343833Y1131233D02*
X344500Y1131733D01*
G01Y1134000D02*
X342000D01*
X342500Y1133500D01*
G01X344500D02*
Y1134500D01*
G01X342417Y1136308D02*
X342167Y1136558D01*
X342042Y1136850D01*
X342000Y1137183D01*
X342083Y1137600D01*
X342292Y1137892D01*
X342542Y1137975D01*
X342792Y1137933D01*
X343000Y1137767D01*
X343417Y1136933D01*
X343708Y1136558D01*
X344125Y1136308D01*
X344500Y1136225D01*
Y1137975D01*
G01X340562Y1121173D02*
X338462Y1122973D01*
X340562Y1125173D01*
G01X340662Y1128773D02*
X321462D01*
Y1117573D01*
X340662D01*
Y1128773D01*
X340262D01*
G01X345500Y1161017D02*
X343000D01*
Y1162058D01*
X343125Y1162392D01*
X343292Y1162600D01*
X343625Y1162683D01*
X343958Y1162600D01*
X344167Y1162350D01*
X344292Y1162058D01*
Y1161017D01*
G01Y1162058D02*
X345500Y1162683D01*
G01Y1164950D02*
X343000D01*
X343500Y1164450D01*
G01X345500D02*
Y1165450D01*
G01Y1167967D02*
X344958Y1168050D01*
X344500Y1168175D01*
X344083Y1168342D01*
X343625Y1168550D01*
X343000Y1168883D01*
Y1167217D01*
G01X345125Y1170233D02*
X345333Y1170483D01*
X345458Y1170775D01*
X345500Y1171150D01*
X345417Y1171525D01*
X345250Y1171817D01*
X344958Y1172025D01*
X344625Y1172067D01*
X344292Y1171983D01*
X344083Y1171775D01*
X343917Y1171483D01*
X343875Y1171192D01*
X343917Y1170900D01*
X344083Y1170525D01*
X343000Y1170650D01*
Y1171775D01*
G01X337862Y1159473D02*
X345862D01*
Y1141873D01*
X337862D01*
Y1159473D01*
G01X322633Y1167480D02*
X322383Y1167605D01*
X322091Y1167688D01*
X321758D01*
X321383Y1167563D01*
X321091Y1167355D01*
X320883Y1167105D01*
X320716Y1166688D01*
X320674Y1166313D01*
X320758Y1165938D01*
X320883Y1165688D01*
X321133Y1165438D01*
X321424Y1165271D01*
X321716Y1165188D01*
X322008D01*
X322299Y1165271D01*
X322549Y1165396D01*
X322758Y1165563D01*
G01X324024Y1166230D02*
X324316Y1166521D01*
X324566Y1166688D01*
X324899Y1166771D01*
X325191Y1166688D01*
X325399Y1166521D01*
X325566Y1166271D01*
X325608Y1165980D01*
X325566Y1165730D01*
X325399Y1165480D01*
X325149Y1165271D01*
X324858Y1165188D01*
X324524Y1165271D01*
X324233Y1165521D01*
X324066Y1165896D01*
X324024Y1166313D01*
X324108Y1166855D01*
X324233Y1167146D01*
X324441Y1167438D01*
X324733Y1167646D01*
X325024Y1167688D01*
X325316Y1167605D01*
X325524Y1167396D01*
G01X327833Y1165188D02*
X327916Y1165730D01*
X328041Y1166188D01*
X328208Y1166605D01*
X328416Y1167063D01*
X328749Y1167688D01*
X327083D01*
G01X336162Y1141673D02*
X330662D01*
G01X336162Y1149673D02*
Y1141673D01*
G01X330662Y1149673D02*
X336162D01*
G01X318562D02*
X324062D01*
G01X318562Y1141673D02*
Y1149673D01*
G01X324062Y1141673D02*
X318562D01*
G01X322452Y1171601D02*
X322202Y1171726D01*
X321910Y1171809D01*
X321577D01*
X321202Y1171684D01*
X320910Y1171476D01*
X320702Y1171226D01*
X320535Y1170809D01*
X320493Y1170434D01*
X320577Y1170059D01*
X320702Y1169809D01*
X320952Y1169559D01*
X321243Y1169392D01*
X321535Y1169309D01*
X321827D01*
X322118Y1169392D01*
X322368Y1169517D01*
X322577Y1169684D01*
G01X323843Y1170351D02*
X324135Y1170642D01*
X324385Y1170809D01*
X324718Y1170892D01*
X325010Y1170809D01*
X325218Y1170642D01*
X325385Y1170392D01*
X325427Y1170101D01*
X325385Y1169851D01*
X325218Y1169601D01*
X324968Y1169392D01*
X324677Y1169309D01*
X324343Y1169392D01*
X324052Y1169642D01*
X323885Y1170017D01*
X323843Y1170434D01*
X323927Y1170976D01*
X324052Y1171267D01*
X324260Y1171559D01*
X324552Y1171767D01*
X324843Y1171809D01*
X325135Y1171726D01*
X325343Y1171517D01*
G01X326943Y1170351D02*
X327235Y1170642D01*
X327485Y1170809D01*
X327818Y1170892D01*
X328110Y1170809D01*
X328318Y1170642D01*
X328485Y1170392D01*
X328527Y1170101D01*
X328485Y1169851D01*
X328318Y1169601D01*
X328068Y1169392D01*
X327777Y1169309D01*
X327443Y1169392D01*
X327152Y1169642D01*
X326985Y1170017D01*
X326943Y1170434D01*
X327027Y1170976D01*
X327152Y1171267D01*
X327360Y1171559D01*
X327652Y1171767D01*
X327943Y1171809D01*
X328235Y1171726D01*
X328443Y1171517D01*
G01X335708Y1186317D02*
X335583Y1186067D01*
X335500Y1185775D01*
Y1185442D01*
X335625Y1185067D01*
X335833Y1184775D01*
X336083Y1184567D01*
X336500Y1184400D01*
X336875Y1184358D01*
X337250Y1184442D01*
X337500Y1184567D01*
X337750Y1184817D01*
X337917Y1185108D01*
X338000Y1185400D01*
Y1185692D01*
X337917Y1185983D01*
X337792Y1186233D01*
X337625Y1186442D01*
G01X338000Y1188417D02*
X337458Y1188500D01*
X337000Y1188625D01*
X336583Y1188792D01*
X336125Y1189000D01*
X335500Y1189333D01*
Y1187667D01*
G01X335917Y1190808D02*
X335667Y1191058D01*
X335542Y1191350D01*
X335500Y1191683D01*
X335583Y1192100D01*
X335792Y1192392D01*
X336042Y1192475D01*
X336292Y1192433D01*
X336500Y1192267D01*
X336917Y1191433D01*
X337208Y1191058D01*
X337625Y1190808D01*
X338000Y1190725D01*
Y1192475D01*
G01X337708Y1196817D02*
X337583Y1196567D01*
X337500Y1196275D01*
Y1195942D01*
X337625Y1195567D01*
X337833Y1195275D01*
X338083Y1195067D01*
X338500Y1194900D01*
X338875Y1194858D01*
X339250Y1194942D01*
X339500Y1195067D01*
X339750Y1195317D01*
X339917Y1195608D01*
X340000Y1195900D01*
Y1196192D01*
X339917Y1196483D01*
X339792Y1196733D01*
X339625Y1196942D01*
G01X340000Y1198917D02*
X339458Y1199000D01*
X339000Y1199125D01*
X338583Y1199292D01*
X338125Y1199500D01*
X337500Y1199833D01*
Y1198167D01*
G01X339500Y1201183D02*
X339792Y1201433D01*
X339958Y1201767D01*
X340000Y1202142D01*
X339958Y1202475D01*
X339750Y1202808D01*
X339500Y1203017D01*
X339250Y1203058D01*
X338958Y1202975D01*
X338750Y1202683D01*
X338667Y1202392D01*
Y1202017D01*
G01Y1202392D02*
X338542Y1202642D01*
X338333Y1202850D01*
X338083Y1202933D01*
X337833Y1202850D01*
X337625Y1202642D01*
X337500Y1202267D01*
X337542Y1201892D01*
X337708Y1201517D01*
G01X350274Y1234004D02*
Y1236504D01*
G01X352024D02*
Y1234004D01*
G01Y1235254D02*
X350274D01*
G01X353332Y1234004D02*
Y1236504D01*
X354166D01*
X354499Y1236379D01*
X354749Y1236212D01*
X354957Y1235962D01*
X355124Y1235671D01*
X355166Y1235254D01*
X355124Y1234837D01*
X354957Y1234546D01*
X354749Y1234296D01*
X354499Y1234129D01*
X354166Y1234004D01*
X353332D01*
G01X356432D02*
Y1236504D01*
X357266D01*
X357599Y1236379D01*
X357849Y1236212D01*
X358057Y1235962D01*
X358224Y1235671D01*
X358266Y1235254D01*
X358224Y1234837D01*
X358057Y1234546D01*
X357849Y1234296D01*
X357599Y1234129D01*
X357266Y1234004D01*
X356432D01*
G01X359574Y1234337D02*
X359907Y1234129D01*
X360282Y1234004D01*
X360616D01*
X360949Y1234129D01*
X361199Y1234337D01*
X361324Y1234629D01*
X361241Y1234921D01*
X361032Y1235171D01*
X360657Y1235337D01*
X360157Y1235421D01*
X359866Y1235587D01*
X359741Y1235879D01*
X359824Y1236171D01*
X360032Y1236379D01*
X360324Y1236504D01*
X360616D01*
X360907Y1236421D01*
X361157Y1236212D01*
G01X362507Y1234004D02*
X363549Y1236504D01*
X364591Y1234004D01*
G01X364216Y1234879D02*
X362882D01*
G01X365774Y1234337D02*
X366107Y1234129D01*
X366482Y1234004D01*
X366816D01*
X367149Y1234129D01*
X367399Y1234337D01*
X367524Y1234629D01*
X367441Y1234921D01*
X367232Y1235171D01*
X366857Y1235337D01*
X366357Y1235421D01*
X366066Y1235587D01*
X365941Y1235879D01*
X366024Y1236171D01*
X366232Y1236379D01*
X366524Y1236504D01*
X366816D01*
X367107Y1236421D01*
X367357Y1236212D01*
G01X368957Y1236087D02*
X369207Y1236337D01*
X369499Y1236462D01*
X369832Y1236504D01*
X370249Y1236421D01*
X370541Y1236212D01*
X370624Y1235962D01*
X370582Y1235712D01*
X370416Y1235504D01*
X369582Y1235087D01*
X369207Y1234796D01*
X368957Y1234379D01*
X368874Y1234004D01*
X370624D01*
G01X367162Y97870D02*
X363162D01*
Y90470D01*
G01Y79270D02*
X367162D01*
Y86670D01*
G01X379001Y165684D02*
X378751Y165809D01*
X378459Y165892D01*
X378126D01*
X377751Y165767D01*
X377459Y165559D01*
X377251Y165309D01*
X377084Y164892D01*
X377042Y164517D01*
X377126Y164142D01*
X377251Y163892D01*
X377501Y163642D01*
X377792Y163475D01*
X378084Y163392D01*
X378376D01*
X378667Y163475D01*
X378917Y163600D01*
X379126Y163767D01*
G01X380267Y163892D02*
X380517Y163600D01*
X380851Y163434D01*
X381226Y163392D01*
X381559Y163434D01*
X381892Y163642D01*
X382101Y163892D01*
X382142Y164142D01*
X382059Y164434D01*
X381767Y164642D01*
X381476Y164725D01*
X381101D01*
G01X381476D02*
X381726Y164850D01*
X381934Y165059D01*
X382017Y165309D01*
X381934Y165559D01*
X381726Y165767D01*
X381351Y165892D01*
X380976Y165850D01*
X380601Y165684D01*
G01X384201Y163392D02*
X384284Y163934D01*
X384409Y164392D01*
X384576Y164809D01*
X384784Y165267D01*
X385117Y165892D01*
X383451D01*
G01X387301Y163392D02*
X387384Y163934D01*
X387509Y164392D01*
X387676Y164809D01*
X387884Y165267D01*
X388217Y165892D01*
X386551D01*
G01X378767Y169792D02*
X378517Y169917D01*
X378225Y170000D01*
X377892D01*
X377517Y169875D01*
X377225Y169667D01*
X377017Y169417D01*
X376850Y169000D01*
X376808Y168625D01*
X376892Y168250D01*
X377017Y168000D01*
X377267Y167750D01*
X377558Y167583D01*
X377850Y167500D01*
X378142D01*
X378433Y167583D01*
X378683Y167708D01*
X378892Y167875D01*
G01X380033Y168000D02*
X380283Y167708D01*
X380617Y167542D01*
X380992Y167500D01*
X381325Y167542D01*
X381658Y167750D01*
X381867Y168000D01*
X381908Y168250D01*
X381825Y168542D01*
X381533Y168750D01*
X381242Y168833D01*
X380867D01*
G01X381242D02*
X381492Y168958D01*
X381700Y169167D01*
X381783Y169417D01*
X381700Y169667D01*
X381492Y169875D01*
X381117Y170000D01*
X380742Y169958D01*
X380367Y169792D01*
G01X383967Y167500D02*
X384050Y168042D01*
X384175Y168500D01*
X384342Y168917D01*
X384550Y169375D01*
X384883Y170000D01*
X383217D01*
G01X386358Y168542D02*
X386650Y168833D01*
X386900Y169000D01*
X387233Y169083D01*
X387525Y169000D01*
X387733Y168833D01*
X387900Y168583D01*
X387942Y168292D01*
X387900Y168042D01*
X387733Y167792D01*
X387483Y167583D01*
X387192Y167500D01*
X386858Y167583D01*
X386567Y167833D01*
X386400Y168208D01*
X386358Y168625D01*
X386442Y169167D01*
X386567Y169458D01*
X386775Y169750D01*
X387067Y169958D01*
X387358Y170000D01*
X387650Y169917D01*
X387858Y169708D01*
G01X381379Y233261D02*
Y235761D01*
X382420D01*
X382754Y235636D01*
X382962Y235469D01*
X383045Y235136D01*
X382962Y234803D01*
X382712Y234594D01*
X382420Y234469D01*
X381379D01*
G01X382420D02*
X383045Y233261D01*
G01X385229D02*
X385312Y233803D01*
X385437Y234261D01*
X385604Y234678D01*
X385812Y235136D01*
X386145Y235761D01*
X384479D01*
G01X387620Y235344D02*
X387870Y235594D01*
X388162Y235719D01*
X388495Y235761D01*
X388912Y235678D01*
X389204Y235469D01*
X389287Y235219D01*
X389245Y234969D01*
X389079Y234761D01*
X388245Y234344D01*
X387870Y234053D01*
X387620Y233636D01*
X387537Y233261D01*
X389287D01*
G01X391512D02*
X391804Y233303D01*
X392137Y233428D01*
X392345Y233636D01*
X392429Y233928D01*
X392345Y234219D01*
X392095Y234469D01*
X391720Y234594D01*
X391304D01*
X391054Y234678D01*
X390845Y234886D01*
X390762Y235178D01*
X390887Y235469D01*
X391179Y235678D01*
X391512Y235761D01*
X391845Y235678D01*
X392137Y235469D01*
X392262Y235178D01*
X392179Y234886D01*
X391970Y234678D01*
X391720Y234594D01*
X391304D01*
X390929Y234469D01*
X390679Y234219D01*
X390595Y233928D01*
X390679Y233636D01*
X390887Y233428D01*
X391220Y233303D01*
X391512Y233261D01*
G01X393062Y242761D02*
Y246761D01*
X385662D01*
G01X391017Y250000D02*
Y252500D01*
X392058D01*
X392392Y252375D01*
X392600Y252208D01*
X392683Y251875D01*
X392600Y251542D01*
X392350Y251333D01*
X392058Y251208D01*
X391017D01*
G01X392058D02*
X392683Y250000D01*
G01X394867D02*
X394950Y250542D01*
X395075Y251000D01*
X395242Y251417D01*
X395450Y251875D01*
X395783Y252500D01*
X394117D01*
G01X397133Y250500D02*
X397383Y250208D01*
X397717Y250042D01*
X398092Y250000D01*
X398425Y250042D01*
X398758Y250250D01*
X398967Y250500D01*
X399008Y250750D01*
X398925Y251042D01*
X398633Y251250D01*
X398342Y251333D01*
X397967D01*
G01X398342D02*
X398592Y251458D01*
X398800Y251667D01*
X398883Y251917D01*
X398800Y252167D01*
X398592Y252375D01*
X398217Y252500D01*
X397842Y252458D01*
X397467Y252292D01*
G01X400358Y252083D02*
X400608Y252333D01*
X400900Y252458D01*
X401233Y252500D01*
X401650Y252417D01*
X401942Y252208D01*
X402025Y251958D01*
X401983Y251708D01*
X401817Y251500D01*
X400983Y251083D01*
X400608Y250792D01*
X400358Y250375D01*
X400275Y250000D01*
X402025D01*
G01X383129Y231453D02*
X382879Y231578D01*
X382587Y231661D01*
X382254D01*
X381879Y231536D01*
X381587Y231328D01*
X381379Y231078D01*
X381212Y230661D01*
X381170Y230286D01*
X381254Y229911D01*
X381379Y229661D01*
X381629Y229411D01*
X381920Y229244D01*
X382212Y229161D01*
X382504D01*
X382795Y229244D01*
X383045Y229369D01*
X383254Y229536D01*
G01X384395Y229661D02*
X384645Y229369D01*
X384979Y229203D01*
X385354Y229161D01*
X385687Y229203D01*
X386020Y229411D01*
X386229Y229661D01*
X386270Y229911D01*
X386187Y230203D01*
X385895Y230411D01*
X385604Y230494D01*
X385229D01*
G01X385604D02*
X385854Y230619D01*
X386062Y230828D01*
X386145Y231078D01*
X386062Y231328D01*
X385854Y231536D01*
X385479Y231661D01*
X385104Y231619D01*
X384729Y231453D01*
G01X388412Y229161D02*
X388704Y229203D01*
X389037Y229328D01*
X389245Y229536D01*
X389329Y229828D01*
X389245Y230119D01*
X388995Y230369D01*
X388620Y230494D01*
X388204D01*
X387954Y230578D01*
X387745Y230786D01*
X387662Y231078D01*
X387787Y231369D01*
X388079Y231578D01*
X388412Y231661D01*
X388745Y231578D01*
X389037Y231369D01*
X389162Y231078D01*
X389079Y230786D01*
X388870Y230578D01*
X388620Y230494D01*
X388204D01*
X387829Y230369D01*
X387579Y230119D01*
X387495Y229828D01*
X387579Y229536D01*
X387787Y229328D01*
X388120Y229203D01*
X388412Y229161D01*
G01X392012D02*
Y231661D01*
X390470Y229869D01*
X392554D01*
G01X381000Y264800D02*
X383500D01*
G01X381000Y263842D02*
Y265758D01*
G01X383500Y267067D02*
X381000D01*
Y268067D01*
X381125Y268400D01*
X381417Y268650D01*
X381750Y268733D01*
X382083Y268650D01*
X382333Y268442D01*
X382458Y268067D01*
Y267067D01*
G01X383500Y271000D02*
X381000D01*
X381500Y270500D01*
G01X383500D02*
Y271500D01*
G01X383000Y273183D02*
X383292Y273433D01*
X383458Y273767D01*
X383500Y274142D01*
X383458Y274475D01*
X383250Y274808D01*
X383000Y275017D01*
X382750Y275058D01*
X382458Y274975D01*
X382250Y274683D01*
X382167Y274392D01*
Y274017D01*
G01Y274392D02*
X382042Y274642D01*
X381833Y274850D01*
X381583Y274933D01*
X381333Y274850D01*
X381125Y274642D01*
X381000Y274267D01*
X381042Y273892D01*
X381208Y273517D01*
G01X381417Y276408D02*
X381167Y276658D01*
X381042Y276950D01*
X381000Y277283D01*
X381083Y277700D01*
X381292Y277992D01*
X381542Y278075D01*
X381792Y278033D01*
X382000Y277867D01*
X382417Y277033D01*
X382708Y276658D01*
X383125Y276408D01*
X383500Y276325D01*
Y278075D01*
G01X378275Y319167D02*
Y321667D01*
G01X380025D02*
Y319167D01*
G01Y320417D02*
X378275D01*
G01X381333Y319167D02*
Y321667D01*
X382167D01*
X382500Y321542D01*
X382750Y321375D01*
X382958Y321125D01*
X383125Y320834D01*
X383167Y320417D01*
X383125Y320000D01*
X382958Y319709D01*
X382750Y319459D01*
X382500Y319292D01*
X382167Y319167D01*
X381333D01*
G01X384433D02*
Y321667D01*
X385267D01*
X385600Y321542D01*
X385850Y321375D01*
X386058Y321125D01*
X386225Y320834D01*
X386267Y320417D01*
X386225Y320000D01*
X386058Y319709D01*
X385850Y319459D01*
X385600Y319292D01*
X385267Y319167D01*
X384433D01*
G01X387575Y319500D02*
X387908Y319292D01*
X388283Y319167D01*
X388617D01*
X388950Y319292D01*
X389200Y319500D01*
X389325Y319792D01*
X389242Y320084D01*
X389033Y320334D01*
X388658Y320500D01*
X388158Y320584D01*
X387867Y320750D01*
X387742Y321042D01*
X387825Y321334D01*
X388033Y321542D01*
X388325Y321667D01*
X388617D01*
X388908Y321584D01*
X389158Y321375D01*
G01X390508Y319167D02*
X391550Y321667D01*
X392592Y319167D01*
G01X392217Y320042D02*
X390883D01*
G01X393775Y319500D02*
X394108Y319292D01*
X394483Y319167D01*
X394817D01*
X395150Y319292D01*
X395400Y319500D01*
X395525Y319792D01*
X395442Y320084D01*
X395233Y320334D01*
X394858Y320500D01*
X394358Y320584D01*
X394067Y320750D01*
X393942Y321042D01*
X394025Y321334D01*
X394233Y321542D01*
X394525Y321667D01*
X394817D01*
X395108Y321584D01*
X395358Y321375D01*
G01X396958Y321250D02*
X397208Y321500D01*
X397500Y321625D01*
X397833Y321667D01*
X398250Y321584D01*
X398542Y321375D01*
X398625Y321125D01*
X398583Y320875D01*
X398417Y320667D01*
X397583Y320250D01*
X397208Y319959D01*
X396958Y319542D01*
X396875Y319167D01*
X398625D01*
G01X400058Y320209D02*
X400350Y320500D01*
X400600Y320667D01*
X400933Y320750D01*
X401225Y320667D01*
X401433Y320500D01*
X401600Y320250D01*
X401642Y319959D01*
X401600Y319709D01*
X401433Y319459D01*
X401183Y319250D01*
X400892Y319167D01*
X400558Y319250D01*
X400267Y319500D01*
X400100Y319875D01*
X400058Y320292D01*
X400142Y320834D01*
X400267Y321125D01*
X400475Y321417D01*
X400767Y321625D01*
X401058Y321667D01*
X401350Y321584D01*
X401558Y321375D01*
G01X367196Y475895D02*
Y448095D01*
X394996D01*
Y475895D01*
X367196D01*
G01X411653Y482105D02*
X411320Y482147D01*
X411028Y482313D01*
X410778Y482563D01*
X410611Y482855D01*
X410528Y483188D01*
Y483522D01*
X410611Y483855D01*
X410778Y484147D01*
X411028Y484397D01*
X411320Y484563D01*
X411653Y484605D01*
X411986Y484563D01*
X412278Y484397D01*
X412528Y484147D01*
X412695Y483855D01*
X412778Y483522D01*
Y483188D01*
X412695Y482855D01*
X412528Y482563D01*
X412278Y482313D01*
X411986Y482147D01*
X411653Y482105D01*
G01X411986Y482772D02*
X412486Y482105D01*
G01X413961Y484188D02*
X414211Y484438D01*
X414503Y484563D01*
X414836Y484605D01*
X415253Y484522D01*
X415545Y484313D01*
X415628Y484063D01*
X415586Y483813D01*
X415420Y483605D01*
X414586Y483188D01*
X414211Y482897D01*
X413961Y482480D01*
X413878Y482105D01*
X415628D01*
G01X417770D02*
X417853Y482647D01*
X417978Y483105D01*
X418145Y483522D01*
X418353Y483980D01*
X418686Y484605D01*
X417020D01*
G01X420953Y482105D02*
X421245Y482147D01*
X421578Y482272D01*
X421786Y482480D01*
X421870Y482772D01*
X421786Y483063D01*
X421536Y483313D01*
X421161Y483438D01*
X420745D01*
X420495Y483522D01*
X420286Y483730D01*
X420203Y484022D01*
X420328Y484313D01*
X420620Y484522D01*
X420953Y484605D01*
X421286Y484522D01*
X421578Y484313D01*
X421703Y484022D01*
X421620Y483730D01*
X421411Y483522D01*
X421161Y483438D01*
X420745D01*
X420370Y483313D01*
X420120Y483063D01*
X420036Y482772D01*
X420120Y482480D01*
X420328Y482272D01*
X420661Y482147D01*
X420953Y482105D01*
G01X409803Y496105D02*
X422803D01*
G01X409803Y510105D02*
Y496105D01*
G01X422803Y510105D02*
X409803D01*
G01X378001Y617940D02*
X377751Y618065D01*
X377459Y618148D01*
X377126D01*
X376751Y618023D01*
X376459Y617815D01*
X376251Y617565D01*
X376084Y617148D01*
X376042Y616773D01*
X376126Y616398D01*
X376251Y616148D01*
X376501Y615898D01*
X376792Y615731D01*
X377084Y615648D01*
X377376D01*
X377667Y615731D01*
X377917Y615856D01*
X378126Y616023D01*
G01X379392Y617731D02*
X379642Y617981D01*
X379934Y618106D01*
X380267Y618148D01*
X380684Y618065D01*
X380976Y617856D01*
X381059Y617606D01*
X381017Y617356D01*
X380851Y617148D01*
X380017Y616731D01*
X379642Y616440D01*
X379392Y616023D01*
X379309Y615648D01*
X381059D01*
G01X382492Y617731D02*
X382742Y617981D01*
X383034Y618106D01*
X383367Y618148D01*
X383784Y618065D01*
X384076Y617856D01*
X384159Y617606D01*
X384117Y617356D01*
X383951Y617148D01*
X383117Y616731D01*
X382742Y616440D01*
X382492Y616023D01*
X382409Y615648D01*
X384159D01*
G01X386384D02*
Y618148D01*
X385884Y617648D01*
G01Y615648D02*
X386884D01*
G01X378267Y621792D02*
X378017Y621917D01*
X377725Y622000D01*
X377392D01*
X377017Y621875D01*
X376725Y621667D01*
X376517Y621417D01*
X376350Y621000D01*
X376308Y620625D01*
X376392Y620250D01*
X376517Y620000D01*
X376767Y619750D01*
X377058Y619583D01*
X377350Y619500D01*
X377642D01*
X377933Y619583D01*
X378183Y619708D01*
X378392Y619875D01*
G01X379658Y621583D02*
X379908Y621833D01*
X380200Y621958D01*
X380533Y622000D01*
X380950Y621917D01*
X381242Y621708D01*
X381325Y621458D01*
X381283Y621208D01*
X381117Y621000D01*
X380283Y620583D01*
X379908Y620292D01*
X379658Y619875D01*
X379575Y619500D01*
X381325D01*
G01X382758Y621583D02*
X383008Y621833D01*
X383300Y621958D01*
X383633Y622000D01*
X384050Y621917D01*
X384342Y621708D01*
X384425Y621458D01*
X384383Y621208D01*
X384217Y621000D01*
X383383Y620583D01*
X383008Y620292D01*
X382758Y619875D01*
X382675Y619500D01*
X384425D01*
G01X386650Y622000D02*
X386317Y621917D01*
X386067Y621708D01*
X385900Y621458D01*
X385775Y621125D01*
X385733Y620750D01*
X385775Y620375D01*
X385900Y620042D01*
X386067Y619792D01*
X386317Y619583D01*
X386650Y619500D01*
X386983Y619583D01*
X387233Y619792D01*
X387400Y620042D01*
X387525Y620375D01*
X387567Y620750D01*
X387525Y621125D01*
X387400Y621458D01*
X387233Y621708D01*
X386983Y621917D01*
X386650Y622000D01*
G01X382879Y686017D02*
Y688517D01*
X383920D01*
X384254Y688392D01*
X384462Y688225D01*
X384545Y687892D01*
X384462Y687559D01*
X384212Y687350D01*
X383920Y687225D01*
X382879D01*
G01X383920D02*
X384545Y686017D01*
G01X387312D02*
Y688517D01*
X385770Y686725D01*
X387854D01*
G01X388995Y686392D02*
X389245Y686184D01*
X389537Y686059D01*
X389912Y686017D01*
X390287Y686100D01*
X390579Y686267D01*
X390787Y686559D01*
X390829Y686892D01*
X390745Y687225D01*
X390537Y687434D01*
X390245Y687600D01*
X389954Y687642D01*
X389662Y687600D01*
X389287Y687434D01*
X389412Y688517D01*
X390537D01*
G01X392220Y688100D02*
X392470Y688350D01*
X392762Y688475D01*
X393095Y688517D01*
X393512Y688434D01*
X393804Y688225D01*
X393887Y687975D01*
X393845Y687725D01*
X393679Y687517D01*
X392845Y687100D01*
X392470Y686809D01*
X392220Y686392D01*
X392137Y686017D01*
X393887D01*
G01X393062Y695517D02*
Y699517D01*
X385662D01*
G01X384629Y684209D02*
X384379Y684334D01*
X384087Y684417D01*
X383754D01*
X383379Y684292D01*
X383087Y684084D01*
X382879Y683834D01*
X382712Y683417D01*
X382670Y683042D01*
X382754Y682667D01*
X382879Y682417D01*
X383129Y682167D01*
X383420Y682000D01*
X383712Y681917D01*
X384004D01*
X384295Y682000D01*
X384545Y682125D01*
X384754Y682292D01*
G01X386020Y684000D02*
X386270Y684250D01*
X386562Y684375D01*
X386895Y684417D01*
X387312Y684334D01*
X387604Y684125D01*
X387687Y683875D01*
X387645Y683625D01*
X387479Y683417D01*
X386645Y683000D01*
X386270Y682709D01*
X386020Y682292D01*
X385937Y681917D01*
X387687D01*
G01X389120Y684000D02*
X389370Y684250D01*
X389662Y684375D01*
X389995Y684417D01*
X390412Y684334D01*
X390704Y684125D01*
X390787Y683875D01*
X390745Y683625D01*
X390579Y683417D01*
X389745Y683000D01*
X389370Y682709D01*
X389120Y682292D01*
X389037Y681917D01*
X390787D01*
G01X392220Y682959D02*
X392512Y683250D01*
X392762Y683417D01*
X393095Y683500D01*
X393387Y683417D01*
X393595Y683250D01*
X393762Y683000D01*
X393804Y682709D01*
X393762Y682459D01*
X393595Y682209D01*
X393345Y682000D01*
X393054Y681917D01*
X392720Y682000D01*
X392429Y682250D01*
X392262Y682625D01*
X392220Y683042D01*
X392304Y683584D01*
X392429Y683875D01*
X392637Y684167D01*
X392929Y684375D01*
X393220Y684417D01*
X393512Y684334D01*
X393720Y684125D01*
G01X384696Y736913D02*
X382196D01*
Y737954D01*
X382321Y738288D01*
X382488Y738496D01*
X382821Y738579D01*
X383154Y738496D01*
X383363Y738246D01*
X383488Y737954D01*
Y736913D01*
G01Y737954D02*
X384696Y738579D01*
G01Y741346D02*
X382196D01*
X383988Y739804D01*
Y741888D01*
G01X383654Y743154D02*
X383363Y743446D01*
X383196Y743696D01*
X383113Y744029D01*
X383196Y744321D01*
X383363Y744529D01*
X383613Y744696D01*
X383904Y744738D01*
X384154Y744696D01*
X384404Y744529D01*
X384613Y744279D01*
X384696Y743988D01*
X384613Y743654D01*
X384363Y743363D01*
X383988Y743196D01*
X383571Y743154D01*
X383029Y743238D01*
X382738Y743363D01*
X382446Y743571D01*
X382238Y743863D01*
X382196Y744154D01*
X382279Y744446D01*
X382488Y744654D01*
G01X384321Y746129D02*
X384529Y746379D01*
X384654Y746671D01*
X384696Y747046D01*
X384613Y747421D01*
X384446Y747713D01*
X384154Y747921D01*
X383821Y747963D01*
X383488Y747879D01*
X383279Y747671D01*
X383113Y747379D01*
X383071Y747088D01*
X383113Y746796D01*
X383279Y746421D01*
X382196Y746546D01*
Y747671D01*
G01X390796Y741596D02*
X386796D01*
Y734196D01*
G01X379317Y716600D02*
Y719100D01*
X380358D01*
X380692Y718975D01*
X380900Y718808D01*
X380983Y718475D01*
X380900Y718142D01*
X380650Y717933D01*
X380358Y717808D01*
X379317D01*
G01X380358D02*
X380983Y716600D01*
G01X383750D02*
Y719100D01*
X382208Y717308D01*
X384292D01*
G01X385558Y717642D02*
X385850Y717933D01*
X386100Y718100D01*
X386433Y718183D01*
X386725Y718100D01*
X386933Y717933D01*
X387100Y717683D01*
X387142Y717392D01*
X387100Y717142D01*
X386933Y716892D01*
X386683Y716683D01*
X386392Y716600D01*
X386058Y716683D01*
X385767Y716933D01*
X385600Y717308D01*
X385558Y717725D01*
X385642Y718267D01*
X385767Y718558D01*
X385975Y718850D01*
X386267Y719058D01*
X386558Y719100D01*
X386850Y719017D01*
X387058Y718808D01*
G01X388658Y718683D02*
X388908Y718933D01*
X389200Y719058D01*
X389533Y719100D01*
X389950Y719017D01*
X390242Y718808D01*
X390325Y718558D01*
X390283Y718308D01*
X390117Y718100D01*
X389283Y717683D01*
X388908Y717392D01*
X388658Y716975D01*
X388575Y716600D01*
X390325D01*
G01X396727Y716027D02*
Y712027D01*
X404127D01*
G01X408750Y723363D02*
X408708Y723030D01*
X408542Y722738D01*
X408292Y722488D01*
X408000Y722321D01*
X407667Y722238D01*
X407333D01*
X407000Y722321D01*
X406708Y722488D01*
X406458Y722738D01*
X406292Y723030D01*
X406250Y723363D01*
X406292Y723696D01*
X406458Y723988D01*
X406708Y724238D01*
X407000Y724405D01*
X407333Y724488D01*
X407667D01*
X408000Y724405D01*
X408292Y724238D01*
X408542Y723988D01*
X408708Y723696D01*
X408750Y723363D01*
G01X408083Y723696D02*
X408750Y724196D01*
G01X406667Y725671D02*
X406417Y725921D01*
X406292Y726213D01*
X406250Y726546D01*
X406333Y726963D01*
X406542Y727255D01*
X406792Y727338D01*
X407042Y727296D01*
X407250Y727130D01*
X407667Y726296D01*
X407958Y725921D01*
X408375Y725671D01*
X408750Y725588D01*
Y727338D01*
G01X407708Y728771D02*
X407417Y729063D01*
X407250Y729313D01*
X407167Y729646D01*
X407250Y729938D01*
X407417Y730146D01*
X407667Y730313D01*
X407958Y730355D01*
X408208Y730313D01*
X408458Y730146D01*
X408667Y729896D01*
X408750Y729605D01*
X408667Y729271D01*
X408417Y728980D01*
X408042Y728813D01*
X407625Y728771D01*
X407083Y728855D01*
X406792Y728980D01*
X406500Y729188D01*
X406292Y729480D01*
X406250Y729771D01*
X406333Y730063D01*
X406542Y730271D01*
G01X407708Y731871D02*
X407417Y732163D01*
X407250Y732413D01*
X407167Y732746D01*
X407250Y733038D01*
X407417Y733246D01*
X407667Y733413D01*
X407958Y733455D01*
X408208Y733413D01*
X408458Y733246D01*
X408667Y732996D01*
X408750Y732705D01*
X408667Y732371D01*
X408417Y732080D01*
X408042Y731913D01*
X407625Y731871D01*
X407083Y731955D01*
X406792Y732080D01*
X406500Y732288D01*
X406292Y732580D01*
X406250Y732871D01*
X406333Y733163D01*
X406542Y733371D01*
G01X391750Y735513D02*
Y721513D01*
G01X404750Y735513D02*
X391750D01*
G01X404750Y721513D02*
Y735513D01*
G01X391750Y721513D02*
X404750D01*
G01X408754Y738283D02*
X408712Y737950D01*
X408546Y737658D01*
X408296Y737408D01*
X408004Y737241D01*
X407671Y737158D01*
X407337D01*
X407004Y737241D01*
X406712Y737408D01*
X406462Y737658D01*
X406296Y737950D01*
X406254Y738283D01*
X406296Y738616D01*
X406462Y738908D01*
X406712Y739158D01*
X407004Y739325D01*
X407337Y739408D01*
X407671D01*
X408004Y739325D01*
X408296Y739158D01*
X408546Y738908D01*
X408712Y738616D01*
X408754Y738283D01*
G01X408087Y738616D02*
X408754Y739116D01*
G01X406671Y740591D02*
X406421Y740841D01*
X406296Y741133D01*
X406254Y741466D01*
X406337Y741883D01*
X406546Y742175D01*
X406796Y742258D01*
X407046Y742216D01*
X407254Y742050D01*
X407671Y741216D01*
X407962Y740841D01*
X408379Y740591D01*
X408754Y740508D01*
Y742258D01*
G01X408254Y743566D02*
X408546Y743816D01*
X408712Y744150D01*
X408754Y744525D01*
X408712Y744858D01*
X408504Y745191D01*
X408254Y745400D01*
X408004Y745441D01*
X407712Y745358D01*
X407504Y745066D01*
X407421Y744775D01*
Y744400D01*
G01Y744775D02*
X407296Y745025D01*
X407087Y745233D01*
X406837Y745316D01*
X406587Y745233D01*
X406379Y745025D01*
X406254Y744650D01*
X406296Y744275D01*
X406462Y743900D01*
G01X406254Y747583D02*
X406337Y747250D01*
X406546Y747000D01*
X406796Y746833D01*
X407129Y746708D01*
X407504Y746666D01*
X407879Y746708D01*
X408212Y746833D01*
X408462Y747000D01*
X408671Y747250D01*
X408754Y747583D01*
X408671Y747916D01*
X408462Y748166D01*
X408212Y748333D01*
X407879Y748458D01*
X407504Y748500D01*
X407129Y748458D01*
X406796Y748333D01*
X406546Y748166D01*
X406337Y747916D01*
X406254Y747583D01*
G01X391754Y750433D02*
Y736433D01*
G01X404754D02*
Y750433D01*
G01X391754Y736433D02*
X404754D01*
G01X378867Y729338D02*
Y726838D01*
G01X377909Y729338D02*
X379825D01*
G01X381134Y726838D02*
Y729338D01*
X382134D01*
X382467Y729213D01*
X382717Y728921D01*
X382800Y728588D01*
X382717Y728255D01*
X382509Y728005D01*
X382134Y727880D01*
X381134D01*
G01X384984Y726838D02*
X385067Y727380D01*
X385192Y727838D01*
X385359Y728255D01*
X385567Y728713D01*
X385900Y729338D01*
X384234D01*
G01X387375Y728921D02*
X387625Y729171D01*
X387917Y729296D01*
X388250Y729338D01*
X388667Y729255D01*
X388959Y729046D01*
X389042Y728796D01*
X389000Y728546D01*
X388834Y728338D01*
X388000Y727921D01*
X387625Y727630D01*
X387375Y727213D01*
X387292Y726838D01*
X389042D01*
G01X375917Y712300D02*
Y714800D01*
X376958D01*
X377292Y714675D01*
X377500Y714508D01*
X377583Y714175D01*
X377500Y713842D01*
X377250Y713633D01*
X376958Y713508D01*
X375917D01*
G01X376958D02*
X377583Y712300D01*
G01X380350D02*
Y714800D01*
X378808Y713008D01*
X380892D01*
G01X382033Y712675D02*
X382283Y712467D01*
X382575Y712342D01*
X382950Y712300D01*
X383325Y712383D01*
X383617Y712550D01*
X383825Y712842D01*
X383867Y713175D01*
X383783Y713508D01*
X383575Y713717D01*
X383283Y713883D01*
X382992Y713925D01*
X382700Y713883D01*
X382325Y713717D01*
X382450Y714800D01*
X383575D01*
G01X385258Y713342D02*
X385550Y713633D01*
X385800Y713800D01*
X386133Y713883D01*
X386425Y713800D01*
X386633Y713633D01*
X386800Y713383D01*
X386842Y713092D01*
X386800Y712842D01*
X386633Y712592D01*
X386383Y712383D01*
X386092Y712300D01*
X385758Y712383D01*
X385467Y712633D01*
X385300Y713008D01*
X385258Y713425D01*
X385342Y713967D01*
X385467Y714258D01*
X385675Y714550D01*
X385967Y714758D01*
X386258Y714800D01*
X386550Y714717D01*
X386758Y714508D01*
G01X404754Y750433D02*
X391754D01*
G01X380979Y1069350D02*
X380729Y1069475D01*
X380437Y1069558D01*
X380104D01*
X379729Y1069433D01*
X379437Y1069225D01*
X379229Y1068975D01*
X379062Y1068558D01*
X379020Y1068183D01*
X379104Y1067808D01*
X379229Y1067558D01*
X379479Y1067308D01*
X379770Y1067141D01*
X380062Y1067058D01*
X380354D01*
X380645Y1067141D01*
X380895Y1067266D01*
X381104Y1067433D01*
G01X382370Y1068100D02*
X382662Y1068391D01*
X382912Y1068558D01*
X383245Y1068641D01*
X383537Y1068558D01*
X383745Y1068391D01*
X383912Y1068141D01*
X383954Y1067850D01*
X383912Y1067600D01*
X383745Y1067350D01*
X383495Y1067141D01*
X383204Y1067058D01*
X382870Y1067141D01*
X382579Y1067391D01*
X382412Y1067766D01*
X382370Y1068183D01*
X382454Y1068725D01*
X382579Y1069016D01*
X382787Y1069308D01*
X383079Y1069516D01*
X383370Y1069558D01*
X383662Y1069475D01*
X383870Y1069266D01*
G01X385345Y1067433D02*
X385595Y1067225D01*
X385887Y1067100D01*
X386262Y1067058D01*
X386637Y1067141D01*
X386929Y1067308D01*
X387137Y1067600D01*
X387179Y1067933D01*
X387095Y1068266D01*
X386887Y1068475D01*
X386595Y1068641D01*
X386304Y1068683D01*
X386012Y1068641D01*
X385637Y1068475D01*
X385762Y1069558D01*
X386887D01*
G01X380979Y1072850D02*
X380729Y1072975D01*
X380437Y1073058D01*
X380104D01*
X379729Y1072933D01*
X379437Y1072725D01*
X379229Y1072475D01*
X379062Y1072058D01*
X379020Y1071683D01*
X379104Y1071308D01*
X379229Y1071058D01*
X379479Y1070808D01*
X379770Y1070641D01*
X380062Y1070558D01*
X380354D01*
X380645Y1070641D01*
X380895Y1070766D01*
X381104Y1070933D01*
G01X382370Y1071600D02*
X382662Y1071891D01*
X382912Y1072058D01*
X383245Y1072141D01*
X383537Y1072058D01*
X383745Y1071891D01*
X383912Y1071641D01*
X383954Y1071350D01*
X383912Y1071100D01*
X383745Y1070850D01*
X383495Y1070641D01*
X383204Y1070558D01*
X382870Y1070641D01*
X382579Y1070891D01*
X382412Y1071266D01*
X382370Y1071683D01*
X382454Y1072225D01*
X382579Y1072516D01*
X382787Y1072808D01*
X383079Y1073016D01*
X383370Y1073058D01*
X383662Y1072975D01*
X383870Y1072766D01*
G01X386762Y1070558D02*
Y1073058D01*
X385220Y1071266D01*
X387304D01*
G01X378379Y1141273D02*
Y1143773D01*
X379420D01*
X379754Y1143648D01*
X379962Y1143481D01*
X380045Y1143148D01*
X379962Y1142815D01*
X379712Y1142606D01*
X379420Y1142481D01*
X378379D01*
G01X379420D02*
X380045Y1141273D01*
G01X382312D02*
Y1143773D01*
X381812Y1143273D01*
G01Y1141273D02*
X382812D01*
G01X385329D02*
X385412Y1141815D01*
X385537Y1142273D01*
X385704Y1142690D01*
X385912Y1143148D01*
X386245Y1143773D01*
X384579D01*
G01X388429Y1141273D02*
X388512Y1141815D01*
X388637Y1142273D01*
X388804Y1142690D01*
X389012Y1143148D01*
X389345Y1143773D01*
X387679D01*
G01X393062Y1148273D02*
Y1152273D01*
X385662D01*
G01X374258Y1172001D02*
Y1174501D01*
X375299D01*
X375633Y1174376D01*
X375841Y1174209D01*
X375924Y1173876D01*
X375841Y1173543D01*
X375591Y1173334D01*
X375299Y1173209D01*
X374258D01*
G01X375299D02*
X375924Y1172001D01*
G01X377274Y1172376D02*
X377524Y1172168D01*
X377816Y1172043D01*
X378191Y1172001D01*
X378566Y1172084D01*
X378858Y1172251D01*
X379066Y1172543D01*
X379108Y1172876D01*
X379024Y1173209D01*
X378816Y1173418D01*
X378524Y1173584D01*
X378233Y1173626D01*
X377941Y1173584D01*
X377566Y1173418D01*
X377691Y1174501D01*
X378816D01*
G01X380499Y1173043D02*
X380791Y1173334D01*
X381041Y1173501D01*
X381374Y1173584D01*
X381666Y1173501D01*
X381874Y1173334D01*
X382041Y1173084D01*
X382083Y1172793D01*
X382041Y1172543D01*
X381874Y1172293D01*
X381624Y1172084D01*
X381333Y1172001D01*
X380999Y1172084D01*
X380708Y1172334D01*
X380541Y1172709D01*
X380499Y1173126D01*
X380583Y1173668D01*
X380708Y1173959D01*
X380916Y1174251D01*
X381208Y1174459D01*
X381499Y1174501D01*
X381791Y1174418D01*
X381999Y1174209D01*
G01X383599Y1174084D02*
X383849Y1174334D01*
X384141Y1174459D01*
X384474Y1174501D01*
X384891Y1174418D01*
X385183Y1174209D01*
X385266Y1173959D01*
X385224Y1173709D01*
X385058Y1173501D01*
X384224Y1173084D01*
X383849Y1172793D01*
X383599Y1172376D01*
X383516Y1172001D01*
X385266D01*
G01X391067Y1171730D02*
X387067D01*
Y1164330D01*
G01X409252Y1179412D02*
X409210Y1179079D01*
X409044Y1178787D01*
X408794Y1178537D01*
X408502Y1178370D01*
X408169Y1178287D01*
X407835D01*
X407502Y1178370D01*
X407210Y1178537D01*
X406960Y1178787D01*
X406794Y1179079D01*
X406752Y1179412D01*
X406794Y1179745D01*
X406960Y1180037D01*
X407210Y1180287D01*
X407502Y1180454D01*
X407835Y1180537D01*
X408169D01*
X408502Y1180454D01*
X408794Y1180287D01*
X409044Y1180037D01*
X409210Y1179745D01*
X409252Y1179412D01*
G01X408585Y1179745D02*
X409252Y1180245D01*
G01X407169Y1181720D02*
X406919Y1181970D01*
X406794Y1182262D01*
X406752Y1182595D01*
X406835Y1183012D01*
X407044Y1183304D01*
X407294Y1183387D01*
X407544Y1183345D01*
X407752Y1183179D01*
X408169Y1182345D01*
X408460Y1181970D01*
X408877Y1181720D01*
X409252Y1181637D01*
Y1183387D01*
G01X408960Y1184904D02*
X409169Y1185195D01*
X409252Y1185529D01*
X409169Y1185862D01*
X408919Y1186154D01*
X408544Y1186362D01*
X408169Y1186445D01*
X407710D01*
X407335Y1186362D01*
X407002Y1186154D01*
X406835Y1185904D01*
X406752Y1185612D01*
X406835Y1185279D01*
X407002Y1185029D01*
X407252Y1184862D01*
X407585Y1184779D01*
X407877Y1184862D01*
X408169Y1185070D01*
X408335Y1185320D01*
X408377Y1185612D01*
X408294Y1185945D01*
X408085Y1186195D01*
X407710Y1186445D01*
G01X406752Y1188712D02*
X406835Y1188379D01*
X407044Y1188129D01*
X407294Y1187962D01*
X407627Y1187837D01*
X408002Y1187795D01*
X408377Y1187837D01*
X408710Y1187962D01*
X408960Y1188129D01*
X409169Y1188379D01*
X409252Y1188712D01*
X409169Y1189045D01*
X408960Y1189295D01*
X408710Y1189462D01*
X408377Y1189587D01*
X408002Y1189629D01*
X407627Y1189587D01*
X407294Y1189462D01*
X407044Y1189295D01*
X406835Y1189045D01*
X406752Y1188712D01*
G01X391781Y1182295D02*
Y1168295D01*
G01X404781D02*
Y1182295D01*
G01X391781Y1168295D02*
X404781D01*
G01X379550Y1182000D02*
Y1179500D01*
G01X378592Y1182000D02*
X380508D01*
G01X381817Y1179500D02*
Y1182000D01*
X382817D01*
X383150Y1181875D01*
X383400Y1181583D01*
X383483Y1181250D01*
X383400Y1180917D01*
X383192Y1180667D01*
X382817Y1180542D01*
X381817D01*
G01X385750Y1179500D02*
Y1182000D01*
X385250Y1181500D01*
G01Y1179500D02*
X386250D01*
G01X388058Y1181583D02*
X388308Y1181833D01*
X388600Y1181958D01*
X388933Y1182000D01*
X389350Y1181917D01*
X389642Y1181708D01*
X389725Y1181458D01*
X389683Y1181208D01*
X389517Y1181000D01*
X388683Y1180583D01*
X388308Y1180292D01*
X388058Y1179875D01*
X387975Y1179500D01*
X389725D01*
G01X380983Y1159062D02*
X378483D01*
Y1160103D01*
X378608Y1160437D01*
X378775Y1160645D01*
X379108Y1160728D01*
X379441Y1160645D01*
X379650Y1160395D01*
X379775Y1160103D01*
Y1159062D01*
G01Y1160103D02*
X380983Y1160728D01*
G01Y1162995D02*
X378483D01*
X378983Y1162495D01*
G01X380983D02*
Y1163495D01*
G01Y1166095D02*
X380941Y1166387D01*
X380816Y1166720D01*
X380608Y1166928D01*
X380316Y1167012D01*
X380025Y1166928D01*
X379775Y1166678D01*
X379650Y1166303D01*
Y1165887D01*
X379566Y1165637D01*
X379358Y1165428D01*
X379066Y1165345D01*
X378775Y1165470D01*
X378566Y1165762D01*
X378483Y1166095D01*
X378566Y1166428D01*
X378775Y1166720D01*
X379066Y1166845D01*
X379358Y1166762D01*
X379566Y1166553D01*
X379650Y1166303D01*
Y1165887D01*
X379775Y1165512D01*
X380025Y1165262D01*
X380316Y1165178D01*
X380608Y1165262D01*
X380816Y1165470D01*
X380941Y1165803D01*
X380983Y1166095D01*
G01X378483Y1169195D02*
X378566Y1168862D01*
X378775Y1168612D01*
X379025Y1168445D01*
X379358Y1168320D01*
X379733Y1168278D01*
X380108Y1168320D01*
X380441Y1168445D01*
X380691Y1168612D01*
X380900Y1168862D01*
X380983Y1169195D01*
X380900Y1169528D01*
X380691Y1169778D01*
X380441Y1169945D01*
X380108Y1170070D01*
X379733Y1170112D01*
X379358Y1170070D01*
X379025Y1169945D01*
X378775Y1169778D01*
X378566Y1169528D01*
X378483Y1169195D01*
G01X381679Y1139465D02*
X381429Y1139590D01*
X381137Y1139673D01*
X380804D01*
X380429Y1139548D01*
X380137Y1139340D01*
X379929Y1139090D01*
X379762Y1138673D01*
X379720Y1138298D01*
X379804Y1137923D01*
X379929Y1137673D01*
X380179Y1137423D01*
X380470Y1137256D01*
X380762Y1137173D01*
X381054D01*
X381345Y1137256D01*
X381595Y1137381D01*
X381804Y1137548D01*
G01X383779Y1137173D02*
X383862Y1137715D01*
X383987Y1138173D01*
X384154Y1138590D01*
X384362Y1139048D01*
X384695Y1139673D01*
X383029D01*
G01X386962D02*
X386629Y1139590D01*
X386379Y1139381D01*
X386212Y1139131D01*
X386087Y1138798D01*
X386045Y1138423D01*
X386087Y1138048D01*
X386212Y1137715D01*
X386379Y1137465D01*
X386629Y1137256D01*
X386962Y1137173D01*
X387295Y1137256D01*
X387545Y1137465D01*
X387712Y1137715D01*
X387837Y1138048D01*
X387879Y1138423D01*
X387837Y1138798D01*
X387712Y1139131D01*
X387545Y1139381D01*
X387295Y1139590D01*
X386962Y1139673D01*
G01X378317Y1184800D02*
Y1187300D01*
X379358D01*
X379692Y1187175D01*
X379900Y1187008D01*
X379983Y1186675D01*
X379900Y1186342D01*
X379650Y1186133D01*
X379358Y1186008D01*
X378317D01*
G01X379358D02*
X379983Y1184800D01*
G01X381333Y1185175D02*
X381583Y1184967D01*
X381875Y1184842D01*
X382250Y1184800D01*
X382625Y1184883D01*
X382917Y1185050D01*
X383125Y1185342D01*
X383167Y1185675D01*
X383083Y1186008D01*
X382875Y1186217D01*
X382583Y1186383D01*
X382292Y1186425D01*
X382000Y1186383D01*
X381625Y1186217D01*
X381750Y1187300D01*
X382875D01*
G01X384558Y1185842D02*
X384850Y1186133D01*
X385100Y1186300D01*
X385433Y1186383D01*
X385725Y1186300D01*
X385933Y1186133D01*
X386100Y1185883D01*
X386142Y1185592D01*
X386100Y1185342D01*
X385933Y1185092D01*
X385683Y1184883D01*
X385392Y1184800D01*
X385058Y1184883D01*
X384767Y1185133D01*
X384600Y1185508D01*
X384558Y1185925D01*
X384642Y1186467D01*
X384767Y1186758D01*
X384975Y1187050D01*
X385267Y1187258D01*
X385558Y1187300D01*
X385850Y1187217D01*
X386058Y1187008D01*
G01X387742Y1185092D02*
X388033Y1184883D01*
X388367Y1184800D01*
X388700Y1184883D01*
X388992Y1185133D01*
X389200Y1185508D01*
X389283Y1185883D01*
Y1186342D01*
X389200Y1186717D01*
X388992Y1187050D01*
X388742Y1187217D01*
X388450Y1187300D01*
X388117Y1187217D01*
X387867Y1187050D01*
X387700Y1186800D01*
X387617Y1186467D01*
X387700Y1186175D01*
X387908Y1185883D01*
X388158Y1185717D01*
X388450Y1185675D01*
X388783Y1185758D01*
X389033Y1185967D01*
X389283Y1186342D01*
G01X396953Y1187011D02*
Y1183011D01*
X404353D01*
G01X404781Y1182295D02*
X391781D01*
G01X395350Y1205500D02*
X395017Y1205542D01*
X394725Y1205708D01*
X394475Y1205958D01*
X394308Y1206250D01*
X394225Y1206583D01*
Y1206917D01*
X394308Y1207250D01*
X394475Y1207542D01*
X394725Y1207792D01*
X395017Y1207958D01*
X395350Y1208000D01*
X395683Y1207958D01*
X395975Y1207792D01*
X396225Y1207542D01*
X396392Y1207250D01*
X396475Y1206917D01*
Y1206583D01*
X396392Y1206250D01*
X396225Y1205958D01*
X395975Y1205708D01*
X395683Y1205542D01*
X395350Y1205500D01*
G01X395683Y1206167D02*
X396183Y1205500D01*
G01X397658Y1207583D02*
X397908Y1207833D01*
X398200Y1207958D01*
X398533Y1208000D01*
X398950Y1207917D01*
X399242Y1207708D01*
X399325Y1207458D01*
X399283Y1207208D01*
X399117Y1207000D01*
X398283Y1206583D01*
X397908Y1206292D01*
X397658Y1205875D01*
X397575Y1205500D01*
X399325D01*
G01X400633Y1205875D02*
X400883Y1205667D01*
X401175Y1205542D01*
X401550Y1205500D01*
X401925Y1205583D01*
X402217Y1205750D01*
X402425Y1206042D01*
X402467Y1206375D01*
X402383Y1206708D01*
X402175Y1206917D01*
X401883Y1207083D01*
X401592Y1207125D01*
X401300Y1207083D01*
X400925Y1206917D01*
X401050Y1208000D01*
X402175D01*
G01X405150Y1205500D02*
Y1208000D01*
X403608Y1206208D01*
X405692D01*
G01X391886Y1203474D02*
Y1189474D01*
G01X404886Y1203474D02*
X391886D01*
G01X404886Y1189474D02*
Y1203474D01*
G01X391886Y1189474D02*
X404886D01*
G01X384849Y1205759D02*
X382349D01*
Y1206800D01*
X382474Y1207134D01*
X382641Y1207342D01*
X382974Y1207425D01*
X383307Y1207342D01*
X383516Y1207092D01*
X383641Y1206800D01*
Y1205759D01*
G01Y1206800D02*
X384849Y1207425D01*
G01X382766Y1208900D02*
X382516Y1209150D01*
X382391Y1209442D01*
X382349Y1209775D01*
X382432Y1210192D01*
X382641Y1210484D01*
X382891Y1210567D01*
X383141Y1210525D01*
X383349Y1210359D01*
X383766Y1209525D01*
X384057Y1209150D01*
X384474Y1208900D01*
X384849Y1208817D01*
Y1210567D01*
G01X384349Y1211875D02*
X384641Y1212125D01*
X384807Y1212459D01*
X384849Y1212834D01*
X384807Y1213167D01*
X384599Y1213500D01*
X384349Y1213709D01*
X384099Y1213750D01*
X383807Y1213667D01*
X383599Y1213375D01*
X383516Y1213084D01*
Y1212709D01*
G01Y1213084D02*
X383391Y1213334D01*
X383182Y1213542D01*
X382932Y1213625D01*
X382682Y1213542D01*
X382474Y1213334D01*
X382349Y1212959D01*
X382391Y1212584D01*
X382557Y1212209D01*
G01X384349Y1214975D02*
X384641Y1215225D01*
X384807Y1215559D01*
X384849Y1215934D01*
X384807Y1216267D01*
X384599Y1216600D01*
X384349Y1216809D01*
X384099Y1216850D01*
X383807Y1216767D01*
X383599Y1216475D01*
X383516Y1216184D01*
Y1215809D01*
G01Y1216184D02*
X383391Y1216434D01*
X383182Y1216642D01*
X382932Y1216725D01*
X382682Y1216642D01*
X382474Y1216434D01*
X382349Y1216059D01*
X382391Y1215684D01*
X382557Y1215309D01*
G01X389849Y1205759D02*
X387349D01*
Y1206800D01*
X387474Y1207134D01*
X387641Y1207342D01*
X387974Y1207425D01*
X388307Y1207342D01*
X388516Y1207092D01*
X388641Y1206800D01*
Y1205759D01*
G01Y1206800D02*
X389849Y1207425D01*
G01X387766Y1208900D02*
X387516Y1209150D01*
X387391Y1209442D01*
X387349Y1209775D01*
X387432Y1210192D01*
X387641Y1210484D01*
X387891Y1210567D01*
X388141Y1210525D01*
X388349Y1210359D01*
X388766Y1209525D01*
X389057Y1209150D01*
X389474Y1208900D01*
X389849Y1208817D01*
Y1210567D01*
G01X389349Y1211875D02*
X389641Y1212125D01*
X389807Y1212459D01*
X389849Y1212834D01*
X389807Y1213167D01*
X389599Y1213500D01*
X389349Y1213709D01*
X389099Y1213750D01*
X388807Y1213667D01*
X388599Y1213375D01*
X388516Y1213084D01*
Y1212709D01*
G01Y1213084D02*
X388391Y1213334D01*
X388182Y1213542D01*
X387932Y1213625D01*
X387682Y1213542D01*
X387474Y1213334D01*
X387349Y1212959D01*
X387391Y1212584D01*
X387557Y1212209D01*
G01X387766Y1215100D02*
X387516Y1215350D01*
X387391Y1215642D01*
X387349Y1215975D01*
X387432Y1216392D01*
X387641Y1216684D01*
X387891Y1216767D01*
X388141Y1216725D01*
X388349Y1216559D01*
X388766Y1215725D01*
X389057Y1215350D01*
X389474Y1215100D01*
X389849Y1215017D01*
Y1216767D01*
G01X446900Y163517D02*
X444400D01*
Y164558D01*
X444525Y164892D01*
X444692Y165100D01*
X445025Y165183D01*
X445358Y165100D01*
X445567Y164850D01*
X445692Y164558D01*
Y163517D01*
G01Y164558D02*
X446900Y165183D01*
G01Y167367D02*
X446358Y167450D01*
X445900Y167575D01*
X445483Y167742D01*
X445025Y167950D01*
X444400Y168283D01*
Y166617D01*
G01X445858Y169758D02*
X445567Y170050D01*
X445400Y170300D01*
X445317Y170633D01*
X445400Y170925D01*
X445567Y171133D01*
X445817Y171300D01*
X446108Y171342D01*
X446358Y171300D01*
X446608Y171133D01*
X446817Y170883D01*
X446900Y170592D01*
X446817Y170258D01*
X446567Y169967D01*
X446192Y169800D01*
X445775Y169758D01*
X445233Y169842D01*
X444942Y169967D01*
X444650Y170175D01*
X444442Y170467D01*
X444400Y170758D01*
X444483Y171050D01*
X444692Y171258D01*
G01X446900Y173650D02*
X446858Y173942D01*
X446733Y174275D01*
X446525Y174483D01*
X446233Y174567D01*
X445942Y174483D01*
X445692Y174233D01*
X445567Y173858D01*
Y173442D01*
X445483Y173192D01*
X445275Y172983D01*
X444983Y172900D01*
X444692Y173025D01*
X444483Y173317D01*
X444400Y173650D01*
X444483Y173983D01*
X444692Y174275D01*
X444983Y174400D01*
X445275Y174317D01*
X445483Y174108D01*
X445567Y173858D01*
Y173442D01*
X445692Y173067D01*
X445942Y172817D01*
X446233Y172733D01*
X446525Y172817D01*
X446733Y173025D01*
X446858Y173358D01*
X446900Y173650D01*
G01X456666Y162369D02*
Y164869D01*
X457707D01*
X458041Y164744D01*
X458249Y164577D01*
X458332Y164244D01*
X458249Y163911D01*
X457999Y163702D01*
X457707Y163577D01*
X456666D01*
G01X457707D02*
X458332Y162369D01*
G01X460516D02*
X460599Y162911D01*
X460724Y163369D01*
X460891Y163786D01*
X461099Y164244D01*
X461432Y164869D01*
X459766D01*
G01X462907Y163411D02*
X463199Y163702D01*
X463449Y163869D01*
X463782Y163952D01*
X464074Y163869D01*
X464282Y163702D01*
X464449Y163452D01*
X464491Y163161D01*
X464449Y162911D01*
X464282Y162661D01*
X464032Y162452D01*
X463741Y162369D01*
X463407Y162452D01*
X463116Y162702D01*
X462949Y163077D01*
X462907Y163494D01*
X462991Y164036D01*
X463116Y164327D01*
X463324Y164619D01*
X463616Y164827D01*
X463907Y164869D01*
X464199Y164786D01*
X464407Y164577D01*
G01X466799Y162369D02*
Y164869D01*
X466299Y164369D01*
G01Y162369D02*
X467299D01*
G01X440000Y163483D02*
X437500D01*
Y164317D01*
X437625Y164650D01*
X437792Y164900D01*
X438042Y165108D01*
X438333Y165275D01*
X438750Y165317D01*
X439167Y165275D01*
X439458Y165108D01*
X439708Y164900D01*
X439875Y164650D01*
X440000Y164317D01*
Y163483D01*
G01X437917Y166708D02*
X437667Y166958D01*
X437542Y167250D01*
X437500Y167583D01*
X437583Y168000D01*
X437792Y168292D01*
X438042Y168375D01*
X438292Y168333D01*
X438500Y168167D01*
X438917Y167333D01*
X439208Y166958D01*
X439625Y166708D01*
X440000Y166625D01*
Y168375D01*
G01Y170517D02*
X439458Y170600D01*
X439000Y170725D01*
X438583Y170892D01*
X438125Y171100D01*
X437500Y171433D01*
Y169767D01*
G01X447474Y183361D02*
X443474D01*
Y175961D01*
G01X456666Y166069D02*
Y168569D01*
X457707D01*
X458041Y168444D01*
X458249Y168277D01*
X458332Y167944D01*
X458249Y167611D01*
X457999Y167402D01*
X457707Y167277D01*
X456666D01*
G01X457707D02*
X458332Y166069D01*
G01X460516D02*
X460599Y166611D01*
X460724Y167069D01*
X460891Y167486D01*
X461099Y167944D01*
X461432Y168569D01*
X459766D01*
G01X462782Y166444D02*
X463032Y166236D01*
X463324Y166111D01*
X463699Y166069D01*
X464074Y166152D01*
X464366Y166319D01*
X464574Y166611D01*
X464616Y166944D01*
X464532Y167277D01*
X464324Y167486D01*
X464032Y167652D01*
X463741Y167694D01*
X463449Y167652D01*
X463074Y167486D01*
X463199Y168569D01*
X464324D01*
G01X466091Y166361D02*
X466382Y166152D01*
X466716Y166069D01*
X467049Y166152D01*
X467341Y166402D01*
X467549Y166777D01*
X467632Y167152D01*
Y167611D01*
X467549Y167986D01*
X467341Y168319D01*
X467091Y168486D01*
X466799Y168569D01*
X466466Y168486D01*
X466216Y168319D01*
X466049Y168069D01*
X465966Y167736D01*
X466049Y167444D01*
X466257Y167152D01*
X466507Y166986D01*
X466799Y166944D01*
X467132Y167027D01*
X467382Y167236D01*
X467632Y167611D01*
G01X456666Y169769D02*
Y172269D01*
X457707D01*
X458041Y172144D01*
X458249Y171977D01*
X458332Y171644D01*
X458249Y171311D01*
X457999Y171102D01*
X457707Y170977D01*
X456666D01*
G01X457707D02*
X458332Y169769D01*
G01X460516D02*
X460599Y170311D01*
X460724Y170769D01*
X460891Y171186D01*
X461099Y171644D01*
X461432Y172269D01*
X459766D01*
G01X462907Y170811D02*
X463199Y171102D01*
X463449Y171269D01*
X463782Y171352D01*
X464074Y171269D01*
X464282Y171102D01*
X464449Y170852D01*
X464491Y170561D01*
X464449Y170311D01*
X464282Y170061D01*
X464032Y169852D01*
X463741Y169769D01*
X463407Y169852D01*
X463116Y170102D01*
X462949Y170477D01*
X462907Y170894D01*
X462991Y171436D01*
X463116Y171727D01*
X463324Y172019D01*
X463616Y172227D01*
X463907Y172269D01*
X464199Y172186D01*
X464407Y171977D01*
G01X465882Y170269D02*
X466132Y169977D01*
X466466Y169811D01*
X466841Y169769D01*
X467174Y169811D01*
X467507Y170019D01*
X467716Y170269D01*
X467757Y170519D01*
X467674Y170811D01*
X467382Y171019D01*
X467091Y171102D01*
X466716D01*
G01X467091D02*
X467341Y171227D01*
X467549Y171436D01*
X467632Y171686D01*
X467549Y171936D01*
X467341Y172144D01*
X466966Y172269D01*
X466591Y172227D01*
X466216Y172061D01*
G01X429500Y183617D02*
X427000D01*
Y184658D01*
X427125Y184992D01*
X427292Y185200D01*
X427625Y185283D01*
X427958Y185200D01*
X428167Y184950D01*
X428292Y184658D01*
Y183617D01*
G01Y184658D02*
X429500Y185283D01*
G01Y187467D02*
X428958Y187550D01*
X428500Y187675D01*
X428083Y187842D01*
X427625Y188050D01*
X427000Y188383D01*
Y186717D01*
G01X428458Y189858D02*
X428167Y190150D01*
X428000Y190400D01*
X427917Y190733D01*
X428000Y191025D01*
X428167Y191233D01*
X428417Y191400D01*
X428708Y191442D01*
X428958Y191400D01*
X429208Y191233D01*
X429417Y190983D01*
X429500Y190692D01*
X429417Y190358D01*
X429167Y190067D01*
X428792Y189900D01*
X428375Y189858D01*
X427833Y189942D01*
X427542Y190067D01*
X427250Y190275D01*
X427042Y190567D01*
X427000Y190858D01*
X427083Y191150D01*
X427292Y191358D01*
G01X429500Y193667D02*
X428958Y193750D01*
X428500Y193875D01*
X428083Y194042D01*
X427625Y194250D01*
X427000Y194583D01*
Y192917D01*
G01X430574Y182061D02*
X434574D01*
Y189461D01*
G01X422917Y172000D02*
Y174500D01*
X423958D01*
X424292Y174375D01*
X424500Y174208D01*
X424583Y173875D01*
X424500Y173542D01*
X424250Y173333D01*
X423958Y173208D01*
X422917D01*
G01X423958D02*
X424583Y172000D01*
G01X426767D02*
X426850Y172542D01*
X426975Y173000D01*
X427142Y173417D01*
X427350Y173875D01*
X427683Y174500D01*
X426017D01*
G01X429158Y173042D02*
X429450Y173333D01*
X429700Y173500D01*
X430033Y173583D01*
X430325Y173500D01*
X430533Y173333D01*
X430700Y173083D01*
X430742Y172792D01*
X430700Y172542D01*
X430533Y172292D01*
X430283Y172083D01*
X429992Y172000D01*
X429658Y172083D01*
X429367Y172333D01*
X429200Y172708D01*
X429158Y173125D01*
X429242Y173667D01*
X429367Y173958D01*
X429575Y174250D01*
X429867Y174458D01*
X430158Y174500D01*
X430450Y174417D01*
X430658Y174208D01*
G01X432133Y172375D02*
X432383Y172167D01*
X432675Y172042D01*
X433050Y172000D01*
X433425Y172083D01*
X433717Y172250D01*
X433925Y172542D01*
X433967Y172875D01*
X433883Y173208D01*
X433675Y173417D01*
X433383Y173583D01*
X433092Y173625D01*
X432800Y173583D01*
X432425Y173417D01*
X432550Y174500D01*
X433675D01*
G01X427274Y181661D02*
Y177661D01*
X434674D01*
G01X415091Y210561D02*
Y213061D01*
X416132D01*
X416466Y212936D01*
X416674Y212769D01*
X416757Y212436D01*
X416674Y212103D01*
X416424Y211894D01*
X416132Y211769D01*
X415091D01*
G01X416132D02*
X416757Y210561D01*
G01X418941D02*
X419024Y211103D01*
X419149Y211561D01*
X419316Y211978D01*
X419524Y212436D01*
X419857Y213061D01*
X418191D01*
G01X421332Y211603D02*
X421624Y211894D01*
X421874Y212061D01*
X422207Y212144D01*
X422499Y212061D01*
X422707Y211894D01*
X422874Y211644D01*
X422916Y211353D01*
X422874Y211103D01*
X422707Y210853D01*
X422457Y210644D01*
X422166Y210561D01*
X421832Y210644D01*
X421541Y210894D01*
X421374Y211269D01*
X421332Y211686D01*
X421416Y212228D01*
X421541Y212519D01*
X421749Y212811D01*
X422041Y213019D01*
X422332Y213061D01*
X422624Y212978D01*
X422832Y212769D01*
G01X424432Y211603D02*
X424724Y211894D01*
X424974Y212061D01*
X425307Y212144D01*
X425599Y212061D01*
X425807Y211894D01*
X425974Y211644D01*
X426016Y211353D01*
X425974Y211103D01*
X425807Y210853D01*
X425557Y210644D01*
X425266Y210561D01*
X424932Y210644D01*
X424641Y210894D01*
X424474Y211269D01*
X424432Y211686D01*
X424516Y212228D01*
X424641Y212519D01*
X424849Y212811D01*
X425141Y213019D01*
X425432Y213061D01*
X425724Y212978D01*
X425932Y212769D01*
G01X434774Y208561D02*
Y212561D01*
X427374D01*
G01X423391Y201061D02*
Y203561D01*
X424432D01*
X424766Y203436D01*
X424974Y203269D01*
X425057Y202936D01*
X424974Y202603D01*
X424724Y202394D01*
X424432Y202269D01*
X423391D01*
G01X424432D02*
X425057Y201061D01*
G01X427241D02*
X427324Y201603D01*
X427449Y202061D01*
X427616Y202478D01*
X427824Y202936D01*
X428157Y203561D01*
X426491D01*
G01X429507Y201436D02*
X429757Y201228D01*
X430049Y201103D01*
X430424Y201061D01*
X430799Y201144D01*
X431091Y201311D01*
X431299Y201603D01*
X431341Y201936D01*
X431257Y202269D01*
X431049Y202478D01*
X430757Y202644D01*
X430466Y202686D01*
X430174Y202644D01*
X429799Y202478D01*
X429924Y203561D01*
X431049D01*
G01X433524Y201061D02*
X433816Y201103D01*
X434149Y201228D01*
X434357Y201436D01*
X434441Y201728D01*
X434357Y202019D01*
X434107Y202269D01*
X433732Y202394D01*
X433316D01*
X433066Y202478D01*
X432857Y202686D01*
X432774Y202978D01*
X432899Y203269D01*
X433191Y203478D01*
X433524Y203561D01*
X433857Y203478D01*
X434149Y203269D01*
X434274Y202978D01*
X434191Y202686D01*
X433982Y202478D01*
X433732Y202394D01*
X433316D01*
X432941Y202269D01*
X432691Y202019D01*
X432607Y201728D01*
X432691Y201436D01*
X432899Y201228D01*
X433232Y201103D01*
X433524Y201061D01*
G01X435174Y207061D02*
Y203061D01*
X442574D01*
G01X435850Y194000D02*
X435517Y194042D01*
X435225Y194208D01*
X434975Y194458D01*
X434808Y194750D01*
X434725Y195083D01*
Y195417D01*
X434808Y195750D01*
X434975Y196042D01*
X435225Y196292D01*
X435517Y196458D01*
X435850Y196500D01*
X436183Y196458D01*
X436475Y196292D01*
X436725Y196042D01*
X436892Y195750D01*
X436975Y195417D01*
Y195083D01*
X436892Y194750D01*
X436725Y194458D01*
X436475Y194208D01*
X436183Y194042D01*
X435850Y194000D01*
G01X436183Y194667D02*
X436683Y194000D01*
G01X438950D02*
Y196500D01*
X438450Y196000D01*
G01Y194000D02*
X439450D01*
G01X441258Y195042D02*
X441550Y195333D01*
X441800Y195500D01*
X442133Y195583D01*
X442425Y195500D01*
X442633Y195333D01*
X442800Y195083D01*
X442842Y194792D01*
X442800Y194542D01*
X442633Y194292D01*
X442383Y194083D01*
X442092Y194000D01*
X441758Y194083D01*
X441467Y194333D01*
X441300Y194708D01*
X441258Y195125D01*
X441342Y195667D01*
X441467Y195958D01*
X441675Y196250D01*
X441967Y196458D01*
X442258Y196500D01*
X442550Y196417D01*
X442758Y196208D01*
G01X444233Y194500D02*
X444483Y194208D01*
X444817Y194042D01*
X445192Y194000D01*
X445525Y194042D01*
X445858Y194250D01*
X446067Y194500D01*
X446108Y194750D01*
X446025Y195042D01*
X445733Y195250D01*
X445442Y195333D01*
X445067D01*
G01X445442D02*
X445692Y195458D01*
X445900Y195667D01*
X445983Y195917D01*
X445900Y196167D01*
X445692Y196375D01*
X445317Y196500D01*
X444942Y196458D01*
X444567Y196292D01*
G01X458774Y197861D02*
X447374D01*
G01X458774Y184461D02*
Y197861D01*
G01X447374Y184461D02*
X458774D01*
G01X447374Y197861D02*
Y184461D01*
G01X442574Y192161D02*
Y176061D01*
G01X435574Y192161D02*
X442574D01*
G01X435574Y176061D02*
Y192161D01*
G01X442574Y176061D02*
X435574D01*
G01X464874Y223261D02*
X445674D01*
Y212061D01*
X464874D01*
Y223261D01*
X464474D01*
G01X425141Y207453D02*
X424891Y207578D01*
X424599Y207661D01*
X424266D01*
X423891Y207536D01*
X423599Y207328D01*
X423391Y207078D01*
X423224Y206661D01*
X423182Y206286D01*
X423266Y205911D01*
X423391Y205661D01*
X423641Y205411D01*
X423932Y205244D01*
X424224Y205161D01*
X424516D01*
X424807Y205244D01*
X425057Y205369D01*
X425266Y205536D01*
G01X426407Y205661D02*
X426657Y205369D01*
X426991Y205203D01*
X427366Y205161D01*
X427699Y205203D01*
X428032Y205411D01*
X428241Y205661D01*
X428282Y205911D01*
X428199Y206203D01*
X427907Y206411D01*
X427616Y206494D01*
X427241D01*
G01X427616D02*
X427866Y206619D01*
X428074Y206828D01*
X428157Y207078D01*
X428074Y207328D01*
X427866Y207536D01*
X427491Y207661D01*
X427116Y207619D01*
X426741Y207453D01*
G01X429716Y205453D02*
X430007Y205244D01*
X430341Y205161D01*
X430674Y205244D01*
X430966Y205494D01*
X431174Y205869D01*
X431257Y206244D01*
Y206703D01*
X431174Y207078D01*
X430966Y207411D01*
X430716Y207578D01*
X430424Y207661D01*
X430091Y207578D01*
X429841Y207411D01*
X429674Y207161D01*
X429591Y206828D01*
X429674Y206536D01*
X429882Y206244D01*
X430132Y206078D01*
X430424Y206036D01*
X430757Y206119D01*
X431007Y206328D01*
X431257Y206703D01*
G01X432816Y205453D02*
X433107Y205244D01*
X433441Y205161D01*
X433774Y205244D01*
X434066Y205494D01*
X434274Y205869D01*
X434357Y206244D01*
Y206703D01*
X434274Y207078D01*
X434066Y207411D01*
X433816Y207578D01*
X433524Y207661D01*
X433191Y207578D01*
X432941Y207411D01*
X432774Y207161D01*
X432691Y206828D01*
X432774Y206536D01*
X432982Y206244D01*
X433232Y206078D01*
X433524Y206036D01*
X433857Y206119D01*
X434107Y206328D01*
X434357Y206703D01*
G01X438274Y250661D02*
Y258661D01*
X455874D01*
Y250661D01*
X438274D01*
G01X426767Y261792D02*
X426517Y261917D01*
X426225Y262000D01*
X425892D01*
X425517Y261875D01*
X425225Y261667D01*
X425017Y261417D01*
X424850Y261000D01*
X424808Y260625D01*
X424892Y260250D01*
X425017Y260000D01*
X425267Y259750D01*
X425558Y259583D01*
X425850Y259500D01*
X426142D01*
X426433Y259583D01*
X426683Y259708D01*
X426892Y259875D01*
G01X428033Y260000D02*
X428283Y259708D01*
X428617Y259542D01*
X428992Y259500D01*
X429325Y259542D01*
X429658Y259750D01*
X429867Y260000D01*
X429908Y260250D01*
X429825Y260542D01*
X429533Y260750D01*
X429242Y260833D01*
X428867D01*
G01X429242D02*
X429492Y260958D01*
X429700Y261167D01*
X429783Y261417D01*
X429700Y261667D01*
X429492Y261875D01*
X429117Y262000D01*
X428742Y261958D01*
X428367Y261792D01*
G01X431342Y259792D02*
X431633Y259583D01*
X431967Y259500D01*
X432300Y259583D01*
X432592Y259833D01*
X432800Y260208D01*
X432883Y260583D01*
Y261042D01*
X432800Y261417D01*
X432592Y261750D01*
X432342Y261917D01*
X432050Y262000D01*
X431717Y261917D01*
X431467Y261750D01*
X431300Y261500D01*
X431217Y261167D01*
X431300Y260875D01*
X431508Y260583D01*
X431758Y260417D01*
X432050Y260375D01*
X432383Y260458D01*
X432633Y260667D01*
X432883Y261042D01*
G01X434233Y259875D02*
X434483Y259667D01*
X434775Y259542D01*
X435150Y259500D01*
X435525Y259583D01*
X435817Y259750D01*
X436025Y260042D01*
X436067Y260375D01*
X435983Y260708D01*
X435775Y260917D01*
X435483Y261083D01*
X435192Y261125D01*
X434900Y261083D01*
X434525Y260917D01*
X434650Y262000D01*
X435775D01*
G01X460374Y236161D02*
X454874D01*
G01Y244161D02*
X460374D01*
G01X442774D02*
X448274D01*
G01X442774Y236161D02*
Y244161D01*
G01X448274Y236161D02*
X442774D01*
G01X418500Y222850D02*
X418458Y222517D01*
X418292Y222225D01*
X418042Y221975D01*
X417750Y221808D01*
X417417Y221725D01*
X417083D01*
X416750Y221808D01*
X416458Y221975D01*
X416208Y222225D01*
X416042Y222517D01*
X416000Y222850D01*
X416042Y223183D01*
X416208Y223475D01*
X416458Y223725D01*
X416750Y223892D01*
X417083Y223975D01*
X417417D01*
X417750Y223892D01*
X418042Y223725D01*
X418292Y223475D01*
X418458Y223183D01*
X418500Y222850D01*
G01X417833Y223183D02*
X418500Y223683D01*
G01Y225950D02*
X416000D01*
X416500Y225450D01*
G01X418500D02*
Y226450D01*
G01X417458Y228258D02*
X417167Y228550D01*
X417000Y228800D01*
X416917Y229133D01*
X417000Y229425D01*
X417167Y229633D01*
X417417Y229800D01*
X417708Y229842D01*
X417958Y229800D01*
X418208Y229633D01*
X418417Y229383D01*
X418500Y229092D01*
X418417Y228758D01*
X418167Y228467D01*
X417792Y228300D01*
X417375Y228258D01*
X416833Y228342D01*
X416542Y228467D01*
X416250Y228675D01*
X416042Y228967D01*
X416000Y229258D01*
X416083Y229550D01*
X416292Y229758D01*
G01X418500Y232650D02*
X416000D01*
X417792Y231108D01*
Y233192D01*
G01X420374Y237661D02*
X422474Y235861D01*
X420374Y233661D01*
G01X420274Y230061D02*
X439474D01*
Y241261D01*
X420274D01*
Y230061D01*
X420674D01*
G01X416841Y216953D02*
X416591Y217078D01*
X416299Y217161D01*
X415966D01*
X415591Y217036D01*
X415299Y216828D01*
X415091Y216578D01*
X414924Y216161D01*
X414882Y215786D01*
X414966Y215411D01*
X415091Y215161D01*
X415341Y214911D01*
X415632Y214744D01*
X415924Y214661D01*
X416216D01*
X416507Y214744D01*
X416757Y214869D01*
X416966Y215036D01*
G01X419524Y214661D02*
Y217161D01*
X417982Y215369D01*
X420066D01*
G01X422124Y217161D02*
X421791Y217078D01*
X421541Y216869D01*
X421374Y216619D01*
X421249Y216286D01*
X421207Y215911D01*
X421249Y215536D01*
X421374Y215203D01*
X421541Y214953D01*
X421791Y214744D01*
X422124Y214661D01*
X422457Y214744D01*
X422707Y214953D01*
X422874Y215203D01*
X422999Y215536D01*
X423041Y215911D01*
X422999Y216286D01*
X422874Y216619D01*
X422707Y216869D01*
X422457Y217078D01*
X422124Y217161D01*
G01X425224D02*
X424891Y217078D01*
X424641Y216869D01*
X424474Y216619D01*
X424349Y216286D01*
X424307Y215911D01*
X424349Y215536D01*
X424474Y215203D01*
X424641Y214953D01*
X424891Y214744D01*
X425224Y214661D01*
X425557Y214744D01*
X425807Y214953D01*
X425974Y215203D01*
X426099Y215536D01*
X426141Y215911D01*
X426099Y216286D01*
X425974Y216619D01*
X425807Y216869D01*
X425557Y217078D01*
X425224Y217161D01*
G01X444017Y271000D02*
Y273500D01*
X445058D01*
X445392Y273375D01*
X445600Y273208D01*
X445683Y272875D01*
X445600Y272542D01*
X445350Y272333D01*
X445058Y272208D01*
X444017D01*
G01X445058D02*
X445683Y271000D01*
G01X447867D02*
X447950Y271542D01*
X448075Y272000D01*
X448242Y272417D01*
X448450Y272875D01*
X448783Y273500D01*
X447117D01*
G01X450133Y271375D02*
X450383Y271167D01*
X450675Y271042D01*
X451050Y271000D01*
X451425Y271083D01*
X451717Y271250D01*
X451925Y271542D01*
X451967Y271875D01*
X451883Y272208D01*
X451675Y272417D01*
X451383Y272583D01*
X451092Y272625D01*
X450800Y272583D01*
X450425Y272417D01*
X450550Y273500D01*
X451675D01*
G01X453358Y273083D02*
X453608Y273333D01*
X453900Y273458D01*
X454233Y273500D01*
X454650Y273417D01*
X454942Y273208D01*
X455025Y272958D01*
X454983Y272708D01*
X454817Y272500D01*
X453983Y272083D01*
X453608Y271792D01*
X453358Y271375D01*
X453275Y271000D01*
X455025D01*
G01X445767Y265292D02*
X445517Y265417D01*
X445225Y265500D01*
X444892D01*
X444517Y265375D01*
X444225Y265167D01*
X444017Y264917D01*
X443850Y264500D01*
X443808Y264125D01*
X443892Y263750D01*
X444017Y263500D01*
X444267Y263250D01*
X444558Y263083D01*
X444850Y263000D01*
X445142D01*
X445433Y263083D01*
X445683Y263208D01*
X445892Y263375D01*
G01X447033Y263500D02*
X447283Y263208D01*
X447617Y263042D01*
X447992Y263000D01*
X448325Y263042D01*
X448658Y263250D01*
X448867Y263500D01*
X448908Y263750D01*
X448825Y264042D01*
X448533Y264250D01*
X448242Y264333D01*
X447867D01*
G01X448242D02*
X448492Y264458D01*
X448700Y264667D01*
X448783Y264917D01*
X448700Y265167D01*
X448492Y265375D01*
X448117Y265500D01*
X447742Y265458D01*
X447367Y265292D01*
G01X450342Y263292D02*
X450633Y263083D01*
X450967Y263000D01*
X451300Y263083D01*
X451592Y263333D01*
X451800Y263708D01*
X451883Y264083D01*
Y264542D01*
X451800Y264917D01*
X451592Y265250D01*
X451342Y265417D01*
X451050Y265500D01*
X450717Y265417D01*
X450467Y265250D01*
X450300Y265000D01*
X450217Y264667D01*
X450300Y264375D01*
X450508Y264083D01*
X450758Y263917D01*
X451050Y263875D01*
X451383Y263958D01*
X451633Y264167D01*
X451883Y264542D01*
G01X453358Y265083D02*
X453608Y265333D01*
X453900Y265458D01*
X454233Y265500D01*
X454650Y265417D01*
X454942Y265208D01*
X455025Y264958D01*
X454983Y264708D01*
X454817Y264500D01*
X453983Y264083D01*
X453608Y263792D01*
X453358Y263375D01*
X453275Y263000D01*
X455025D01*
G01X445767Y269292D02*
X445517Y269417D01*
X445225Y269500D01*
X444892D01*
X444517Y269375D01*
X444225Y269167D01*
X444017Y268917D01*
X443850Y268500D01*
X443808Y268125D01*
X443892Y267750D01*
X444017Y267500D01*
X444267Y267250D01*
X444558Y267083D01*
X444850Y267000D01*
X445142D01*
X445433Y267083D01*
X445683Y267208D01*
X445892Y267375D01*
G01X447033Y267500D02*
X447283Y267208D01*
X447617Y267042D01*
X447992Y267000D01*
X448325Y267042D01*
X448658Y267250D01*
X448867Y267500D01*
X448908Y267750D01*
X448825Y268042D01*
X448533Y268250D01*
X448242Y268333D01*
X447867D01*
G01X448242D02*
X448492Y268458D01*
X448700Y268667D01*
X448783Y268917D01*
X448700Y269167D01*
X448492Y269375D01*
X448117Y269500D01*
X447742Y269458D01*
X447367Y269292D01*
G01X450342Y267292D02*
X450633Y267083D01*
X450967Y267000D01*
X451300Y267083D01*
X451592Y267333D01*
X451800Y267708D01*
X451883Y268083D01*
Y268542D01*
X451800Y268917D01*
X451592Y269250D01*
X451342Y269417D01*
X451050Y269500D01*
X450717Y269417D01*
X450467Y269250D01*
X450300Y269000D01*
X450217Y268667D01*
X450300Y268375D01*
X450508Y268083D01*
X450758Y267917D01*
X451050Y267875D01*
X451383Y267958D01*
X451633Y268167D01*
X451883Y268542D01*
G01X454150Y267000D02*
Y269500D01*
X453650Y269000D01*
G01Y267000D02*
X454650D01*
G01X435675Y381654D02*
Y384154D01*
X437259D01*
G01X436675Y382946D02*
X435675D01*
G01X438734Y384154D02*
Y381654D01*
X440400D01*
G01X443500D02*
X441834D01*
Y384154D01*
X443500D01*
G01X442834Y382946D02*
X441834D01*
G01X444850Y381654D02*
Y384154D01*
X445684D01*
X446017Y384029D01*
X446267Y383862D01*
X446475Y383612D01*
X446642Y383321D01*
X446684Y382904D01*
X446642Y382487D01*
X446475Y382196D01*
X446267Y381946D01*
X446017Y381779D01*
X445684Y381654D01*
X444850D01*
G01X448867D02*
Y384154D01*
X448367Y383654D01*
G01Y381654D02*
X449367D01*
G01X451175Y382696D02*
X451467Y382987D01*
X451717Y383154D01*
X452050Y383237D01*
X452342Y383154D01*
X452550Y382987D01*
X452717Y382737D01*
X452759Y382446D01*
X452717Y382196D01*
X452550Y381946D01*
X452300Y381737D01*
X452009Y381654D01*
X451675Y381737D01*
X451384Y381987D01*
X451217Y382362D01*
X451175Y382779D01*
X451259Y383321D01*
X451384Y383612D01*
X451592Y383904D01*
X451884Y384112D01*
X452175Y384154D01*
X452467Y384071D01*
X452675Y383862D01*
G01X438317Y366054D02*
Y377254D01*
X447117D01*
Y366054D01*
X438317D01*
G01X422803Y496105D02*
Y510105D01*
G01X425888Y482068D02*
X425555Y482110D01*
X425263Y482276D01*
X425013Y482526D01*
X424846Y482818D01*
X424763Y483151D01*
Y483485D01*
X424846Y483818D01*
X425013Y484110D01*
X425263Y484360D01*
X425555Y484526D01*
X425888Y484568D01*
X426221Y484526D01*
X426513Y484360D01*
X426763Y484110D01*
X426930Y483818D01*
X427013Y483485D01*
Y483151D01*
X426930Y482818D01*
X426763Y482526D01*
X426513Y482276D01*
X426221Y482110D01*
X425888Y482068D01*
G01X426221Y482735D02*
X426721Y482068D01*
G01X428196Y484151D02*
X428446Y484401D01*
X428738Y484526D01*
X429071Y484568D01*
X429488Y484485D01*
X429780Y484276D01*
X429863Y484026D01*
X429821Y483776D01*
X429655Y483568D01*
X428821Y483151D01*
X428446Y482860D01*
X428196Y482443D01*
X428113Y482068D01*
X429863D01*
G01X432588D02*
Y484568D01*
X431046Y482776D01*
X433130D01*
G01X434396Y484151D02*
X434646Y484401D01*
X434938Y484526D01*
X435271Y484568D01*
X435688Y484485D01*
X435980Y484276D01*
X436063Y484026D01*
X436021Y483776D01*
X435855Y483568D01*
X435021Y483151D01*
X434646Y482860D01*
X434396Y482443D01*
X434313Y482068D01*
X436063D01*
G01X437038Y496068D02*
Y510068D01*
G01X424038Y496068D02*
X437038D01*
G01X424038Y510068D02*
Y496068D01*
G01X426676Y523341D02*
Y525841D01*
X427717D01*
X428051Y525716D01*
X428259Y525549D01*
X428342Y525216D01*
X428259Y524883D01*
X428009Y524674D01*
X427717Y524549D01*
X426676D01*
G01X427717D02*
X428342Y523341D01*
G01X429692Y523716D02*
X429942Y523508D01*
X430234Y523383D01*
X430609Y523341D01*
X430984Y523424D01*
X431276Y523591D01*
X431484Y523883D01*
X431526Y524216D01*
X431442Y524549D01*
X431234Y524758D01*
X430942Y524924D01*
X430651Y524966D01*
X430359Y524924D01*
X429984Y524758D01*
X430109Y525841D01*
X431234D01*
G01X433709Y523341D02*
Y525841D01*
X433209Y525341D01*
G01Y523341D02*
X434209D01*
G01X436726D02*
X436809Y523883D01*
X436934Y524341D01*
X437101Y524758D01*
X437309Y525216D01*
X437642Y525841D01*
X435976D01*
G01X436359Y510841D02*
Y514841D01*
X428959D01*
G01X412449Y523337D02*
Y525837D01*
X413490D01*
X413824Y525712D01*
X414032Y525545D01*
X414115Y525212D01*
X414032Y524879D01*
X413782Y524670D01*
X413490Y524545D01*
X412449D01*
G01X413490D02*
X414115Y523337D01*
G01X415465Y523712D02*
X415715Y523504D01*
X416007Y523379D01*
X416382Y523337D01*
X416757Y523420D01*
X417049Y523587D01*
X417257Y523879D01*
X417299Y524212D01*
X417215Y524545D01*
X417007Y524754D01*
X416715Y524920D01*
X416424Y524962D01*
X416132Y524920D01*
X415757Y524754D01*
X415882Y525837D01*
X417007D01*
G01X419482Y523337D02*
Y525837D01*
X418982Y525337D01*
G01Y523337D02*
X419982D01*
G01X421790Y524379D02*
X422082Y524670D01*
X422332Y524837D01*
X422665Y524920D01*
X422957Y524837D01*
X423165Y524670D01*
X423332Y524420D01*
X423374Y524129D01*
X423332Y523879D01*
X423165Y523629D01*
X422915Y523420D01*
X422624Y523337D01*
X422290Y523420D01*
X421999Y523670D01*
X421832Y524045D01*
X421790Y524462D01*
X421874Y525004D01*
X421999Y525295D01*
X422207Y525587D01*
X422499Y525795D01*
X422790Y525837D01*
X423082Y525754D01*
X423290Y525545D01*
G01X422132Y510837D02*
Y514837D01*
X414732D01*
G01X437038Y510068D02*
X424038D01*
G01X446065Y511806D02*
X443565D01*
Y512847D01*
X443690Y513181D01*
X443857Y513389D01*
X444190Y513472D01*
X444523Y513389D01*
X444732Y513139D01*
X444857Y512847D01*
Y511806D01*
G01Y512847D02*
X446065Y513472D01*
G01X443982Y514947D02*
X443732Y515197D01*
X443607Y515489D01*
X443565Y515822D01*
X443648Y516239D01*
X443857Y516531D01*
X444107Y516614D01*
X444357Y516572D01*
X444565Y516406D01*
X444982Y515572D01*
X445273Y515197D01*
X445690Y514947D01*
X446065Y514864D01*
Y516614D01*
G01X445773Y518131D02*
X445982Y518422D01*
X446065Y518756D01*
X445982Y519089D01*
X445732Y519381D01*
X445357Y519589D01*
X444982Y519672D01*
X444523D01*
X444148Y519589D01*
X443815Y519381D01*
X443648Y519131D01*
X443565Y518839D01*
X443648Y518506D01*
X443815Y518256D01*
X444065Y518089D01*
X444398Y518006D01*
X444690Y518089D01*
X444982Y518297D01*
X445148Y518547D01*
X445190Y518839D01*
X445107Y519172D01*
X444898Y519422D01*
X444523Y519672D01*
G01X445023Y521147D02*
X444732Y521439D01*
X444565Y521689D01*
X444482Y522022D01*
X444565Y522314D01*
X444732Y522522D01*
X444982Y522689D01*
X445273Y522731D01*
X445523Y522689D01*
X445773Y522522D01*
X445982Y522272D01*
X446065Y521981D01*
X445982Y521647D01*
X445732Y521356D01*
X445357Y521189D01*
X444940Y521147D01*
X444398Y521231D01*
X444107Y521356D01*
X443815Y521564D01*
X443607Y521856D01*
X443565Y522147D01*
X443648Y522439D01*
X443857Y522647D01*
G01X441065Y511806D02*
X438565D01*
Y512847D01*
X438690Y513181D01*
X438857Y513389D01*
X439190Y513472D01*
X439523Y513389D01*
X439732Y513139D01*
X439857Y512847D01*
Y511806D01*
G01Y512847D02*
X441065Y513472D01*
G01X438982Y514947D02*
X438732Y515197D01*
X438607Y515489D01*
X438565Y515822D01*
X438648Y516239D01*
X438857Y516531D01*
X439107Y516614D01*
X439357Y516572D01*
X439565Y516406D01*
X439982Y515572D01*
X440273Y515197D01*
X440690Y514947D01*
X441065Y514864D01*
Y516614D01*
G01X440773Y518131D02*
X440982Y518422D01*
X441065Y518756D01*
X440982Y519089D01*
X440732Y519381D01*
X440357Y519589D01*
X439982Y519672D01*
X439523D01*
X439148Y519589D01*
X438815Y519381D01*
X438648Y519131D01*
X438565Y518839D01*
X438648Y518506D01*
X438815Y518256D01*
X439065Y518089D01*
X439398Y518006D01*
X439690Y518089D01*
X439982Y518297D01*
X440148Y518547D01*
X440190Y518839D01*
X440107Y519172D01*
X439898Y519422D01*
X439523Y519672D01*
G01X440565Y521022D02*
X440857Y521272D01*
X441023Y521606D01*
X441065Y521981D01*
X441023Y522314D01*
X440815Y522647D01*
X440565Y522856D01*
X440315Y522897D01*
X440023Y522814D01*
X439815Y522522D01*
X439732Y522231D01*
Y521856D01*
G01Y522231D02*
X439607Y522481D01*
X439398Y522689D01*
X439148Y522772D01*
X438898Y522689D01*
X438690Y522481D01*
X438565Y522106D01*
X438607Y521731D01*
X438773Y521356D01*
G01X455191Y614917D02*
Y617417D01*
X456232D01*
X456566Y617292D01*
X456774Y617125D01*
X456857Y616792D01*
X456774Y616459D01*
X456524Y616250D01*
X456232Y616125D01*
X455191D01*
G01X456232D02*
X456857Y614917D01*
G01X459624D02*
Y617417D01*
X458082Y615625D01*
X460166D01*
G01X462224Y614917D02*
X462516Y614959D01*
X462849Y615084D01*
X463057Y615292D01*
X463141Y615584D01*
X463057Y615875D01*
X462807Y616125D01*
X462432Y616250D01*
X462016D01*
X461766Y616334D01*
X461557Y616542D01*
X461474Y616834D01*
X461599Y617125D01*
X461891Y617334D01*
X462224Y617417D01*
X462557Y617334D01*
X462849Y617125D01*
X462974Y616834D01*
X462891Y616542D01*
X462682Y616334D01*
X462432Y616250D01*
X462016D01*
X461641Y616125D01*
X461391Y615875D01*
X461307Y615584D01*
X461391Y615292D01*
X461599Y615084D01*
X461932Y614959D01*
X462224Y614917D01*
G01X464407Y615417D02*
X464657Y615125D01*
X464991Y614959D01*
X465366Y614917D01*
X465699Y614959D01*
X466032Y615167D01*
X466241Y615417D01*
X466282Y615667D01*
X466199Y615959D01*
X465907Y616167D01*
X465616Y616250D01*
X465241D01*
G01X465616D02*
X465866Y616375D01*
X466074Y616584D01*
X466157Y616834D01*
X466074Y617084D01*
X465866Y617292D01*
X465491Y617417D01*
X465116Y617375D01*
X464741Y617209D01*
G01X455017Y611000D02*
Y613500D01*
X456058D01*
X456392Y613375D01*
X456600Y613208D01*
X456683Y612875D01*
X456600Y612542D01*
X456350Y612333D01*
X456058Y612208D01*
X455017D01*
G01X456058D02*
X456683Y611000D01*
G01X459450D02*
Y613500D01*
X457908Y611708D01*
X459992D01*
G01X462050Y611000D02*
X462342Y611042D01*
X462675Y611167D01*
X462883Y611375D01*
X462967Y611667D01*
X462883Y611958D01*
X462633Y612208D01*
X462258Y612333D01*
X461842D01*
X461592Y612417D01*
X461383Y612625D01*
X461300Y612917D01*
X461425Y613208D01*
X461717Y613417D01*
X462050Y613500D01*
X462383Y613417D01*
X462675Y613208D01*
X462800Y612917D01*
X462717Y612625D01*
X462508Y612417D01*
X462258Y612333D01*
X461842D01*
X461467Y612208D01*
X461217Y611958D01*
X461133Y611667D01*
X461217Y611375D01*
X461425Y611167D01*
X461758Y611042D01*
X462050Y611000D01*
G01X464233Y611375D02*
X464483Y611167D01*
X464775Y611042D01*
X465150Y611000D01*
X465525Y611083D01*
X465817Y611250D01*
X466025Y611542D01*
X466067Y611875D01*
X465983Y612208D01*
X465775Y612417D01*
X465483Y612583D01*
X465192Y612625D01*
X464900Y612583D01*
X464525Y612417D01*
X464650Y613500D01*
X465775D01*
G01X455903Y631682D02*
Y627682D01*
X463303D01*
G01X455117Y618500D02*
Y621000D01*
X456158D01*
X456492Y620875D01*
X456700Y620708D01*
X456783Y620375D01*
X456700Y620042D01*
X456450Y619833D01*
X456158Y619708D01*
X455117D01*
G01X456158D02*
X456783Y618500D01*
G01X459550D02*
Y621000D01*
X458008Y619208D01*
X460092D01*
G01X462150Y618500D02*
X462442Y618542D01*
X462775Y618667D01*
X462983Y618875D01*
X463067Y619167D01*
X462983Y619458D01*
X462733Y619708D01*
X462358Y619833D01*
X461942D01*
X461692Y619917D01*
X461483Y620125D01*
X461400Y620417D01*
X461525Y620708D01*
X461817Y620917D01*
X462150Y621000D01*
X462483Y620917D01*
X462775Y620708D01*
X462900Y620417D01*
X462817Y620125D01*
X462608Y619917D01*
X462358Y619833D01*
X461942D01*
X461567Y619708D01*
X461317Y619458D01*
X461233Y619167D01*
X461317Y618875D01*
X461525Y618667D01*
X461858Y618542D01*
X462150Y618500D01*
G01X465167D02*
X465250Y619042D01*
X465375Y619500D01*
X465542Y619917D01*
X465750Y620375D01*
X466083Y621000D01*
X464417D01*
G01X422917Y626400D02*
Y628900D01*
X423958D01*
X424292Y628775D01*
X424500Y628608D01*
X424583Y628275D01*
X424500Y627942D01*
X424250Y627733D01*
X423958Y627608D01*
X422917D01*
G01X423958D02*
X424583Y626400D01*
G01X427350D02*
Y628900D01*
X425808Y627108D01*
X427892D01*
G01X429950Y626400D02*
X430242Y626442D01*
X430575Y626567D01*
X430783Y626775D01*
X430867Y627067D01*
X430783Y627358D01*
X430533Y627608D01*
X430158Y627733D01*
X429742D01*
X429492Y627817D01*
X429283Y628025D01*
X429200Y628317D01*
X429325Y628608D01*
X429617Y628817D01*
X429950Y628900D01*
X430283Y628817D01*
X430575Y628608D01*
X430700Y628317D01*
X430617Y628025D01*
X430408Y627817D01*
X430158Y627733D01*
X429742D01*
X429367Y627608D01*
X429117Y627358D01*
X429033Y627067D01*
X429117Y626775D01*
X429325Y626567D01*
X429658Y626442D01*
X429950Y626400D01*
G01X432342Y626692D02*
X432633Y626483D01*
X432967Y626400D01*
X433300Y626483D01*
X433592Y626733D01*
X433800Y627108D01*
X433883Y627483D01*
Y627942D01*
X433800Y628317D01*
X433592Y628650D01*
X433342Y628817D01*
X433050Y628900D01*
X432717Y628817D01*
X432467Y628650D01*
X432300Y628400D01*
X432217Y628067D01*
X432300Y627775D01*
X432508Y627483D01*
X432758Y627317D01*
X433050Y627275D01*
X433383Y627358D01*
X433633Y627567D01*
X433883Y627942D01*
G01X427274Y634317D02*
Y630317D01*
X434674D01*
G01X429000Y636017D02*
X426500D01*
Y637058D01*
X426625Y637392D01*
X426792Y637600D01*
X427125Y637683D01*
X427458Y637600D01*
X427667Y637350D01*
X427792Y637058D01*
Y636017D01*
G01Y637058D02*
X429000Y637683D01*
G01Y640450D02*
X426500D01*
X428292Y638908D01*
Y640992D01*
G01X428708Y642342D02*
X428917Y642633D01*
X429000Y642967D01*
X428917Y643300D01*
X428667Y643592D01*
X428292Y643800D01*
X427917Y643883D01*
X427458D01*
X427083Y643800D01*
X426750Y643592D01*
X426583Y643342D01*
X426500Y643050D01*
X426583Y642717D01*
X426750Y642467D01*
X427000Y642300D01*
X427333Y642217D01*
X427625Y642300D01*
X427917Y642508D01*
X428083Y642758D01*
X428125Y643050D01*
X428042Y643383D01*
X427833Y643633D01*
X427458Y643883D01*
G01X429000Y646150D02*
X426500D01*
X427000Y645650D01*
G01X429000D02*
Y646650D01*
G01X430574Y634717D02*
X434574D01*
Y642117D01*
G01X444400Y616017D02*
X441900D01*
Y617058D01*
X442025Y617392D01*
X442192Y617600D01*
X442525Y617683D01*
X442858Y617600D01*
X443067Y617350D01*
X443192Y617058D01*
Y616017D01*
G01Y617058D02*
X444400Y617683D01*
G01Y620450D02*
X441900D01*
X443692Y618908D01*
Y620992D01*
G01X444108Y622342D02*
X444317Y622633D01*
X444400Y622967D01*
X444317Y623300D01*
X444067Y623592D01*
X443692Y623800D01*
X443317Y623883D01*
X442858D01*
X442483Y623800D01*
X442150Y623592D01*
X441983Y623342D01*
X441900Y623050D01*
X441983Y622717D01*
X442150Y622467D01*
X442400Y622300D01*
X442733Y622217D01*
X443025Y622300D01*
X443317Y622508D01*
X443483Y622758D01*
X443525Y623050D01*
X443442Y623383D01*
X443233Y623633D01*
X442858Y623883D01*
G01X442317Y625358D02*
X442067Y625608D01*
X441942Y625900D01*
X441900Y626233D01*
X441983Y626650D01*
X442192Y626942D01*
X442442Y627025D01*
X442692Y626983D01*
X442900Y626817D01*
X443317Y625983D01*
X443608Y625608D01*
X444025Y625358D01*
X444400Y625275D01*
Y627025D01*
G01X447474Y636117D02*
X443474D01*
Y628717D01*
G01X446900Y625000D02*
X446567Y625042D01*
X446275Y625208D01*
X446025Y625458D01*
X445858Y625750D01*
X445775Y626083D01*
Y626417D01*
X445858Y626750D01*
X446025Y627042D01*
X446275Y627292D01*
X446567Y627458D01*
X446900Y627500D01*
X447233Y627458D01*
X447525Y627292D01*
X447775Y627042D01*
X447942Y626750D01*
X448025Y626417D01*
Y626083D01*
X447942Y625750D01*
X447775Y625458D01*
X447525Y625208D01*
X447233Y625042D01*
X446900Y625000D01*
G01X447233Y625667D02*
X447733Y625000D01*
G01X449292Y625292D02*
X449583Y625083D01*
X449917Y625000D01*
X450250Y625083D01*
X450542Y625333D01*
X450750Y625708D01*
X450833Y626083D01*
Y626542D01*
X450750Y626917D01*
X450542Y627250D01*
X450292Y627417D01*
X450000Y627500D01*
X449667Y627417D01*
X449417Y627250D01*
X449250Y627000D01*
X449167Y626667D01*
X449250Y626375D01*
X449458Y626083D01*
X449708Y625917D01*
X450000Y625875D01*
X450333Y625958D01*
X450583Y626167D01*
X450833Y626542D01*
G01X453100Y625000D02*
Y627500D01*
X452600Y627000D01*
G01Y625000D02*
X453600D01*
G01X458774Y637217D02*
Y650617D01*
G01X447374Y637217D02*
X458774D01*
G01X447374Y650617D02*
Y637217D01*
G01X439500Y618983D02*
X437000D01*
Y619817D01*
X437125Y620150D01*
X437292Y620400D01*
X437542Y620608D01*
X437833Y620775D01*
X438250Y620817D01*
X438667Y620775D01*
X438958Y620608D01*
X439208Y620400D01*
X439375Y620150D01*
X439500Y619817D01*
Y618983D01*
G01Y623000D02*
X437000D01*
X437500Y622500D01*
G01X439500D02*
Y623500D01*
G01X439125Y625183D02*
X439333Y625433D01*
X439458Y625725D01*
X439500Y626100D01*
X439417Y626475D01*
X439250Y626767D01*
X438958Y626975D01*
X438625Y627017D01*
X438292Y626933D01*
X438083Y626725D01*
X437917Y626433D01*
X437875Y626142D01*
X437917Y625850D01*
X438083Y625475D01*
X437000Y625600D01*
Y626725D01*
G01X442574Y644917D02*
Y628817D01*
G01X435574Y644917D02*
X442574D01*
G01X435574Y628817D02*
Y644917D01*
G01X442574Y628817D02*
X435574D01*
G01X422491Y653317D02*
Y655817D01*
X423532D01*
X423866Y655692D01*
X424074Y655525D01*
X424157Y655192D01*
X424074Y654859D01*
X423824Y654650D01*
X423532Y654525D01*
X422491D01*
G01X423532D02*
X424157Y653317D01*
G01X426924D02*
Y655817D01*
X425382Y654025D01*
X427466D01*
G01X429524Y653317D02*
X429816Y653359D01*
X430149Y653484D01*
X430357Y653692D01*
X430441Y653984D01*
X430357Y654275D01*
X430107Y654525D01*
X429732Y654650D01*
X429316D01*
X429066Y654734D01*
X428857Y654942D01*
X428774Y655234D01*
X428899Y655525D01*
X429191Y655734D01*
X429524Y655817D01*
X429857Y655734D01*
X430149Y655525D01*
X430274Y655234D01*
X430191Y654942D01*
X429982Y654734D01*
X429732Y654650D01*
X429316D01*
X428941Y654525D01*
X428691Y654275D01*
X428607Y653984D01*
X428691Y653692D01*
X428899Y653484D01*
X429232Y653359D01*
X429524Y653317D01*
G01X431832Y655400D02*
X432082Y655650D01*
X432374Y655775D01*
X432707Y655817D01*
X433124Y655734D01*
X433416Y655525D01*
X433499Y655275D01*
X433457Y655025D01*
X433291Y654817D01*
X432457Y654400D01*
X432082Y654109D01*
X431832Y653692D01*
X431749Y653317D01*
X433499D01*
G01X435274Y659817D02*
Y655817D01*
X442674D01*
G01X415591Y661817D02*
Y664317D01*
X416632D01*
X416966Y664192D01*
X417174Y664025D01*
X417257Y663692D01*
X417174Y663359D01*
X416924Y663150D01*
X416632Y663025D01*
X415591D01*
G01X416632D02*
X417257Y661817D01*
G01X420024D02*
Y664317D01*
X418482Y662525D01*
X420566D01*
G01X421916Y662109D02*
X422207Y661900D01*
X422541Y661817D01*
X422874Y661900D01*
X423166Y662150D01*
X423374Y662525D01*
X423457Y662900D01*
Y663359D01*
X423374Y663734D01*
X423166Y664067D01*
X422916Y664234D01*
X422624Y664317D01*
X422291Y664234D01*
X422041Y664067D01*
X421874Y663817D01*
X421791Y663484D01*
X421874Y663192D01*
X422082Y662900D01*
X422332Y662734D01*
X422624Y662692D01*
X422957Y662775D01*
X423207Y662984D01*
X423457Y663359D01*
G01X425724Y664317D02*
X425391Y664234D01*
X425141Y664025D01*
X424974Y663775D01*
X424849Y663442D01*
X424807Y663067D01*
X424849Y662692D01*
X424974Y662359D01*
X425141Y662109D01*
X425391Y661900D01*
X425724Y661817D01*
X426057Y661900D01*
X426307Y662109D01*
X426474Y662359D01*
X426599Y662692D01*
X426641Y663067D01*
X426599Y663442D01*
X426474Y663775D01*
X426307Y664025D01*
X426057Y664234D01*
X425724Y664317D01*
G01X434774Y661317D02*
Y665317D01*
X427374D01*
G01X458774Y650617D02*
X447374D01*
G01X460374Y688917D02*
X454874D01*
G01X442774D02*
Y696917D01*
G01X448274Y688917D02*
X442774D01*
G01X418500Y678400D02*
X418458Y678067D01*
X418292Y677775D01*
X418042Y677525D01*
X417750Y677358D01*
X417417Y677275D01*
X417083D01*
X416750Y677358D01*
X416458Y677525D01*
X416208Y677775D01*
X416042Y678067D01*
X416000Y678400D01*
X416042Y678733D01*
X416208Y679025D01*
X416458Y679275D01*
X416750Y679442D01*
X417083Y679525D01*
X417417D01*
X417750Y679442D01*
X418042Y679275D01*
X418292Y679025D01*
X418458Y678733D01*
X418500Y678400D01*
G01X417833Y678733D02*
X418500Y679233D01*
G01X418208Y680792D02*
X418417Y681083D01*
X418500Y681417D01*
X418417Y681750D01*
X418167Y682042D01*
X417792Y682250D01*
X417417Y682333D01*
X416958D01*
X416583Y682250D01*
X416250Y682042D01*
X416083Y681792D01*
X416000Y681500D01*
X416083Y681167D01*
X416250Y680917D01*
X416500Y680750D01*
X416833Y680667D01*
X417125Y680750D01*
X417417Y680958D01*
X417583Y681208D01*
X417625Y681500D01*
X417542Y681833D01*
X417333Y682083D01*
X416958Y682333D01*
G01X416417Y683808D02*
X416167Y684058D01*
X416042Y684350D01*
X416000Y684683D01*
X416083Y685100D01*
X416292Y685392D01*
X416542Y685475D01*
X416792Y685433D01*
X417000Y685267D01*
X417417Y684433D01*
X417708Y684058D01*
X418125Y683808D01*
X418500Y683725D01*
Y685475D01*
G01X420374Y690417D02*
X422474Y688617D01*
X420374Y686417D01*
G01X420274Y682817D02*
X439474D01*
Y694017D01*
X420274D01*
Y682817D01*
X420674D01*
G01X464874Y676017D02*
X445674D01*
Y664817D01*
X464874D01*
Y676017D01*
X464474D01*
G01X417341Y668209D02*
X417091Y668334D01*
X416799Y668417D01*
X416466D01*
X416091Y668292D01*
X415799Y668084D01*
X415591Y667834D01*
X415424Y667417D01*
X415382Y667042D01*
X415466Y666667D01*
X415591Y666417D01*
X415841Y666167D01*
X416132Y666000D01*
X416424Y665917D01*
X416716D01*
X417007Y666000D01*
X417257Y666125D01*
X417466Y666292D01*
G01X418732Y668000D02*
X418982Y668250D01*
X419274Y668375D01*
X419607Y668417D01*
X420024Y668334D01*
X420316Y668125D01*
X420399Y667875D01*
X420357Y667625D01*
X420191Y667417D01*
X419357Y667000D01*
X418982Y666709D01*
X418732Y666292D01*
X418649Y665917D01*
X420399D01*
G01X423124D02*
Y668417D01*
X421582Y666625D01*
X423666D01*
G01X426224Y665917D02*
Y668417D01*
X424682Y666625D01*
X426766D01*
G01X424241Y659709D02*
X423991Y659834D01*
X423699Y659917D01*
X423366D01*
X422991Y659792D01*
X422699Y659584D01*
X422491Y659334D01*
X422324Y658917D01*
X422282Y658542D01*
X422366Y658167D01*
X422491Y657917D01*
X422741Y657667D01*
X423032Y657500D01*
X423324Y657417D01*
X423616D01*
X423907Y657500D01*
X424157Y657625D01*
X424366Y657792D01*
G01X425632Y659500D02*
X425882Y659750D01*
X426174Y659875D01*
X426507Y659917D01*
X426924Y659834D01*
X427216Y659625D01*
X427299Y659375D01*
X427257Y659125D01*
X427091Y658917D01*
X426257Y658500D01*
X425882Y658209D01*
X425632Y657792D01*
X425549Y657417D01*
X427299D01*
G01X430024D02*
Y659917D01*
X428482Y658125D01*
X430566D01*
G01X431707Y657917D02*
X431957Y657625D01*
X432291Y657459D01*
X432666Y657417D01*
X432999Y657459D01*
X433332Y657667D01*
X433541Y657917D01*
X433582Y658167D01*
X433499Y658459D01*
X433207Y658667D01*
X432916Y658750D01*
X432541D01*
G01X432916D02*
X433166Y658875D01*
X433374Y659084D01*
X433457Y659334D01*
X433374Y659584D01*
X433166Y659792D01*
X432791Y659917D01*
X432416Y659875D01*
X432041Y659709D01*
G01X444017Y724000D02*
Y726500D01*
X445058D01*
X445392Y726375D01*
X445600Y726208D01*
X445683Y725875D01*
X445600Y725542D01*
X445350Y725333D01*
X445058Y725208D01*
X444017D01*
G01X445058D02*
X445683Y724000D01*
G01X448450D02*
Y726500D01*
X446908Y724708D01*
X448992D01*
G01X450967Y724000D02*
X451050Y724542D01*
X451175Y725000D01*
X451342Y725417D01*
X451550Y725875D01*
X451883Y726500D01*
X450217D01*
G01X453358Y725042D02*
X453650Y725333D01*
X453900Y725500D01*
X454233Y725583D01*
X454525Y725500D01*
X454733Y725333D01*
X454900Y725083D01*
X454942Y724792D01*
X454900Y724542D01*
X454733Y724292D01*
X454483Y724083D01*
X454192Y724000D01*
X453858Y724083D01*
X453567Y724333D01*
X453400Y724708D01*
X453358Y725125D01*
X453442Y725667D01*
X453567Y725958D01*
X453775Y726250D01*
X454067Y726458D01*
X454358Y726500D01*
X454650Y726417D01*
X454858Y726208D01*
G01X438274Y703417D02*
Y711417D01*
X455874D01*
Y703417D01*
X438274D01*
G01X427267Y714792D02*
X427017Y714917D01*
X426725Y715000D01*
X426392D01*
X426017Y714875D01*
X425725Y714667D01*
X425517Y714417D01*
X425350Y714000D01*
X425308Y713625D01*
X425392Y713250D01*
X425517Y713000D01*
X425767Y712750D01*
X426058Y712583D01*
X426350Y712500D01*
X426642D01*
X426933Y712583D01*
X427183Y712708D01*
X427392Y712875D01*
G01X428658Y714583D02*
X428908Y714833D01*
X429200Y714958D01*
X429533Y715000D01*
X429950Y714917D01*
X430242Y714708D01*
X430325Y714458D01*
X430283Y714208D01*
X430117Y714000D01*
X429283Y713583D01*
X428908Y713292D01*
X428658Y712875D01*
X428575Y712500D01*
X430325D01*
G01X433050D02*
Y715000D01*
X431508Y713208D01*
X433592D01*
G01X435650Y715000D02*
X435317Y714917D01*
X435067Y714708D01*
X434900Y714458D01*
X434775Y714125D01*
X434733Y713750D01*
X434775Y713375D01*
X434900Y713042D01*
X435067Y712792D01*
X435317Y712583D01*
X435650Y712500D01*
X435983Y712583D01*
X436233Y712792D01*
X436400Y713042D01*
X436525Y713375D01*
X436567Y713750D01*
X436525Y714125D01*
X436400Y714458D01*
X436233Y714708D01*
X435983Y714917D01*
X435650Y715000D01*
G01X445841Y718209D02*
X445591Y718334D01*
X445299Y718417D01*
X444966D01*
X444591Y718292D01*
X444299Y718084D01*
X444091Y717834D01*
X443924Y717417D01*
X443882Y717042D01*
X443966Y716667D01*
X444091Y716417D01*
X444341Y716167D01*
X444632Y716000D01*
X444924Y715917D01*
X445216D01*
X445507Y716000D01*
X445757Y716125D01*
X445966Y716292D01*
G01X447232Y718000D02*
X447482Y718250D01*
X447774Y718375D01*
X448107Y718417D01*
X448524Y718334D01*
X448816Y718125D01*
X448899Y717875D01*
X448857Y717625D01*
X448691Y717417D01*
X447857Y717000D01*
X447482Y716709D01*
X447232Y716292D01*
X447149Y715917D01*
X448899D01*
G01X450207Y716417D02*
X450457Y716125D01*
X450791Y715959D01*
X451166Y715917D01*
X451499Y715959D01*
X451832Y716167D01*
X452041Y716417D01*
X452082Y716667D01*
X451999Y716959D01*
X451707Y717167D01*
X451416Y717250D01*
X451041D01*
G01X451416D02*
X451666Y717375D01*
X451874Y717584D01*
X451957Y717834D01*
X451874Y718084D01*
X451666Y718292D01*
X451291Y718417D01*
X450916Y718375D01*
X450541Y718209D01*
G01X453432Y716959D02*
X453724Y717250D01*
X453974Y717417D01*
X454307Y717500D01*
X454599Y717417D01*
X454807Y717250D01*
X454974Y717000D01*
X455016Y716709D01*
X454974Y716459D01*
X454807Y716209D01*
X454557Y716000D01*
X454266Y715917D01*
X453932Y716000D01*
X453641Y716250D01*
X453474Y716625D01*
X453432Y717042D01*
X453516Y717584D01*
X453641Y717875D01*
X453849Y718167D01*
X454141Y718375D01*
X454432Y718417D01*
X454724Y718334D01*
X454932Y718125D01*
G01X454874Y696917D02*
X460374D01*
G01X442774D02*
X448274D01*
G01X445767Y722292D02*
X445517Y722417D01*
X445225Y722500D01*
X444892D01*
X444517Y722375D01*
X444225Y722167D01*
X444017Y721917D01*
X443850Y721500D01*
X443808Y721125D01*
X443892Y720750D01*
X444017Y720500D01*
X444267Y720250D01*
X444558Y720083D01*
X444850Y720000D01*
X445142D01*
X445433Y720083D01*
X445683Y720208D01*
X445892Y720375D01*
G01X447158Y722083D02*
X447408Y722333D01*
X447700Y722458D01*
X448033Y722500D01*
X448450Y722417D01*
X448742Y722208D01*
X448825Y721958D01*
X448783Y721708D01*
X448617Y721500D01*
X447783Y721083D01*
X447408Y720792D01*
X447158Y720375D01*
X447075Y720000D01*
X448825D01*
G01X450133Y720500D02*
X450383Y720208D01*
X450717Y720042D01*
X451092Y720000D01*
X451425Y720042D01*
X451758Y720250D01*
X451967Y720500D01*
X452008Y720750D01*
X451925Y721042D01*
X451633Y721250D01*
X451342Y721333D01*
X450967D01*
G01X451342D02*
X451592Y721458D01*
X451800Y721667D01*
X451883Y721917D01*
X451800Y722167D01*
X451592Y722375D01*
X451217Y722500D01*
X450842Y722458D01*
X450467Y722292D01*
G01X453233Y720375D02*
X453483Y720167D01*
X453775Y720042D01*
X454150Y720000D01*
X454525Y720083D01*
X454817Y720250D01*
X455025Y720542D01*
X455067Y720875D01*
X454983Y721208D01*
X454775Y721417D01*
X454483Y721583D01*
X454192Y721625D01*
X453900Y721583D01*
X453525Y721417D01*
X453650Y722500D01*
X454775D01*
G01X441725Y779030D02*
Y781530D01*
G01X443475D02*
Y779030D01*
G01Y780280D02*
X441725D01*
G01X444783Y779030D02*
Y781530D01*
X445617D01*
X445950Y781405D01*
X446200Y781238D01*
X446408Y780988D01*
X446575Y780697D01*
X446617Y780280D01*
X446575Y779863D01*
X446408Y779572D01*
X446200Y779322D01*
X445950Y779155D01*
X445617Y779030D01*
X444783D01*
G01X447883D02*
Y781530D01*
X448717D01*
X449050Y781405D01*
X449300Y781238D01*
X449508Y780988D01*
X449675Y780697D01*
X449717Y780280D01*
X449675Y779863D01*
X449508Y779572D01*
X449300Y779322D01*
X449050Y779155D01*
X448717Y779030D01*
X447883D01*
G01X451025Y779363D02*
X451358Y779155D01*
X451733Y779030D01*
X452067D01*
X452400Y779155D01*
X452650Y779363D01*
X452775Y779655D01*
X452692Y779947D01*
X452483Y780197D01*
X452108Y780363D01*
X451608Y780447D01*
X451317Y780613D01*
X451192Y780905D01*
X451275Y781197D01*
X451483Y781405D01*
X451775Y781530D01*
X452067D01*
X452358Y781447D01*
X452608Y781238D01*
G01X453958Y779030D02*
X455000Y781530D01*
X456042Y779030D01*
G01X455667Y779905D02*
X454333D01*
G01X457225Y779363D02*
X457558Y779155D01*
X457933Y779030D01*
X458267D01*
X458600Y779155D01*
X458850Y779363D01*
X458975Y779655D01*
X458892Y779947D01*
X458683Y780197D01*
X458308Y780363D01*
X457808Y780447D01*
X457517Y780613D01*
X457392Y780905D01*
X457475Y781197D01*
X457683Y781405D01*
X457975Y781530D01*
X458267D01*
X458558Y781447D01*
X458808Y781238D01*
G01X461200Y779030D02*
Y781530D01*
X460700Y781030D01*
G01Y779030D02*
X461700D01*
G01X463383Y779405D02*
X463633Y779197D01*
X463925Y779072D01*
X464300Y779030D01*
X464675Y779113D01*
X464967Y779280D01*
X465175Y779572D01*
X465217Y779905D01*
X465133Y780238D01*
X464925Y780447D01*
X464633Y780613D01*
X464342Y780655D01*
X464050Y780613D01*
X463675Y780447D01*
X463800Y781530D01*
X464925D01*
G01X444291Y800411D02*
X441791D01*
Y801995D01*
G01X442999Y801411D02*
Y800411D01*
G01X441791Y803470D02*
X444291D01*
Y805136D01*
G01Y808236D02*
Y806570D01*
X441791D01*
Y808236D01*
G01X442999Y807570D02*
Y806570D01*
G01X444291Y809586D02*
X441791D01*
Y810420D01*
X441916Y810753D01*
X442083Y811003D01*
X442333Y811211D01*
X442624Y811378D01*
X443041Y811420D01*
X443458Y811378D01*
X443749Y811211D01*
X443999Y811003D01*
X444166Y810753D01*
X444291Y810420D01*
Y809586D01*
G01Y814103D02*
X441791D01*
X443583Y812561D01*
Y814645D01*
G01X438317Y818809D02*
Y830009D01*
X447117D01*
Y818809D01*
X438317D01*
G01X451731Y948448D02*
X449231D01*
Y949489D01*
X449356Y949823D01*
X449523Y950031D01*
X449856Y950114D01*
X450189Y950031D01*
X450398Y949781D01*
X450523Y949489D01*
Y948448D01*
G01Y949489D02*
X451731Y950114D01*
G01X449648Y951589D02*
X449398Y951839D01*
X449273Y952131D01*
X449231Y952464D01*
X449314Y952881D01*
X449523Y953173D01*
X449773Y953256D01*
X450023Y953214D01*
X450231Y953048D01*
X450648Y952214D01*
X450939Y951839D01*
X451356Y951589D01*
X451731Y951506D01*
Y953256D01*
G01X449648Y954689D02*
X449398Y954939D01*
X449273Y955231D01*
X449231Y955564D01*
X449314Y955981D01*
X449523Y956273D01*
X449773Y956356D01*
X450023Y956314D01*
X450231Y956148D01*
X450648Y955314D01*
X450939Y954939D01*
X451356Y954689D01*
X451731Y954606D01*
Y956356D01*
G01X449231Y958581D02*
X449314Y958248D01*
X449523Y957998D01*
X449773Y957831D01*
X450106Y957706D01*
X450481Y957664D01*
X450856Y957706D01*
X451189Y957831D01*
X451439Y957998D01*
X451648Y958248D01*
X451731Y958581D01*
X451648Y958914D01*
X451439Y959164D01*
X451189Y959331D01*
X450856Y959456D01*
X450481Y959498D01*
X450106Y959456D01*
X449773Y959331D01*
X449523Y959164D01*
X449314Y958914D01*
X449231Y958581D01*
G01X435072Y948447D02*
X432572D01*
Y949488D01*
X432697Y949822D01*
X432864Y950030D01*
X433197Y950113D01*
X433530Y950030D01*
X433739Y949780D01*
X433864Y949488D01*
Y948447D01*
G01Y949488D02*
X435072Y950113D01*
G01X432989Y951588D02*
X432739Y951838D01*
X432614Y952130D01*
X432572Y952463D01*
X432655Y952880D01*
X432864Y953172D01*
X433114Y953255D01*
X433364Y953213D01*
X433572Y953047D01*
X433989Y952213D01*
X434280Y951838D01*
X434697Y951588D01*
X435072Y951505D01*
Y953255D01*
G01Y955480D02*
X432572D01*
X433072Y954980D01*
G01X435072D02*
Y955980D01*
G01X434780Y957872D02*
X434989Y958163D01*
X435072Y958497D01*
X434989Y958830D01*
X434739Y959122D01*
X434364Y959330D01*
X433989Y959413D01*
X433530D01*
X433155Y959330D01*
X432822Y959122D01*
X432655Y958872D01*
X432572Y958580D01*
X432655Y958247D01*
X432822Y957997D01*
X433072Y957830D01*
X433405Y957747D01*
X433697Y957830D01*
X433989Y958038D01*
X434155Y958288D01*
X434197Y958580D01*
X434114Y958913D01*
X433905Y959163D01*
X433530Y959413D01*
G01X439673Y1068743D02*
X437173D01*
Y1069784D01*
X437298Y1070118D01*
X437465Y1070326D01*
X437798Y1070409D01*
X438131Y1070326D01*
X438340Y1070076D01*
X438465Y1069784D01*
Y1068743D01*
G01Y1069784D02*
X439673Y1070409D01*
G01X437590Y1071884D02*
X437340Y1072134D01*
X437215Y1072426D01*
X437173Y1072759D01*
X437256Y1073176D01*
X437465Y1073468D01*
X437715Y1073551D01*
X437965Y1073509D01*
X438173Y1073343D01*
X438590Y1072509D01*
X438881Y1072134D01*
X439298Y1071884D01*
X439673Y1071801D01*
Y1073551D01*
G01X437173Y1075776D02*
X437256Y1075443D01*
X437465Y1075193D01*
X437715Y1075026D01*
X438048Y1074901D01*
X438423Y1074859D01*
X438798Y1074901D01*
X439131Y1075026D01*
X439381Y1075193D01*
X439590Y1075443D01*
X439673Y1075776D01*
X439590Y1076109D01*
X439381Y1076359D01*
X439131Y1076526D01*
X438798Y1076651D01*
X438423Y1076693D01*
X438048Y1076651D01*
X437715Y1076526D01*
X437465Y1076359D01*
X437256Y1076109D01*
X437173Y1075776D01*
G01X439673Y1078793D02*
X439131Y1078876D01*
X438673Y1079001D01*
X438256Y1079168D01*
X437798Y1079376D01*
X437173Y1079709D01*
Y1078043D01*
G01X445173Y1070026D02*
X449173D01*
Y1077426D01*
G01X434973Y1068743D02*
X432473D01*
Y1069784D01*
X432598Y1070118D01*
X432765Y1070326D01*
X433098Y1070409D01*
X433431Y1070326D01*
X433640Y1070076D01*
X433765Y1069784D01*
Y1068743D01*
G01Y1069784D02*
X434973Y1070409D01*
G01X432890Y1071884D02*
X432640Y1072134D01*
X432515Y1072426D01*
X432473Y1072759D01*
X432556Y1073176D01*
X432765Y1073468D01*
X433015Y1073551D01*
X433265Y1073509D01*
X433473Y1073343D01*
X433890Y1072509D01*
X434181Y1072134D01*
X434598Y1071884D01*
X434973Y1071801D01*
Y1073551D01*
G01Y1075776D02*
X432473D01*
X432973Y1075276D01*
G01X434973D02*
Y1076276D01*
G01Y1078876D02*
X432473D01*
X432973Y1078376D01*
G01X434973D02*
Y1079376D01*
G01X440473Y1070026D02*
X444473D01*
Y1077426D01*
G01X459173D02*
X455173D01*
Y1070026D01*
G01X450473Y1078126D02*
X463873D01*
G01X450473Y1089526D02*
Y1078126D01*
G01X429334Y1102517D02*
X426834D01*
Y1103558D01*
X426959Y1103892D01*
X427126Y1104100D01*
X427459Y1104183D01*
X427792Y1104100D01*
X428001Y1103850D01*
X428126Y1103558D01*
Y1102517D01*
G01Y1103558D02*
X429334Y1104183D01*
G01X427251Y1105658D02*
X427001Y1105908D01*
X426876Y1106200D01*
X426834Y1106533D01*
X426917Y1106950D01*
X427126Y1107242D01*
X427376Y1107325D01*
X427626Y1107283D01*
X427834Y1107117D01*
X428251Y1106283D01*
X428542Y1105908D01*
X428959Y1105658D01*
X429334Y1105575D01*
Y1107325D01*
G01Y1109550D02*
X426834D01*
X427334Y1109050D01*
G01X429334D02*
Y1110050D01*
G01X428834Y1111733D02*
X429126Y1111983D01*
X429292Y1112317D01*
X429334Y1112692D01*
X429292Y1113025D01*
X429084Y1113358D01*
X428834Y1113567D01*
X428584Y1113608D01*
X428292Y1113525D01*
X428084Y1113233D01*
X428001Y1112942D01*
Y1112567D01*
G01Y1112942D02*
X427876Y1113192D01*
X427667Y1113400D01*
X427417Y1113483D01*
X427167Y1113400D01*
X426959Y1113192D01*
X426834Y1112817D01*
X426876Y1112442D01*
X427042Y1112067D01*
G01X447573Y1109526D02*
X443573D01*
Y1102126D01*
G01X433691Y1114973D02*
Y1117473D01*
X434732D01*
X435066Y1117348D01*
X435274Y1117181D01*
X435357Y1116848D01*
X435274Y1116515D01*
X435024Y1116306D01*
X434732Y1116181D01*
X433691D01*
G01X434732D02*
X435357Y1114973D01*
G01X436832Y1117056D02*
X437082Y1117306D01*
X437374Y1117431D01*
X437707Y1117473D01*
X438124Y1117390D01*
X438416Y1117181D01*
X438499Y1116931D01*
X438457Y1116681D01*
X438291Y1116473D01*
X437457Y1116056D01*
X437082Y1115765D01*
X436832Y1115348D01*
X436749Y1114973D01*
X438499D01*
G01X440724D02*
Y1117473D01*
X440224Y1116973D01*
G01Y1114973D02*
X441224D01*
G01X444324D02*
Y1117473D01*
X442782Y1115681D01*
X444866D01*
G01X455374Y1110973D02*
Y1114973D01*
X447974D01*
G01X431190Y1103326D02*
Y1105826D01*
X432231D01*
X432565Y1105701D01*
X432773Y1105534D01*
X432856Y1105201D01*
X432773Y1104868D01*
X432523Y1104659D01*
X432231Y1104534D01*
X431190D01*
G01X432231D02*
X432856Y1103326D01*
G01X434331Y1105409D02*
X434581Y1105659D01*
X434873Y1105784D01*
X435206Y1105826D01*
X435623Y1105743D01*
X435915Y1105534D01*
X435998Y1105284D01*
X435956Y1105034D01*
X435790Y1104826D01*
X434956Y1104409D01*
X434581Y1104118D01*
X434331Y1103701D01*
X434248Y1103326D01*
X435998D01*
G01X438223D02*
Y1105826D01*
X437723Y1105326D01*
G01Y1103326D02*
X438723D01*
G01X440406Y1103701D02*
X440656Y1103493D01*
X440948Y1103368D01*
X441323Y1103326D01*
X441698Y1103409D01*
X441990Y1103576D01*
X442198Y1103868D01*
X442240Y1104201D01*
X442156Y1104534D01*
X441948Y1104743D01*
X441656Y1104909D01*
X441365Y1104951D01*
X441073Y1104909D01*
X440698Y1104743D01*
X440823Y1105826D01*
X441948D01*
G01X447973Y1106326D02*
Y1102326D01*
X455373D01*
G01X430017Y1092100D02*
Y1094600D01*
X431058D01*
X431392Y1094475D01*
X431600Y1094308D01*
X431683Y1093975D01*
X431600Y1093642D01*
X431350Y1093433D01*
X431058Y1093308D01*
X430017D01*
G01X431058D02*
X431683Y1092100D01*
G01X433158Y1094183D02*
X433408Y1094433D01*
X433700Y1094558D01*
X434033Y1094600D01*
X434450Y1094517D01*
X434742Y1094308D01*
X434825Y1094058D01*
X434783Y1093808D01*
X434617Y1093600D01*
X433783Y1093183D01*
X433408Y1092892D01*
X433158Y1092475D01*
X433075Y1092100D01*
X434825D01*
G01X437050D02*
Y1094600D01*
X436550Y1094100D01*
G01Y1092100D02*
X437550D01*
G01X439358Y1093142D02*
X439650Y1093433D01*
X439900Y1093600D01*
X440233Y1093683D01*
X440525Y1093600D01*
X440733Y1093433D01*
X440900Y1093183D01*
X440942Y1092892D01*
X440900Y1092642D01*
X440733Y1092392D01*
X440483Y1092183D01*
X440192Y1092100D01*
X439858Y1092183D01*
X439567Y1092433D01*
X439400Y1092808D01*
X439358Y1093225D01*
X439442Y1093767D01*
X439567Y1094058D01*
X439775Y1094350D01*
X440067Y1094558D01*
X440358Y1094600D01*
X440650Y1094517D01*
X440858Y1094308D01*
G01X449373Y1089326D02*
Y1093326D01*
X441973D01*
G01X463873Y1089526D02*
X450473D01*
G01X435533Y1097000D02*
Y1099500D01*
X436367D01*
X436700Y1099375D01*
X436950Y1099208D01*
X437158Y1098958D01*
X437325Y1098667D01*
X437367Y1098250D01*
X437325Y1097833D01*
X437158Y1097542D01*
X436950Y1097292D01*
X436700Y1097125D01*
X436367Y1097000D01*
X435533D01*
G01X438633Y1097500D02*
X438883Y1097208D01*
X439217Y1097042D01*
X439592Y1097000D01*
X439925Y1097042D01*
X440258Y1097250D01*
X440467Y1097500D01*
X440508Y1097750D01*
X440425Y1098042D01*
X440133Y1098250D01*
X439842Y1098333D01*
X439467D01*
G01X439842D02*
X440092Y1098458D01*
X440300Y1098667D01*
X440383Y1098917D01*
X440300Y1099167D01*
X440092Y1099375D01*
X439717Y1099500D01*
X439342Y1099458D01*
X438967Y1099292D01*
G01X458173Y1094226D02*
X442073D01*
G01X458173Y1101226D02*
Y1094226D01*
G01X442073Y1101226D02*
X458173D01*
G01X442073Y1094226D02*
Y1101226D01*
G01X436991Y1121365D02*
X436741Y1121490D01*
X436449Y1121573D01*
X436116D01*
X435741Y1121448D01*
X435449Y1121240D01*
X435241Y1120990D01*
X435074Y1120573D01*
X435032Y1120198D01*
X435116Y1119823D01*
X435241Y1119573D01*
X435491Y1119323D01*
X435782Y1119156D01*
X436074Y1119073D01*
X436366D01*
X436657Y1119156D01*
X436907Y1119281D01*
X437116Y1119448D01*
G01X439174Y1119073D02*
X439466Y1119115D01*
X439799Y1119240D01*
X440007Y1119448D01*
X440091Y1119740D01*
X440007Y1120031D01*
X439757Y1120281D01*
X439382Y1120406D01*
X438966D01*
X438716Y1120490D01*
X438507Y1120698D01*
X438424Y1120990D01*
X438549Y1121281D01*
X438841Y1121490D01*
X439174Y1121573D01*
X439507Y1121490D01*
X439799Y1121281D01*
X439924Y1120990D01*
X439841Y1120698D01*
X439632Y1120490D01*
X439382Y1120406D01*
X438966D01*
X438591Y1120281D01*
X438341Y1120031D01*
X438257Y1119740D01*
X438341Y1119448D01*
X438549Y1119240D01*
X438882Y1119115D01*
X439174Y1119073D01*
G01X442274D02*
X442566Y1119115D01*
X442899Y1119240D01*
X443107Y1119448D01*
X443191Y1119740D01*
X443107Y1120031D01*
X442857Y1120281D01*
X442482Y1120406D01*
X442066D01*
X441816Y1120490D01*
X441607Y1120698D01*
X441524Y1120990D01*
X441649Y1121281D01*
X441941Y1121490D01*
X442274Y1121573D01*
X442607Y1121490D01*
X442899Y1121281D01*
X443024Y1120990D01*
X442941Y1120698D01*
X442732Y1120490D01*
X442482Y1120406D01*
X442066D01*
X441691Y1120281D01*
X441441Y1120031D01*
X441357Y1119740D01*
X441441Y1119448D01*
X441649Y1119240D01*
X441982Y1119115D01*
X442274Y1119073D01*
G01X459217Y1165700D02*
Y1168200D01*
X460258D01*
X460592Y1168075D01*
X460800Y1167908D01*
X460883Y1167575D01*
X460800Y1167242D01*
X460550Y1167033D01*
X460258Y1166908D01*
X459217D01*
G01X460258D02*
X460883Y1165700D01*
G01X462358Y1167783D02*
X462608Y1168033D01*
X462900Y1168158D01*
X463233Y1168200D01*
X463650Y1168117D01*
X463942Y1167908D01*
X464025Y1167658D01*
X463983Y1167408D01*
X463817Y1167200D01*
X462983Y1166783D01*
X462608Y1166492D01*
X462358Y1166075D01*
X462275Y1165700D01*
X464025D01*
G01X466250Y1168200D02*
X465917Y1168117D01*
X465667Y1167908D01*
X465500Y1167658D01*
X465375Y1167325D01*
X465333Y1166950D01*
X465375Y1166575D01*
X465500Y1166242D01*
X465667Y1165992D01*
X465917Y1165783D01*
X466250Y1165700D01*
X466583Y1165783D01*
X466833Y1165992D01*
X467000Y1166242D01*
X467125Y1166575D01*
X467167Y1166950D01*
X467125Y1167325D01*
X467000Y1167658D01*
X466833Y1167908D01*
X466583Y1168117D01*
X466250Y1168200D01*
G01X468558Y1167783D02*
X468808Y1168033D01*
X469100Y1168158D01*
X469433Y1168200D01*
X469850Y1168117D01*
X470142Y1167908D01*
X470225Y1167658D01*
X470183Y1167408D01*
X470017Y1167200D01*
X469183Y1166783D01*
X468808Y1166492D01*
X468558Y1166075D01*
X468475Y1165700D01*
X470225D01*
G01X452900Y1156200D02*
Y1164200D01*
X470500D01*
Y1156200D01*
X452900D01*
G01X446355Y1168488D02*
X446105Y1168613D01*
X445813Y1168696D01*
X445480D01*
X445105Y1168571D01*
X444813Y1168363D01*
X444605Y1168113D01*
X444438Y1167696D01*
X444396Y1167321D01*
X444480Y1166946D01*
X444605Y1166696D01*
X444855Y1166446D01*
X445146Y1166279D01*
X445438Y1166196D01*
X445730D01*
X446021Y1166279D01*
X446271Y1166404D01*
X446480Y1166571D01*
G01X448538Y1166196D02*
X448830Y1166238D01*
X449163Y1166363D01*
X449371Y1166571D01*
X449455Y1166863D01*
X449371Y1167154D01*
X449121Y1167404D01*
X448746Y1167529D01*
X448330D01*
X448080Y1167613D01*
X447871Y1167821D01*
X447788Y1168113D01*
X447913Y1168404D01*
X448205Y1168613D01*
X448538Y1168696D01*
X448871Y1168613D01*
X449163Y1168404D01*
X449288Y1168113D01*
X449205Y1167821D01*
X448996Y1167613D01*
X448746Y1167529D01*
X448330D01*
X447955Y1167404D01*
X447705Y1167154D01*
X447621Y1166863D01*
X447705Y1166571D01*
X447913Y1166363D01*
X448246Y1166238D01*
X448538Y1166196D01*
G01X450721Y1166571D02*
X450971Y1166363D01*
X451263Y1166238D01*
X451638Y1166196D01*
X452013Y1166279D01*
X452305Y1166446D01*
X452513Y1166738D01*
X452555Y1167071D01*
X452471Y1167404D01*
X452263Y1167613D01*
X451971Y1167779D01*
X451680Y1167821D01*
X451388Y1167779D01*
X451013Y1167613D01*
X451138Y1168696D01*
X452263D01*
G01X443900Y1142200D02*
X446000Y1140400D01*
X443900Y1138200D01*
G01X443800Y1134600D02*
X463000D01*
Y1145800D01*
X443800D01*
Y1134600D01*
X444200D01*
G01X453416Y1270412D02*
X450916D01*
Y1271453D01*
X451041Y1271787D01*
X451208Y1271995D01*
X451541Y1272078D01*
X451874Y1271995D01*
X452083Y1271745D01*
X452208Y1271453D01*
Y1270412D01*
G01Y1271453D02*
X453416Y1272078D01*
G01X450916Y1273512D02*
X453416D01*
Y1275178D01*
G01Y1278278D02*
Y1276612D01*
X450916D01*
Y1278278D01*
G01X452124Y1277612D02*
Y1276612D01*
G01X453416Y1279628D02*
X450916D01*
Y1280462D01*
X451041Y1280795D01*
X451208Y1281045D01*
X451458Y1281253D01*
X451749Y1281420D01*
X452166Y1281462D01*
X452583Y1281420D01*
X452874Y1281253D01*
X453124Y1281045D01*
X453291Y1280795D01*
X453416Y1280462D01*
Y1279628D01*
G01X451333Y1282853D02*
X451083Y1283103D01*
X450958Y1283395D01*
X450916Y1283728D01*
X450999Y1284145D01*
X451208Y1284437D01*
X451458Y1284520D01*
X451708Y1284478D01*
X451916Y1284312D01*
X452333Y1283478D01*
X452624Y1283103D01*
X453041Y1282853D01*
X453416Y1282770D01*
Y1284520D01*
G01Y1286745D02*
X453374Y1287037D01*
X453249Y1287370D01*
X453041Y1287578D01*
X452749Y1287662D01*
X452458Y1287578D01*
X452208Y1287328D01*
X452083Y1286953D01*
Y1286537D01*
X451999Y1286287D01*
X451791Y1286078D01*
X451499Y1285995D01*
X451208Y1286120D01*
X450999Y1286412D01*
X450916Y1286745D01*
X450999Y1287078D01*
X451208Y1287370D01*
X451499Y1287495D01*
X451791Y1287412D01*
X451999Y1287203D01*
X452083Y1286953D01*
Y1286537D01*
X452208Y1286162D01*
X452458Y1285912D01*
X452749Y1285828D01*
X453041Y1285912D01*
X453249Y1286120D01*
X453374Y1286453D01*
X453416Y1286745D01*
G01X438317Y1271565D02*
Y1282765D01*
X447117D01*
Y1271565D01*
X438317D01*
G01X466761Y221492D02*
X471811D01*
Y320192D01*
X496461D01*
Y135792D01*
X471811D01*
Y194492D01*
X466761D01*
Y221492D01*
G01X466874Y174461D02*
Y178461D01*
X459474D01*
G01X466874Y179161D02*
Y183161D01*
X459474D01*
G01Y193161D02*
Y189161D01*
X466874D01*
G01X467000Y255517D02*
X464500D01*
Y256558D01*
X464625Y256892D01*
X464792Y257100D01*
X465125Y257183D01*
X465458Y257100D01*
X465667Y256850D01*
X465792Y256558D01*
Y255517D01*
G01Y256558D02*
X467000Y257183D01*
G01Y259367D02*
X466458Y259450D01*
X466000Y259575D01*
X465583Y259742D01*
X465125Y259950D01*
X464500Y260283D01*
Y258617D01*
G01X466625Y261633D02*
X466833Y261883D01*
X466958Y262175D01*
X467000Y262550D01*
X466917Y262925D01*
X466750Y263217D01*
X466458Y263425D01*
X466125Y263467D01*
X465792Y263383D01*
X465583Y263175D01*
X465417Y262883D01*
X465375Y262592D01*
X465417Y262300D01*
X465583Y261925D01*
X464500Y262050D01*
Y263175D01*
G01Y265650D02*
X464583Y265317D01*
X464792Y265067D01*
X465042Y264900D01*
X465375Y264775D01*
X465750Y264733D01*
X466125Y264775D01*
X466458Y264900D01*
X466708Y265067D01*
X466917Y265317D01*
X467000Y265650D01*
X466917Y265983D01*
X466708Y266233D01*
X466458Y266400D01*
X466125Y266525D01*
X465750Y266567D01*
X465375Y266525D01*
X465042Y266400D01*
X464792Y266233D01*
X464583Y265983D01*
X464500Y265650D01*
G01X462074Y253961D02*
X470074D01*
Y236361D01*
X462074D01*
Y253961D01*
G01X460374Y244161D02*
Y236161D01*
G01X469000Y224850D02*
X468958Y224517D01*
X468792Y224225D01*
X468542Y223975D01*
X468250Y223808D01*
X467917Y223725D01*
X467583D01*
X467250Y223808D01*
X466958Y223975D01*
X466708Y224225D01*
X466542Y224517D01*
X466500Y224850D01*
X466542Y225183D01*
X466708Y225475D01*
X466958Y225725D01*
X467250Y225892D01*
X467583Y225975D01*
X467917D01*
X468250Y225892D01*
X468542Y225725D01*
X468792Y225475D01*
X468958Y225183D01*
X469000Y224850D01*
G01X468333Y225183D02*
X469000Y225683D01*
G01Y227950D02*
X466500D01*
X467000Y227450D01*
G01X469000D02*
Y228450D01*
G01X467958Y230258D02*
X467667Y230550D01*
X467500Y230800D01*
X467417Y231133D01*
X467500Y231425D01*
X467667Y231633D01*
X467917Y231800D01*
X468208Y231842D01*
X468458Y231800D01*
X468708Y231633D01*
X468917Y231383D01*
X469000Y231092D01*
X468917Y230758D01*
X468667Y230467D01*
X468292Y230300D01*
X467875Y230258D01*
X467333Y230342D01*
X467042Y230467D01*
X466750Y230675D01*
X466542Y230967D01*
X466500Y231258D01*
X466583Y231550D01*
X466792Y231758D01*
G01X469000Y234150D02*
X466500D01*
X467000Y233650D01*
G01X469000D02*
Y234650D01*
G01X464774Y215661D02*
X462674Y217461D01*
X464774Y219661D01*
G01X504017Y260167D02*
Y262667D01*
X505058D01*
X505392Y262542D01*
X505600Y262375D01*
X505683Y262042D01*
X505600Y261709D01*
X505350Y261500D01*
X505058Y261375D01*
X504017D01*
G01X505058D02*
X505683Y260167D01*
G01X507867D02*
X507950Y260709D01*
X508075Y261167D01*
X508242Y261584D01*
X508450Y262042D01*
X508783Y262667D01*
X507117D01*
G01X510133Y260542D02*
X510383Y260334D01*
X510675Y260209D01*
X511050Y260167D01*
X511425Y260250D01*
X511717Y260417D01*
X511925Y260709D01*
X511967Y261042D01*
X511883Y261375D01*
X511675Y261584D01*
X511383Y261750D01*
X511092Y261792D01*
X510800Y261750D01*
X510425Y261584D01*
X510550Y262667D01*
X511675D01*
G01X513233Y260542D02*
X513483Y260334D01*
X513775Y260209D01*
X514150Y260167D01*
X514525Y260250D01*
X514817Y260417D01*
X515025Y260709D01*
X515067Y261042D01*
X514983Y261375D01*
X514775Y261584D01*
X514483Y261750D01*
X514192Y261792D01*
X513900Y261750D01*
X513525Y261584D01*
X513650Y262667D01*
X514775D01*
G01X459708Y281267D02*
X459583Y281017D01*
X459500Y280725D01*
Y280392D01*
X459625Y280017D01*
X459833Y279725D01*
X460083Y279517D01*
X460500Y279350D01*
X460875Y279308D01*
X461250Y279392D01*
X461500Y279517D01*
X461750Y279767D01*
X461917Y280058D01*
X462000Y280350D01*
Y280642D01*
X461917Y280933D01*
X461792Y281183D01*
X461625Y281392D01*
G01X461500Y282533D02*
X461792Y282783D01*
X461958Y283117D01*
X462000Y283492D01*
X461958Y283825D01*
X461750Y284158D01*
X461500Y284367D01*
X461250Y284408D01*
X460958Y284325D01*
X460750Y284033D01*
X460667Y283742D01*
Y283367D01*
G01Y283742D02*
X460542Y283992D01*
X460333Y284200D01*
X460083Y284283D01*
X459833Y284200D01*
X459625Y283992D01*
X459500Y283617D01*
X459542Y283242D01*
X459708Y282867D01*
G01X461708Y285842D02*
X461917Y286133D01*
X462000Y286467D01*
X461917Y286800D01*
X461667Y287092D01*
X461292Y287300D01*
X460917Y287383D01*
X460458D01*
X460083Y287300D01*
X459750Y287092D01*
X459583Y286842D01*
X459500Y286550D01*
X459583Y286217D01*
X459750Y285967D01*
X460000Y285800D01*
X460333Y285717D01*
X460625Y285800D01*
X460917Y286008D01*
X461083Y286258D01*
X461125Y286550D01*
X461042Y286883D01*
X460833Y287133D01*
X460458Y287383D01*
G01X462000Y289567D02*
X461458Y289650D01*
X461000Y289775D01*
X460583Y289942D01*
X460125Y290150D01*
X459500Y290483D01*
Y288817D01*
G01X505334Y266800D02*
X507834D01*
G01X505334Y265842D02*
Y267758D01*
G01X507834Y269067D02*
X505334D01*
Y270067D01*
X505459Y270400D01*
X505751Y270650D01*
X506084Y270733D01*
X506417Y270650D01*
X506667Y270442D01*
X506792Y270067D01*
Y269067D01*
G01X507834Y273000D02*
X505334D01*
X505834Y272500D01*
G01X507834D02*
Y273500D01*
G01X507334Y275183D02*
X507626Y275433D01*
X507792Y275767D01*
X507834Y276142D01*
X507792Y276475D01*
X507584Y276808D01*
X507334Y277017D01*
X507084Y277058D01*
X506792Y276975D01*
X506584Y276683D01*
X506501Y276392D01*
Y276017D01*
G01Y276392D02*
X506376Y276642D01*
X506167Y276850D01*
X505917Y276933D01*
X505667Y276850D01*
X505459Y276642D01*
X505334Y276267D01*
X505376Y275892D01*
X505542Y275517D01*
G01X507834Y279117D02*
X507292Y279200D01*
X506834Y279325D01*
X506417Y279492D01*
X505959Y279700D01*
X505334Y280033D01*
Y278367D01*
G01X462208Y293767D02*
X462083Y293517D01*
X462000Y293225D01*
Y292892D01*
X462125Y292517D01*
X462333Y292225D01*
X462583Y292017D01*
X463000Y291850D01*
X463375Y291808D01*
X463750Y291892D01*
X464000Y292017D01*
X464250Y292267D01*
X464417Y292558D01*
X464500Y292850D01*
Y293142D01*
X464417Y293433D01*
X464292Y293683D01*
X464125Y293892D01*
G01X464000Y295033D02*
X464292Y295283D01*
X464458Y295617D01*
X464500Y295992D01*
X464458Y296325D01*
X464250Y296658D01*
X464000Y296867D01*
X463750Y296908D01*
X463458Y296825D01*
X463250Y296533D01*
X463167Y296242D01*
Y295867D01*
G01Y296242D02*
X463042Y296492D01*
X462833Y296700D01*
X462583Y296783D01*
X462333Y296700D01*
X462125Y296492D01*
X462000Y296117D01*
X462042Y295742D01*
X462208Y295367D01*
G01X464208Y298342D02*
X464417Y298633D01*
X464500Y298967D01*
X464417Y299300D01*
X464167Y299592D01*
X463792Y299800D01*
X463417Y299883D01*
X462958D01*
X462583Y299800D01*
X462250Y299592D01*
X462083Y299342D01*
X462000Y299050D01*
X462083Y298717D01*
X462250Y298467D01*
X462500Y298300D01*
X462833Y298217D01*
X463125Y298300D01*
X463417Y298508D01*
X463583Y298758D01*
X463625Y299050D01*
X463542Y299383D01*
X463333Y299633D01*
X462958Y299883D01*
G01X464500Y302150D02*
X464458Y302442D01*
X464333Y302775D01*
X464125Y302983D01*
X463833Y303067D01*
X463542Y302983D01*
X463292Y302733D01*
X463167Y302358D01*
Y301942D01*
X463083Y301692D01*
X462875Y301483D01*
X462583Y301400D01*
X462292Y301525D01*
X462083Y301817D01*
X462000Y302150D01*
X462083Y302483D01*
X462292Y302775D01*
X462583Y302900D01*
X462875Y302817D01*
X463083Y302608D01*
X463167Y302358D01*
Y301942D01*
X463292Y301567D01*
X463542Y301317D01*
X463833Y301233D01*
X464125Y301317D01*
X464333Y301525D01*
X464458Y301858D01*
X464500Y302150D01*
G01X485275Y327000D02*
Y329500D01*
G01X487025D02*
Y327000D01*
G01Y328250D02*
X485275D01*
G01X488333Y327000D02*
Y329500D01*
X489167D01*
X489500Y329375D01*
X489750Y329208D01*
X489958Y328958D01*
X490125Y328667D01*
X490167Y328250D01*
X490125Y327833D01*
X489958Y327542D01*
X489750Y327292D01*
X489500Y327125D01*
X489167Y327000D01*
X488333D01*
G01X491433D02*
Y329500D01*
X492267D01*
X492600Y329375D01*
X492850Y329208D01*
X493058Y328958D01*
X493225Y328667D01*
X493267Y328250D01*
X493225Y327833D01*
X493058Y327542D01*
X492850Y327292D01*
X492600Y327125D01*
X492267Y327000D01*
X491433D01*
G01X494575Y327333D02*
X494908Y327125D01*
X495283Y327000D01*
X495617D01*
X495950Y327125D01*
X496200Y327333D01*
X496325Y327625D01*
X496242Y327917D01*
X496033Y328167D01*
X495658Y328333D01*
X495158Y328417D01*
X494867Y328583D01*
X494742Y328875D01*
X494825Y329167D01*
X495033Y329375D01*
X495325Y329500D01*
X495617D01*
X495908Y329417D01*
X496158Y329208D01*
G01X497508Y327000D02*
X498550Y329500D01*
X499592Y327000D01*
G01X499217Y327875D02*
X497883D01*
G01X500775Y327333D02*
X501108Y327125D01*
X501483Y327000D01*
X501817D01*
X502150Y327125D01*
X502400Y327333D01*
X502525Y327625D01*
X502442Y327917D01*
X502233Y328167D01*
X501858Y328333D01*
X501358Y328417D01*
X501067Y328583D01*
X500942Y328875D01*
X501025Y329167D01*
X501233Y329375D01*
X501525Y329500D01*
X501817D01*
X502108Y329417D01*
X502358Y329208D01*
G01X503958Y329083D02*
X504208Y329333D01*
X504500Y329458D01*
X504833Y329500D01*
X505250Y329417D01*
X505542Y329208D01*
X505625Y328958D01*
X505583Y328708D01*
X505417Y328500D01*
X504583Y328083D01*
X504208Y327792D01*
X503958Y327375D01*
X503875Y327000D01*
X505625D01*
G01X507767D02*
X507850Y327542D01*
X507975Y328000D01*
X508142Y328417D01*
X508350Y328875D01*
X508683Y329500D01*
X507017D01*
G01X504471Y482142D02*
X504138Y482184D01*
X503846Y482350D01*
X503596Y482600D01*
X503429Y482892D01*
X503346Y483225D01*
Y483559D01*
X503429Y483892D01*
X503596Y484184D01*
X503846Y484434D01*
X504138Y484600D01*
X504471Y484642D01*
X504804Y484600D01*
X505096Y484434D01*
X505346Y484184D01*
X505513Y483892D01*
X505596Y483559D01*
Y483225D01*
X505513Y482892D01*
X505346Y482600D01*
X505096Y482350D01*
X504804Y482184D01*
X504471Y482142D01*
G01X504804Y482809D02*
X505304Y482142D01*
G01X506779Y484225D02*
X507029Y484475D01*
X507321Y484600D01*
X507654Y484642D01*
X508071Y484559D01*
X508363Y484350D01*
X508446Y484100D01*
X508404Y483850D01*
X508238Y483642D01*
X507404Y483225D01*
X507029Y482934D01*
X506779Y482517D01*
X506696Y482142D01*
X508446D01*
G01X510588D02*
X510671Y482684D01*
X510796Y483142D01*
X510963Y483559D01*
X511171Y484017D01*
X511504Y484642D01*
X509838D01*
G01X513063Y482434D02*
X513354Y482225D01*
X513688Y482142D01*
X514021Y482225D01*
X514313Y482475D01*
X514521Y482850D01*
X514604Y483225D01*
Y483684D01*
X514521Y484059D01*
X514313Y484392D01*
X514063Y484559D01*
X513771Y484642D01*
X513438Y484559D01*
X513188Y484392D01*
X513021Y484142D01*
X512938Y483809D01*
X513021Y483517D01*
X513229Y483225D01*
X513479Y483059D01*
X513771Y483017D01*
X514104Y483100D01*
X514354Y483309D01*
X514604Y483684D01*
G01X504121Y496142D02*
X517121D01*
G01X504121Y510142D02*
Y496142D01*
G01X500767Y521874D02*
Y524374D01*
X501808D01*
X502142Y524249D01*
X502350Y524082D01*
X502433Y523749D01*
X502350Y523416D01*
X502100Y523207D01*
X501808Y523082D01*
X500767D01*
G01X501808D02*
X502433Y521874D01*
G01X503783Y522249D02*
X504033Y522041D01*
X504325Y521916D01*
X504700Y521874D01*
X505075Y521957D01*
X505367Y522124D01*
X505575Y522416D01*
X505617Y522749D01*
X505533Y523082D01*
X505325Y523291D01*
X505033Y523457D01*
X504742Y523499D01*
X504450Y523457D01*
X504075Y523291D01*
X504200Y524374D01*
X505325D01*
G01X507800Y521874D02*
Y524374D01*
X507300Y523874D01*
G01Y521874D02*
X508300D01*
G01X510900D02*
X511192Y521916D01*
X511525Y522041D01*
X511733Y522249D01*
X511817Y522541D01*
X511733Y522832D01*
X511483Y523082D01*
X511108Y523207D01*
X510692D01*
X510442Y523291D01*
X510233Y523499D01*
X510150Y523791D01*
X510275Y524082D01*
X510567Y524291D01*
X510900Y524374D01*
X511233Y524291D01*
X511525Y524082D01*
X511650Y523791D01*
X511567Y523499D01*
X511358Y523291D01*
X511108Y523207D01*
X510692D01*
X510317Y523082D01*
X510067Y522832D01*
X509983Y522541D01*
X510067Y522249D01*
X510275Y522041D01*
X510608Y521916D01*
X510900Y521874D01*
G01X517121Y510142D02*
X504121D01*
G01X466761Y674248D02*
X471811D01*
Y772948D01*
X496461D01*
Y588548D01*
X471811D01*
Y647248D01*
X466761D01*
Y674248D01*
G01X506838Y569084D02*
X504338D01*
Y569918D01*
X504463Y570251D01*
X504630Y570501D01*
X504880Y570709D01*
X505171Y570876D01*
X505588Y570918D01*
X506005Y570876D01*
X506296Y570709D01*
X506546Y570501D01*
X506713Y570251D01*
X506838Y569918D01*
Y569084D01*
G01Y573601D02*
X504338D01*
X506130Y572059D01*
Y574143D01*
G01X504755Y575409D02*
X504505Y575659D01*
X504380Y575951D01*
X504338Y576284D01*
X504421Y576701D01*
X504630Y576993D01*
X504880Y577076D01*
X505130Y577034D01*
X505338Y576868D01*
X505755Y576034D01*
X506046Y575659D01*
X506463Y575409D01*
X506838Y575326D01*
Y577076D01*
G01X466874Y631917D02*
Y635917D01*
X459474D01*
G01Y645917D02*
Y641917D01*
X466874D01*
G01X502713Y618440D02*
X502463Y618565D01*
X502171Y618648D01*
X501838D01*
X501463Y618523D01*
X501171Y618315D01*
X500963Y618065D01*
X500796Y617648D01*
X500754Y617273D01*
X500838Y616898D01*
X500963Y616648D01*
X501213Y616398D01*
X501504Y616231D01*
X501796Y616148D01*
X502088D01*
X502379Y616231D01*
X502629Y616356D01*
X502838Y616523D01*
G01X504104Y618231D02*
X504354Y618481D01*
X504646Y618606D01*
X504979Y618648D01*
X505396Y618565D01*
X505688Y618356D01*
X505771Y618106D01*
X505729Y617856D01*
X505563Y617648D01*
X504729Y617231D01*
X504354Y616940D01*
X504104Y616523D01*
X504021Y616148D01*
X505771D01*
G01X507079Y616648D02*
X507329Y616356D01*
X507663Y616190D01*
X508038Y616148D01*
X508371Y616190D01*
X508704Y616398D01*
X508913Y616648D01*
X508954Y616898D01*
X508871Y617190D01*
X508579Y617398D01*
X508288Y617481D01*
X507913D01*
G01X508288D02*
X508538Y617606D01*
X508746Y617815D01*
X508829Y618065D01*
X508746Y618315D01*
X508538Y618523D01*
X508163Y618648D01*
X507788Y618606D01*
X507413Y618440D01*
G01X511596Y616148D02*
Y618648D01*
X510054Y616856D01*
X512138D01*
G01X502767Y622292D02*
X502517Y622417D01*
X502225Y622500D01*
X501892D01*
X501517Y622375D01*
X501225Y622167D01*
X501017Y621917D01*
X500850Y621500D01*
X500808Y621125D01*
X500892Y620750D01*
X501017Y620500D01*
X501267Y620250D01*
X501558Y620083D01*
X501850Y620000D01*
X502142D01*
X502433Y620083D01*
X502683Y620208D01*
X502892Y620375D01*
G01X504158Y622083D02*
X504408Y622333D01*
X504700Y622458D01*
X505033Y622500D01*
X505450Y622417D01*
X505742Y622208D01*
X505825Y621958D01*
X505783Y621708D01*
X505617Y621500D01*
X504783Y621083D01*
X504408Y620792D01*
X504158Y620375D01*
X504075Y620000D01*
X505825D01*
G01X507133Y620500D02*
X507383Y620208D01*
X507717Y620042D01*
X508092Y620000D01*
X508425Y620042D01*
X508758Y620250D01*
X508967Y620500D01*
X509008Y620750D01*
X508925Y621042D01*
X508633Y621250D01*
X508342Y621333D01*
X507967D01*
G01X508342D02*
X508592Y621458D01*
X508800Y621667D01*
X508883Y621917D01*
X508800Y622167D01*
X508592Y622375D01*
X508217Y622500D01*
X507842Y622458D01*
X507467Y622292D01*
G01X510233Y620500D02*
X510483Y620208D01*
X510817Y620042D01*
X511192Y620000D01*
X511525Y620042D01*
X511858Y620250D01*
X512067Y620500D01*
X512108Y620750D01*
X512025Y621042D01*
X511733Y621250D01*
X511442Y621333D01*
X511067D01*
G01X511442D02*
X511692Y621458D01*
X511900Y621667D01*
X511983Y621917D01*
X511900Y622167D01*
X511692Y622375D01*
X511317Y622500D01*
X510942Y622458D01*
X510567Y622292D01*
G01X462074Y706717D02*
X470074D01*
Y689117D01*
X462074D01*
Y706717D01*
G01X460374Y696917D02*
Y688917D01*
G01X469000Y678900D02*
X468958Y678567D01*
X468792Y678275D01*
X468542Y678025D01*
X468250Y677858D01*
X467917Y677775D01*
X467583D01*
X467250Y677858D01*
X466958Y678025D01*
X466708Y678275D01*
X466542Y678567D01*
X466500Y678900D01*
X466542Y679233D01*
X466708Y679525D01*
X466958Y679775D01*
X467250Y679942D01*
X467583Y680025D01*
X467917D01*
X468250Y679942D01*
X468542Y679775D01*
X468792Y679525D01*
X468958Y679233D01*
X469000Y678900D01*
G01X468333Y679233D02*
X469000Y679733D01*
G01Y682000D02*
X468958Y682292D01*
X468833Y682625D01*
X468625Y682833D01*
X468333Y682917D01*
X468042Y682833D01*
X467792Y682583D01*
X467667Y682208D01*
Y681792D01*
X467583Y681542D01*
X467375Y681333D01*
X467083Y681250D01*
X466792Y681375D01*
X466583Y681667D01*
X466500Y682000D01*
X466583Y682333D01*
X466792Y682625D01*
X467083Y682750D01*
X467375Y682667D01*
X467583Y682458D01*
X467667Y682208D01*
Y681792D01*
X467792Y681417D01*
X468042Y681167D01*
X468333Y681083D01*
X468625Y681167D01*
X468833Y681375D01*
X468958Y681708D01*
X469000Y682000D01*
G01X468708Y684392D02*
X468917Y684683D01*
X469000Y685017D01*
X468917Y685350D01*
X468667Y685642D01*
X468292Y685850D01*
X467917Y685933D01*
X467458D01*
X467083Y685850D01*
X466750Y685642D01*
X466583Y685392D01*
X466500Y685100D01*
X466583Y684767D01*
X466750Y684517D01*
X467000Y684350D01*
X467333Y684267D01*
X467625Y684350D01*
X467917Y684558D01*
X468083Y684808D01*
X468125Y685100D01*
X468042Y685433D01*
X467833Y685683D01*
X467458Y685933D01*
G01X464774Y668417D02*
X462674Y670217D01*
X464774Y672417D01*
G01X509392Y732666D02*
X506892D01*
Y733707D01*
X507017Y734041D01*
X507184Y734249D01*
X507517Y734332D01*
X507850Y734249D01*
X508059Y733999D01*
X508184Y733707D01*
Y732666D01*
G01Y733707D02*
X509392Y734332D01*
G01Y737099D02*
X506892D01*
X508684Y735557D01*
Y737641D01*
G01X509392Y739616D02*
X508850Y739699D01*
X508392Y739824D01*
X507975Y739991D01*
X507517Y740199D01*
X506892Y740532D01*
Y738866D01*
G01X509392Y742799D02*
X506892D01*
X507392Y742299D01*
G01X509392D02*
Y743299D01*
G01X467000Y708017D02*
X464500D01*
Y709058D01*
X464625Y709392D01*
X464792Y709600D01*
X465125Y709683D01*
X465458Y709600D01*
X465667Y709350D01*
X465792Y709058D01*
Y708017D01*
G01Y709058D02*
X467000Y709683D01*
G01Y712450D02*
X464500D01*
X466292Y710908D01*
Y712992D01*
G01X467000Y714967D02*
X466458Y715050D01*
X466000Y715175D01*
X465583Y715342D01*
X465125Y715550D01*
X464500Y715883D01*
Y714217D01*
G01X467000Y718650D02*
X464500D01*
X466292Y717108D01*
Y719192D01*
G01X459708Y733767D02*
X459583Y733517D01*
X459500Y733225D01*
Y732892D01*
X459625Y732517D01*
X459833Y732225D01*
X460083Y732017D01*
X460500Y731850D01*
X460875Y731808D01*
X461250Y731892D01*
X461500Y732017D01*
X461750Y732267D01*
X461917Y732558D01*
X462000Y732850D01*
Y733142D01*
X461917Y733433D01*
X461792Y733683D01*
X461625Y733892D01*
G01X459917Y735158D02*
X459667Y735408D01*
X459542Y735700D01*
X459500Y736033D01*
X459583Y736450D01*
X459792Y736742D01*
X460042Y736825D01*
X460292Y736783D01*
X460500Y736617D01*
X460917Y735783D01*
X461208Y735408D01*
X461625Y735158D01*
X462000Y735075D01*
Y736825D01*
G01Y739550D02*
X459500D01*
X461292Y738008D01*
Y740092D01*
G01X462000Y742150D02*
X459500D01*
X460000Y741650D01*
G01X462000D02*
Y742650D01*
G01X506574Y718767D02*
X509074D01*
G01X506574Y717809D02*
Y719725D01*
G01X509074Y721034D02*
X506574D01*
Y722034D01*
X506699Y722367D01*
X506991Y722617D01*
X507324Y722700D01*
X507657Y722617D01*
X507907Y722409D01*
X508032Y722034D01*
Y721034D01*
G01X509074Y724884D02*
X508532Y724967D01*
X508074Y725092D01*
X507657Y725259D01*
X507199Y725467D01*
X506574Y725800D01*
Y724134D01*
G01X509074Y727984D02*
X508532Y728067D01*
X508074Y728192D01*
X507657Y728359D01*
X507199Y728567D01*
X506574Y728900D01*
Y727234D01*
G01X501017Y712000D02*
Y714500D01*
X502058D01*
X502392Y714375D01*
X502600Y714208D01*
X502683Y713875D01*
X502600Y713542D01*
X502350Y713333D01*
X502058Y713208D01*
X501017D01*
G01X502058D02*
X502683Y712000D01*
G01X505450D02*
Y714500D01*
X503908Y712708D01*
X505992D01*
G01X507967Y712000D02*
X508050Y712542D01*
X508175Y713000D01*
X508342Y713417D01*
X508550Y713875D01*
X508883Y714500D01*
X507217D01*
G01X510442Y712292D02*
X510733Y712083D01*
X511067Y712000D01*
X511400Y712083D01*
X511692Y712333D01*
X511900Y712708D01*
X511983Y713083D01*
Y713542D01*
X511900Y713917D01*
X511692Y714250D01*
X511442Y714417D01*
X511150Y714500D01*
X510817Y714417D01*
X510567Y714250D01*
X510400Y714000D01*
X510317Y713667D01*
X510400Y713375D01*
X510608Y713083D01*
X510858Y712917D01*
X511150Y712875D01*
X511483Y712958D01*
X511733Y713167D01*
X511983Y713542D01*
G01X462208Y745767D02*
X462083Y745517D01*
X462000Y745225D01*
Y744892D01*
X462125Y744517D01*
X462333Y744225D01*
X462583Y744017D01*
X463000Y743850D01*
X463375Y743808D01*
X463750Y743892D01*
X464000Y744017D01*
X464250Y744267D01*
X464417Y744558D01*
X464500Y744850D01*
Y745142D01*
X464417Y745433D01*
X464292Y745683D01*
X464125Y745892D01*
G01X462417Y747158D02*
X462167Y747408D01*
X462042Y747700D01*
X462000Y748033D01*
X462083Y748450D01*
X462292Y748742D01*
X462542Y748825D01*
X462792Y748783D01*
X463000Y748617D01*
X463417Y747783D01*
X463708Y747408D01*
X464125Y747158D01*
X464500Y747075D01*
Y748825D01*
G01Y751550D02*
X462000D01*
X463792Y750008D01*
Y752092D01*
G01X462417Y753358D02*
X462167Y753608D01*
X462042Y753900D01*
X462000Y754233D01*
X462083Y754650D01*
X462292Y754942D01*
X462542Y755025D01*
X462792Y754983D01*
X463000Y754817D01*
X463417Y753983D01*
X463708Y753608D01*
X464125Y753358D01*
X464500Y753275D01*
Y755025D01*
G01X466761Y1127004D02*
X471811D01*
Y1225704D01*
X496461D01*
Y1041304D01*
X471811D01*
Y1100004D01*
X466761D01*
Y1127004D01*
G01X464500Y1065517D02*
X462000D01*
Y1066558D01*
X462125Y1066892D01*
X462292Y1067100D01*
X462625Y1067183D01*
X462958Y1067100D01*
X463167Y1066850D01*
X463292Y1066558D01*
Y1065517D01*
G01Y1066558D02*
X464500Y1067183D01*
G01X462417Y1068658D02*
X462167Y1068908D01*
X462042Y1069200D01*
X462000Y1069533D01*
X462083Y1069950D01*
X462292Y1070242D01*
X462542Y1070325D01*
X462792Y1070283D01*
X463000Y1070117D01*
X463417Y1069283D01*
X463708Y1068908D01*
X464125Y1068658D01*
X464500Y1068575D01*
Y1070325D01*
G01Y1072550D02*
X462000D01*
X462500Y1072050D01*
G01X464500D02*
Y1073050D01*
G01X462417Y1074858D02*
X462167Y1075108D01*
X462042Y1075400D01*
X462000Y1075733D01*
X462083Y1076150D01*
X462292Y1076442D01*
X462542Y1076525D01*
X462792Y1076483D01*
X463000Y1076317D01*
X463417Y1075483D01*
X463708Y1075108D01*
X464125Y1074858D01*
X464500Y1074775D01*
Y1076525D01*
G01X467500Y1081000D02*
X467458Y1080667D01*
X467292Y1080375D01*
X467042Y1080125D01*
X466750Y1079958D01*
X466417Y1079875D01*
X466083D01*
X465750Y1079958D01*
X465458Y1080125D01*
X465208Y1080375D01*
X465042Y1080667D01*
X465000Y1081000D01*
X465042Y1081333D01*
X465208Y1081625D01*
X465458Y1081875D01*
X465750Y1082042D01*
X466083Y1082125D01*
X466417D01*
X466750Y1082042D01*
X467042Y1081875D01*
X467292Y1081625D01*
X467458Y1081333D01*
X467500Y1081000D01*
G01X466833Y1081333D02*
X467500Y1081833D01*
G01Y1084100D02*
X465000D01*
X465500Y1083600D01*
G01X467500D02*
Y1084600D01*
G01X467208Y1086492D02*
X467417Y1086783D01*
X467500Y1087117D01*
X467417Y1087450D01*
X467167Y1087742D01*
X466792Y1087950D01*
X466417Y1088033D01*
X465958D01*
X465583Y1087950D01*
X465250Y1087742D01*
X465083Y1087492D01*
X465000Y1087200D01*
X465083Y1086867D01*
X465250Y1086617D01*
X465500Y1086450D01*
X465833Y1086367D01*
X466125Y1086450D01*
X466417Y1086658D01*
X466583Y1086908D01*
X466625Y1087200D01*
X466542Y1087533D01*
X466333Y1087783D01*
X465958Y1088033D01*
G01X463873Y1078126D02*
Y1089526D01*
G01X505888Y1074354D02*
X505638Y1074479D01*
X505346Y1074562D01*
X505013D01*
X504638Y1074437D01*
X504346Y1074229D01*
X504138Y1073979D01*
X503971Y1073562D01*
X503929Y1073187D01*
X504013Y1072812D01*
X504138Y1072562D01*
X504388Y1072312D01*
X504679Y1072145D01*
X504971Y1072062D01*
X505263D01*
X505554Y1072145D01*
X505804Y1072270D01*
X506013Y1072437D01*
G01X507988Y1072062D02*
X508071Y1072604D01*
X508196Y1073062D01*
X508363Y1073479D01*
X508571Y1073937D01*
X508904Y1074562D01*
X507238D01*
G01X511171Y1072062D02*
X511463Y1072104D01*
X511796Y1072229D01*
X512004Y1072437D01*
X512088Y1072729D01*
X512004Y1073020D01*
X511754Y1073270D01*
X511379Y1073395D01*
X510963D01*
X510713Y1073479D01*
X510504Y1073687D01*
X510421Y1073979D01*
X510546Y1074270D01*
X510838Y1074479D01*
X511171Y1074562D01*
X511504Y1074479D01*
X511796Y1074270D01*
X511921Y1073979D01*
X511838Y1073687D01*
X511629Y1073479D01*
X511379Y1073395D01*
X510963D01*
X510588Y1073270D01*
X510338Y1073020D01*
X510254Y1072729D01*
X510338Y1072437D01*
X510546Y1072229D01*
X510879Y1072104D01*
X511171Y1072062D01*
G01X506188Y1070054D02*
X505938Y1070179D01*
X505646Y1070262D01*
X505313D01*
X504938Y1070137D01*
X504646Y1069929D01*
X504438Y1069679D01*
X504271Y1069262D01*
X504229Y1068887D01*
X504313Y1068512D01*
X504438Y1068262D01*
X504688Y1068012D01*
X504979Y1067845D01*
X505271Y1067762D01*
X505563D01*
X505854Y1067845D01*
X506104Y1067970D01*
X506313Y1068137D01*
G01X508288Y1067762D02*
X508371Y1068304D01*
X508496Y1068762D01*
X508663Y1069179D01*
X508871Y1069637D01*
X509204Y1070262D01*
X507538D01*
G01X511388Y1067762D02*
X511471Y1068304D01*
X511596Y1068762D01*
X511763Y1069179D01*
X511971Y1069637D01*
X512304Y1070262D01*
X510638D01*
G01X503491Y1098573D02*
Y1101073D01*
X504532D01*
X504866Y1100948D01*
X505074Y1100781D01*
X505157Y1100448D01*
X505074Y1100115D01*
X504824Y1099906D01*
X504532Y1099781D01*
X503491D01*
G01X504532D02*
X505157Y1098573D01*
G01X506632Y1100656D02*
X506882Y1100906D01*
X507174Y1101031D01*
X507507Y1101073D01*
X507924Y1100990D01*
X508216Y1100781D01*
X508299Y1100531D01*
X508257Y1100281D01*
X508091Y1100073D01*
X507257Y1099656D01*
X506882Y1099365D01*
X506632Y1098948D01*
X506549Y1098573D01*
X508299D01*
G01X510524Y1101073D02*
X510191Y1100990D01*
X509941Y1100781D01*
X509774Y1100531D01*
X509649Y1100198D01*
X509607Y1099823D01*
X509649Y1099448D01*
X509774Y1099115D01*
X509941Y1098865D01*
X510191Y1098656D01*
X510524Y1098573D01*
X510857Y1098656D01*
X511107Y1098865D01*
X511274Y1099115D01*
X511399Y1099448D01*
X511441Y1099823D01*
X511399Y1100198D01*
X511274Y1100531D01*
X511107Y1100781D01*
X510857Y1100990D01*
X510524Y1101073D01*
G01X512832Y1099615D02*
X513124Y1099906D01*
X513374Y1100073D01*
X513707Y1100156D01*
X513999Y1100073D01*
X514207Y1099906D01*
X514374Y1099656D01*
X514416Y1099365D01*
X514374Y1099115D01*
X514207Y1098865D01*
X513957Y1098656D01*
X513666Y1098573D01*
X513332Y1098656D01*
X513041Y1098906D01*
X512874Y1099281D01*
X512832Y1099698D01*
X512916Y1100240D01*
X513041Y1100531D01*
X513249Y1100823D01*
X513541Y1101031D01*
X513832Y1101073D01*
X514124Y1100990D01*
X514332Y1100781D01*
G01X502774Y1112573D02*
Y1108573D01*
X510174D01*
G01X498517Y1124500D02*
Y1127000D01*
X499558D01*
X499892Y1126875D01*
X500100Y1126708D01*
X500183Y1126375D01*
X500100Y1126042D01*
X499850Y1125833D01*
X499558Y1125708D01*
X498517D01*
G01X499558D02*
X500183Y1124500D01*
G01X501658Y1126583D02*
X501908Y1126833D01*
X502200Y1126958D01*
X502533Y1127000D01*
X502950Y1126917D01*
X503242Y1126708D01*
X503325Y1126458D01*
X503283Y1126208D01*
X503117Y1126000D01*
X502283Y1125583D01*
X501908Y1125292D01*
X501658Y1124875D01*
X501575Y1124500D01*
X503325D01*
G01X505550Y1127000D02*
X505217Y1126917D01*
X504967Y1126708D01*
X504800Y1126458D01*
X504675Y1126125D01*
X504633Y1125750D01*
X504675Y1125375D01*
X504800Y1125042D01*
X504967Y1124792D01*
X505217Y1124583D01*
X505550Y1124500D01*
X505883Y1124583D01*
X506133Y1124792D01*
X506300Y1125042D01*
X506425Y1125375D01*
X506467Y1125750D01*
X506425Y1126125D01*
X506300Y1126458D01*
X506133Y1126708D01*
X505883Y1126917D01*
X505550Y1127000D01*
G01X507733Y1125000D02*
X507983Y1124708D01*
X508317Y1124542D01*
X508692Y1124500D01*
X509025Y1124542D01*
X509358Y1124750D01*
X509567Y1125000D01*
X509608Y1125250D01*
X509525Y1125542D01*
X509233Y1125750D01*
X508942Y1125833D01*
X508567D01*
G01X508942D02*
X509192Y1125958D01*
X509400Y1126167D01*
X509483Y1126417D01*
X509400Y1126667D01*
X509192Y1126875D01*
X508817Y1127000D01*
X508442Y1126958D01*
X508067Y1126792D01*
G01X506791Y1104865D02*
X506541Y1104990D01*
X506249Y1105073D01*
X505916D01*
X505541Y1104948D01*
X505249Y1104740D01*
X505041Y1104490D01*
X504874Y1104073D01*
X504832Y1103698D01*
X504916Y1103323D01*
X505041Y1103073D01*
X505291Y1102823D01*
X505582Y1102656D01*
X505874Y1102573D01*
X506166D01*
X506457Y1102656D01*
X506707Y1102781D01*
X506916Y1102948D01*
G01X508974Y1102573D02*
X509266Y1102615D01*
X509599Y1102740D01*
X509807Y1102948D01*
X509891Y1103240D01*
X509807Y1103531D01*
X509557Y1103781D01*
X509182Y1103906D01*
X508766D01*
X508516Y1103990D01*
X508307Y1104198D01*
X508224Y1104490D01*
X508349Y1104781D01*
X508641Y1104990D01*
X508974Y1105073D01*
X509307Y1104990D01*
X509599Y1104781D01*
X509724Y1104490D01*
X509641Y1104198D01*
X509432Y1103990D01*
X509182Y1103906D01*
X508766D01*
X508391Y1103781D01*
X508141Y1103531D01*
X508057Y1103240D01*
X508141Y1102948D01*
X508349Y1102740D01*
X508682Y1102615D01*
X508974Y1102573D01*
G01X511991D02*
X512074Y1103115D01*
X512199Y1103573D01*
X512366Y1103990D01*
X512574Y1104448D01*
X512907Y1105073D01*
X511241D01*
G01X498591Y1152973D02*
Y1155473D01*
X499632D01*
X499966Y1155348D01*
X500174Y1155181D01*
X500257Y1154848D01*
X500174Y1154515D01*
X499924Y1154306D01*
X499632Y1154181D01*
X498591D01*
G01X499632D02*
X500257Y1152973D01*
G01X501732Y1155056D02*
X501982Y1155306D01*
X502274Y1155431D01*
X502607Y1155473D01*
X503024Y1155390D01*
X503316Y1155181D01*
X503399Y1154931D01*
X503357Y1154681D01*
X503191Y1154473D01*
X502357Y1154056D01*
X501982Y1153765D01*
X501732Y1153348D01*
X501649Y1152973D01*
X503399D01*
G01X505624Y1155473D02*
X505291Y1155390D01*
X505041Y1155181D01*
X504874Y1154931D01*
X504749Y1154598D01*
X504707Y1154223D01*
X504749Y1153848D01*
X504874Y1153515D01*
X505041Y1153265D01*
X505291Y1153056D01*
X505624Y1152973D01*
X505957Y1153056D01*
X506207Y1153265D01*
X506374Y1153515D01*
X506499Y1153848D01*
X506541Y1154223D01*
X506499Y1154598D01*
X506374Y1154931D01*
X506207Y1155181D01*
X505957Y1155390D01*
X505624Y1155473D01*
G01X508724Y1152973D02*
Y1155473D01*
X508224Y1154973D01*
G01Y1152973D02*
X509224D01*
G01X505274Y1143973D02*
Y1147973D01*
X497874D01*
G01X504017Y1165167D02*
Y1167667D01*
X505058D01*
X505392Y1167542D01*
X505600Y1167375D01*
X505683Y1167042D01*
X505600Y1166709D01*
X505350Y1166500D01*
X505058Y1166375D01*
X504017D01*
G01X505058D02*
X505683Y1165167D01*
G01X507033Y1165542D02*
X507283Y1165334D01*
X507575Y1165209D01*
X507950Y1165167D01*
X508325Y1165250D01*
X508617Y1165417D01*
X508825Y1165709D01*
X508867Y1166042D01*
X508783Y1166375D01*
X508575Y1166584D01*
X508283Y1166750D01*
X507992Y1166792D01*
X507700Y1166750D01*
X507325Y1166584D01*
X507450Y1167667D01*
X508575D01*
G01X510258Y1166209D02*
X510550Y1166500D01*
X510800Y1166667D01*
X511133Y1166750D01*
X511425Y1166667D01*
X511633Y1166500D01*
X511800Y1166250D01*
X511842Y1165959D01*
X511800Y1165709D01*
X511633Y1165459D01*
X511383Y1165250D01*
X511092Y1165167D01*
X510758Y1165250D01*
X510467Y1165500D01*
X510300Y1165875D01*
X510258Y1166292D01*
X510342Y1166834D01*
X510467Y1167125D01*
X510675Y1167417D01*
X510967Y1167625D01*
X511258Y1167667D01*
X511550Y1167584D01*
X511758Y1167375D01*
G01X513233Y1165667D02*
X513483Y1165375D01*
X513817Y1165209D01*
X514192Y1165167D01*
X514525Y1165209D01*
X514858Y1165417D01*
X515067Y1165667D01*
X515108Y1165917D01*
X515025Y1166209D01*
X514733Y1166417D01*
X514442Y1166500D01*
X514067D01*
G01X514442D02*
X514692Y1166625D01*
X514900Y1166834D01*
X514983Y1167084D01*
X514900Y1167334D01*
X514692Y1167542D01*
X514317Y1167667D01*
X513942Y1167625D01*
X513567Y1167459D01*
G01X499017Y1159166D02*
Y1161666D01*
X500058D01*
X500392Y1161541D01*
X500600Y1161374D01*
X500683Y1161041D01*
X500600Y1160708D01*
X500350Y1160499D01*
X500058Y1160374D01*
X499017D01*
G01X500058D02*
X500683Y1159166D01*
G01X502950D02*
Y1161666D01*
X502450Y1161166D01*
G01Y1159166D02*
X503450D01*
G01X505342Y1159458D02*
X505633Y1159249D01*
X505967Y1159166D01*
X506300Y1159249D01*
X506592Y1159499D01*
X506800Y1159874D01*
X506883Y1160249D01*
Y1160708D01*
X506800Y1161083D01*
X506592Y1161416D01*
X506342Y1161583D01*
X506050Y1161666D01*
X505717Y1161583D01*
X505467Y1161416D01*
X505300Y1161166D01*
X505217Y1160833D01*
X505300Y1160541D01*
X505508Y1160249D01*
X505758Y1160083D01*
X506050Y1160041D01*
X506383Y1160124D01*
X506633Y1160333D01*
X506883Y1160708D01*
G01X509150Y1159166D02*
X509442Y1159208D01*
X509775Y1159333D01*
X509983Y1159541D01*
X510067Y1159833D01*
X509983Y1160124D01*
X509733Y1160374D01*
X509358Y1160499D01*
X508942D01*
X508692Y1160583D01*
X508483Y1160791D01*
X508400Y1161083D01*
X508525Y1161374D01*
X508817Y1161583D01*
X509150Y1161666D01*
X509483Y1161583D01*
X509775Y1161374D01*
X509900Y1161083D01*
X509817Y1160791D01*
X509608Y1160583D01*
X509358Y1160499D01*
X508942D01*
X508567Y1160374D01*
X508317Y1160124D01*
X508233Y1159833D01*
X508317Y1159541D01*
X508525Y1159333D01*
X508858Y1159208D01*
X509150Y1159166D01*
G01X469700Y1137500D02*
X469658Y1137167D01*
X469492Y1136875D01*
X469242Y1136625D01*
X468950Y1136458D01*
X468617Y1136375D01*
X468283D01*
X467950Y1136458D01*
X467658Y1136625D01*
X467408Y1136875D01*
X467242Y1137167D01*
X467200Y1137500D01*
X467242Y1137833D01*
X467408Y1138125D01*
X467658Y1138375D01*
X467950Y1138542D01*
X468283Y1138625D01*
X468617D01*
X468950Y1138542D01*
X469242Y1138375D01*
X469492Y1138125D01*
X469658Y1137833D01*
X469700Y1137500D01*
G01X469033Y1137833D02*
X469700Y1138333D01*
G01X467617Y1139808D02*
X467367Y1140058D01*
X467242Y1140350D01*
X467200Y1140683D01*
X467283Y1141100D01*
X467492Y1141392D01*
X467742Y1141475D01*
X467992Y1141433D01*
X468200Y1141267D01*
X468617Y1140433D01*
X468908Y1140058D01*
X469325Y1139808D01*
X469700Y1139725D01*
Y1141475D01*
G01X467200Y1143700D02*
X467283Y1143367D01*
X467492Y1143117D01*
X467742Y1142950D01*
X468075Y1142825D01*
X468450Y1142783D01*
X468825Y1142825D01*
X469158Y1142950D01*
X469408Y1143117D01*
X469617Y1143367D01*
X469700Y1143700D01*
X469617Y1144033D01*
X469408Y1144283D01*
X469158Y1144450D01*
X468825Y1144575D01*
X468450Y1144617D01*
X468075Y1144575D01*
X467742Y1144450D01*
X467492Y1144283D01*
X467283Y1144033D01*
X467200Y1143700D01*
G01X506000Y1171850D02*
X508500D01*
G01X506000Y1170892D02*
Y1172808D01*
G01X508500Y1174117D02*
X506000D01*
Y1175117D01*
X506125Y1175450D01*
X506417Y1175700D01*
X506750Y1175783D01*
X507083Y1175700D01*
X507333Y1175492D01*
X507458Y1175117D01*
Y1174117D01*
G01X508500Y1178050D02*
X506000D01*
X506500Y1177550D01*
G01X508500D02*
Y1178550D01*
G01Y1181067D02*
X507958Y1181150D01*
X507500Y1181275D01*
X507083Y1181442D01*
X506625Y1181650D01*
X506000Y1181983D01*
Y1180317D01*
G01X501891Y1151265D02*
X501641Y1151390D01*
X501349Y1151473D01*
X501016D01*
X500641Y1151348D01*
X500349Y1151140D01*
X500141Y1150890D01*
X499974Y1150473D01*
X499932Y1150098D01*
X500016Y1149723D01*
X500141Y1149473D01*
X500391Y1149223D01*
X500682Y1149056D01*
X500974Y1148973D01*
X501266D01*
X501557Y1149056D01*
X501807Y1149181D01*
X502016Y1149348D01*
G01X504074Y1148973D02*
X504366Y1149015D01*
X504699Y1149140D01*
X504907Y1149348D01*
X504991Y1149640D01*
X504907Y1149931D01*
X504657Y1150181D01*
X504282Y1150306D01*
X503866D01*
X503616Y1150390D01*
X503407Y1150598D01*
X503324Y1150890D01*
X503449Y1151181D01*
X503741Y1151390D01*
X504074Y1151473D01*
X504407Y1151390D01*
X504699Y1151181D01*
X504824Y1150890D01*
X504741Y1150598D01*
X504532Y1150390D01*
X504282Y1150306D01*
X503866D01*
X503491Y1150181D01*
X503241Y1149931D01*
X503157Y1149640D01*
X503241Y1149348D01*
X503449Y1149140D01*
X503782Y1149015D01*
X504074Y1148973D01*
G01X507674D02*
Y1151473D01*
X506132Y1149681D01*
X508216D01*
G01X460208Y1186317D02*
X460083Y1186067D01*
X460000Y1185775D01*
Y1185442D01*
X460125Y1185067D01*
X460333Y1184775D01*
X460583Y1184567D01*
X461000Y1184400D01*
X461375Y1184358D01*
X461750Y1184442D01*
X462000Y1184567D01*
X462250Y1184817D01*
X462417Y1185108D01*
X462500Y1185400D01*
Y1185692D01*
X462417Y1185983D01*
X462292Y1186233D01*
X462125Y1186442D01*
G01X462500Y1188500D02*
X462458Y1188792D01*
X462333Y1189125D01*
X462125Y1189333D01*
X461833Y1189417D01*
X461542Y1189333D01*
X461292Y1189083D01*
X461167Y1188708D01*
Y1188292D01*
X461083Y1188042D01*
X460875Y1187833D01*
X460583Y1187750D01*
X460292Y1187875D01*
X460083Y1188167D01*
X460000Y1188500D01*
X460083Y1188833D01*
X460292Y1189125D01*
X460583Y1189250D01*
X460875Y1189167D01*
X461083Y1188958D01*
X461167Y1188708D01*
Y1188292D01*
X461292Y1187917D01*
X461542Y1187667D01*
X461833Y1187583D01*
X462125Y1187667D01*
X462333Y1187875D01*
X462458Y1188208D01*
X462500Y1188500D01*
G01X462000Y1190683D02*
X462292Y1190933D01*
X462458Y1191267D01*
X462500Y1191642D01*
X462458Y1191975D01*
X462250Y1192308D01*
X462000Y1192517D01*
X461750Y1192558D01*
X461458Y1192475D01*
X461250Y1192183D01*
X461167Y1191892D01*
Y1191517D01*
G01Y1191892D02*
X461042Y1192142D01*
X460833Y1192350D01*
X460583Y1192433D01*
X460333Y1192350D01*
X460125Y1192142D01*
X460000Y1191767D01*
X460042Y1191392D01*
X460208Y1191017D01*
G01X509103Y1204674D02*
X506603D01*
Y1205715D01*
X506728Y1206049D01*
X506895Y1206257D01*
X507228Y1206340D01*
X507561Y1206257D01*
X507770Y1206007D01*
X507895Y1205715D01*
Y1204674D01*
G01Y1205715D02*
X509103Y1206340D01*
G01X507020Y1207815D02*
X506770Y1208065D01*
X506645Y1208357D01*
X506603Y1208690D01*
X506686Y1209107D01*
X506895Y1209399D01*
X507145Y1209482D01*
X507395Y1209440D01*
X507603Y1209274D01*
X508020Y1208440D01*
X508311Y1208065D01*
X508728Y1207815D01*
X509103Y1207732D01*
Y1209482D01*
G01X508728Y1210790D02*
X508936Y1211040D01*
X509061Y1211332D01*
X509103Y1211707D01*
X509020Y1212082D01*
X508853Y1212374D01*
X508561Y1212582D01*
X508228Y1212624D01*
X507895Y1212540D01*
X507686Y1212332D01*
X507520Y1212040D01*
X507478Y1211749D01*
X507520Y1211457D01*
X507686Y1211082D01*
X506603Y1211207D01*
Y1212332D01*
G01X509103Y1215307D02*
X506603D01*
X508395Y1213765D01*
Y1215849D01*
G01X462708Y1196817D02*
X462583Y1196567D01*
X462500Y1196275D01*
Y1195942D01*
X462625Y1195567D01*
X462833Y1195275D01*
X463083Y1195067D01*
X463500Y1194900D01*
X463875Y1194858D01*
X464250Y1194942D01*
X464500Y1195067D01*
X464750Y1195317D01*
X464917Y1195608D01*
X465000Y1195900D01*
Y1196192D01*
X464917Y1196483D01*
X464792Y1196733D01*
X464625Y1196942D01*
G01X465000Y1199000D02*
X464958Y1199292D01*
X464833Y1199625D01*
X464625Y1199833D01*
X464333Y1199917D01*
X464042Y1199833D01*
X463792Y1199583D01*
X463667Y1199208D01*
Y1198792D01*
X463583Y1198542D01*
X463375Y1198333D01*
X463083Y1198250D01*
X462792Y1198375D01*
X462583Y1198667D01*
X462500Y1199000D01*
X462583Y1199333D01*
X462792Y1199625D01*
X463083Y1199750D01*
X463375Y1199667D01*
X463583Y1199458D01*
X463667Y1199208D01*
Y1198792D01*
X463792Y1198417D01*
X464042Y1198167D01*
X464333Y1198083D01*
X464625Y1198167D01*
X464833Y1198375D01*
X464958Y1198708D01*
X465000Y1199000D01*
G01X463958Y1201308D02*
X463667Y1201600D01*
X463500Y1201850D01*
X463417Y1202183D01*
X463500Y1202475D01*
X463667Y1202683D01*
X463917Y1202850D01*
X464208Y1202892D01*
X464458Y1202850D01*
X464708Y1202683D01*
X464917Y1202433D01*
X465000Y1202142D01*
X464917Y1201808D01*
X464667Y1201517D01*
X464292Y1201350D01*
X463875Y1201308D01*
X463333Y1201392D01*
X463042Y1201517D01*
X462750Y1201725D01*
X462542Y1202017D01*
X462500Y1202308D01*
X462583Y1202600D01*
X462792Y1202808D01*
G01X484115Y1235448D02*
Y1237948D01*
G01X485865D02*
Y1235448D01*
G01Y1236698D02*
X484115D01*
G01X487173Y1235448D02*
Y1237948D01*
X488007D01*
X488340Y1237823D01*
X488590Y1237656D01*
X488798Y1237406D01*
X488965Y1237115D01*
X489007Y1236698D01*
X488965Y1236281D01*
X488798Y1235990D01*
X488590Y1235740D01*
X488340Y1235573D01*
X488007Y1235448D01*
X487173D01*
G01X490273D02*
Y1237948D01*
X491107D01*
X491440Y1237823D01*
X491690Y1237656D01*
X491898Y1237406D01*
X492065Y1237115D01*
X492107Y1236698D01*
X492065Y1236281D01*
X491898Y1235990D01*
X491690Y1235740D01*
X491440Y1235573D01*
X491107Y1235448D01*
X490273D01*
G01X493415Y1235781D02*
X493748Y1235573D01*
X494123Y1235448D01*
X494457D01*
X494790Y1235573D01*
X495040Y1235781D01*
X495165Y1236073D01*
X495082Y1236365D01*
X494873Y1236615D01*
X494498Y1236781D01*
X493998Y1236865D01*
X493707Y1237031D01*
X493582Y1237323D01*
X493665Y1237615D01*
X493873Y1237823D01*
X494165Y1237948D01*
X494457D01*
X494748Y1237865D01*
X494998Y1237656D01*
G01X496348Y1235448D02*
X497390Y1237948D01*
X498432Y1235448D01*
G01X498057Y1236323D02*
X496723D01*
G01X499615Y1235781D02*
X499948Y1235573D01*
X500323Y1235448D01*
X500657D01*
X500990Y1235573D01*
X501240Y1235781D01*
X501365Y1236073D01*
X501282Y1236365D01*
X501073Y1236615D01*
X500698Y1236781D01*
X500198Y1236865D01*
X499907Y1237031D01*
X499782Y1237323D01*
X499865Y1237615D01*
X500073Y1237823D01*
X500365Y1237948D01*
X500657D01*
X500948Y1237865D01*
X501198Y1237656D01*
G01X502673Y1235948D02*
X502923Y1235656D01*
X503257Y1235490D01*
X503632Y1235448D01*
X503965Y1235490D01*
X504298Y1235698D01*
X504507Y1235948D01*
X504548Y1236198D01*
X504465Y1236490D01*
X504173Y1236698D01*
X503882Y1236781D01*
X503507D01*
G01X503882D02*
X504132Y1236906D01*
X504340Y1237115D01*
X504423Y1237365D01*
X504340Y1237615D01*
X504132Y1237823D01*
X503757Y1237948D01*
X503382Y1237906D01*
X503007Y1237740D01*
G01X511213Y166684D02*
X510963Y166809D01*
X510671Y166892D01*
X510338D01*
X509963Y166767D01*
X509671Y166559D01*
X509463Y166309D01*
X509296Y165892D01*
X509254Y165517D01*
X509338Y165142D01*
X509463Y164892D01*
X509713Y164642D01*
X510004Y164475D01*
X510296Y164392D01*
X510588D01*
X510879Y164475D01*
X511129Y164600D01*
X511338Y164767D01*
G01X512479Y164892D02*
X512729Y164600D01*
X513063Y164434D01*
X513438Y164392D01*
X513771Y164434D01*
X514104Y164642D01*
X514313Y164892D01*
X514354Y165142D01*
X514271Y165434D01*
X513979Y165642D01*
X513688Y165725D01*
X513313D01*
G01X513688D02*
X513938Y165850D01*
X514146Y166059D01*
X514229Y166309D01*
X514146Y166559D01*
X513938Y166767D01*
X513563Y166892D01*
X513188Y166850D01*
X512813Y166684D01*
G01X515788Y164684D02*
X516079Y164475D01*
X516413Y164392D01*
X516746Y164475D01*
X517038Y164725D01*
X517246Y165100D01*
X517329Y165475D01*
Y165934D01*
X517246Y166309D01*
X517038Y166642D01*
X516788Y166809D01*
X516496Y166892D01*
X516163Y166809D01*
X515913Y166642D01*
X515746Y166392D01*
X515663Y166059D01*
X515746Y165767D01*
X515954Y165475D01*
X516204Y165309D01*
X516496Y165267D01*
X516829Y165350D01*
X517079Y165559D01*
X517329Y165934D01*
G01X519596Y166892D02*
X519263Y166809D01*
X519013Y166600D01*
X518846Y166350D01*
X518721Y166017D01*
X518679Y165642D01*
X518721Y165267D01*
X518846Y164934D01*
X519013Y164684D01*
X519263Y164475D01*
X519596Y164392D01*
X519929Y164475D01*
X520179Y164684D01*
X520346Y164934D01*
X520471Y165267D01*
X520513Y165642D01*
X520471Y166017D01*
X520346Y166350D01*
X520179Y166600D01*
X519929Y166809D01*
X519596Y166892D01*
G01X553500Y183017D02*
X551000D01*
Y184058D01*
X551125Y184392D01*
X551292Y184600D01*
X551625Y184683D01*
X551958Y184600D01*
X552167Y184350D01*
X552292Y184058D01*
Y183017D01*
G01Y184058D02*
X553500Y184683D01*
G01Y186867D02*
X552958Y186950D01*
X552500Y187075D01*
X552083Y187242D01*
X551625Y187450D01*
X551000Y187783D01*
Y186117D01*
G01X553208Y189342D02*
X553417Y189633D01*
X553500Y189967D01*
X553417Y190300D01*
X553167Y190592D01*
X552792Y190800D01*
X552417Y190883D01*
X551958D01*
X551583Y190800D01*
X551250Y190592D01*
X551083Y190342D01*
X551000Y190050D01*
X551083Y189717D01*
X551250Y189467D01*
X551500Y189300D01*
X551833Y189217D01*
X552125Y189300D01*
X552417Y189508D01*
X552583Y189758D01*
X552625Y190050D01*
X552542Y190383D01*
X552333Y190633D01*
X551958Y190883D01*
G01X551000Y193150D02*
X551083Y192817D01*
X551292Y192567D01*
X551542Y192400D01*
X551875Y192275D01*
X552250Y192233D01*
X552625Y192275D01*
X552958Y192400D01*
X553208Y192567D01*
X553417Y192817D01*
X553500Y193150D01*
X553417Y193483D01*
X553208Y193733D01*
X552958Y193900D01*
X552625Y194025D01*
X552250Y194067D01*
X551875Y194025D01*
X551542Y193900D01*
X551292Y193733D01*
X551083Y193483D01*
X551000Y193150D01*
G01X554787Y181961D02*
X558787D01*
Y189361D01*
G01X546817Y173400D02*
Y175900D01*
X547858D01*
X548192Y175775D01*
X548400Y175608D01*
X548483Y175275D01*
X548400Y174942D01*
X548150Y174733D01*
X547858Y174608D01*
X546817D01*
G01X547858D02*
X548483Y173400D01*
G01X550667D02*
X550750Y173942D01*
X550875Y174400D01*
X551042Y174817D01*
X551250Y175275D01*
X551583Y175900D01*
X549917D01*
G01X553850Y173400D02*
X554142Y173442D01*
X554475Y173567D01*
X554683Y173775D01*
X554767Y174067D01*
X554683Y174358D01*
X554433Y174608D01*
X554058Y174733D01*
X553642D01*
X553392Y174817D01*
X553183Y175025D01*
X553100Y175317D01*
X553225Y175608D01*
X553517Y175817D01*
X553850Y175900D01*
X554183Y175817D01*
X554475Y175608D01*
X554600Y175317D01*
X554517Y175025D01*
X554308Y174817D01*
X554058Y174733D01*
X553642D01*
X553267Y174608D01*
X553017Y174358D01*
X552933Y174067D01*
X553017Y173775D01*
X553225Y173567D01*
X553558Y173442D01*
X553850Y173400D01*
G01X556950D02*
X557242Y173442D01*
X557575Y173567D01*
X557783Y173775D01*
X557867Y174067D01*
X557783Y174358D01*
X557533Y174608D01*
X557158Y174733D01*
X556742D01*
X556492Y174817D01*
X556283Y175025D01*
X556200Y175317D01*
X556325Y175608D01*
X556617Y175817D01*
X556950Y175900D01*
X557283Y175817D01*
X557575Y175608D01*
X557700Y175317D01*
X557617Y175025D01*
X557408Y174817D01*
X557158Y174733D01*
X556742D01*
X556367Y174608D01*
X556117Y174358D01*
X556033Y174067D01*
X556117Y173775D01*
X556325Y173567D01*
X556658Y173442D01*
X556950Y173400D01*
G01X551387Y181561D02*
Y177561D01*
X558787D01*
G01X539304Y209661D02*
Y212161D01*
X540345D01*
X540679Y212036D01*
X540887Y211869D01*
X540970Y211536D01*
X540887Y211203D01*
X540637Y210994D01*
X540345Y210869D01*
X539304D01*
G01X540345D02*
X540970Y209661D01*
G01X543154D02*
X543237Y210203D01*
X543362Y210661D01*
X543529Y211078D01*
X543737Y211536D01*
X544070Y212161D01*
X542404D01*
G01X546337Y209661D02*
X546629Y209703D01*
X546962Y209828D01*
X547170Y210036D01*
X547254Y210328D01*
X547170Y210619D01*
X546920Y210869D01*
X546545Y210994D01*
X546129D01*
X545879Y211078D01*
X545670Y211286D01*
X545587Y211578D01*
X545712Y211869D01*
X546004Y212078D01*
X546337Y212161D01*
X546670Y212078D01*
X546962Y211869D01*
X547087Y211578D01*
X547004Y211286D01*
X546795Y211078D01*
X546545Y210994D01*
X546129D01*
X545754Y210869D01*
X545504Y210619D01*
X545420Y210328D01*
X545504Y210036D01*
X545712Y209828D01*
X546045Y209703D01*
X546337Y209661D01*
G01X548729Y209953D02*
X549020Y209744D01*
X549354Y209661D01*
X549687Y209744D01*
X549979Y209994D01*
X550187Y210369D01*
X550270Y210744D01*
Y211203D01*
X550187Y211578D01*
X549979Y211911D01*
X549729Y212078D01*
X549437Y212161D01*
X549104Y212078D01*
X548854Y211911D01*
X548687Y211661D01*
X548604Y211328D01*
X548687Y211036D01*
X548895Y210744D01*
X549145Y210578D01*
X549437Y210536D01*
X549770Y210619D01*
X550020Y210828D01*
X550270Y211203D01*
G01X546704Y200361D02*
Y202861D01*
X547745D01*
X548079Y202736D01*
X548287Y202569D01*
X548370Y202236D01*
X548287Y201903D01*
X548037Y201694D01*
X547745Y201569D01*
X546704D01*
G01X547745D02*
X548370Y200361D01*
G01X550554D02*
X550637Y200903D01*
X550762Y201361D01*
X550929Y201778D01*
X551137Y202236D01*
X551470Y202861D01*
X549804D01*
G01X553737Y200361D02*
X554029Y200403D01*
X554362Y200528D01*
X554570Y200736D01*
X554654Y201028D01*
X554570Y201319D01*
X554320Y201569D01*
X553945Y201694D01*
X553529D01*
X553279Y201778D01*
X553070Y201986D01*
X552987Y202278D01*
X553112Y202569D01*
X553404Y202778D01*
X553737Y202861D01*
X554070Y202778D01*
X554362Y202569D01*
X554487Y202278D01*
X554404Y201986D01*
X554195Y201778D01*
X553945Y201694D01*
X553529D01*
X553154Y201569D01*
X552904Y201319D01*
X552820Y201028D01*
X552904Y200736D01*
X553112Y200528D01*
X553445Y200403D01*
X553737Y200361D01*
G01X556837D02*
Y202861D01*
X556337Y202361D01*
G01Y200361D02*
X557337D01*
G01X511267Y170292D02*
X511017Y170417D01*
X510725Y170500D01*
X510392D01*
X510017Y170375D01*
X509725Y170167D01*
X509517Y169917D01*
X509350Y169500D01*
X509308Y169125D01*
X509392Y168750D01*
X509517Y168500D01*
X509767Y168250D01*
X510058Y168083D01*
X510350Y168000D01*
X510642D01*
X510933Y168083D01*
X511183Y168208D01*
X511392Y168375D01*
G01X512533Y168500D02*
X512783Y168208D01*
X513117Y168042D01*
X513492Y168000D01*
X513825Y168042D01*
X514158Y168250D01*
X514367Y168500D01*
X514408Y168750D01*
X514325Y169042D01*
X514033Y169250D01*
X513742Y169333D01*
X513367D01*
G01X513742D02*
X513992Y169458D01*
X514200Y169667D01*
X514283Y169917D01*
X514200Y170167D01*
X513992Y170375D01*
X513617Y170500D01*
X513242Y170458D01*
X512867Y170292D01*
G01X516550Y168000D02*
X516842Y168042D01*
X517175Y168167D01*
X517383Y168375D01*
X517467Y168667D01*
X517383Y168958D01*
X517133Y169208D01*
X516758Y169333D01*
X516342D01*
X516092Y169417D01*
X515883Y169625D01*
X515800Y169917D01*
X515925Y170208D01*
X516217Y170417D01*
X516550Y170500D01*
X516883Y170417D01*
X517175Y170208D01*
X517300Y169917D01*
X517217Y169625D01*
X517008Y169417D01*
X516758Y169333D01*
X516342D01*
X515967Y169208D01*
X515717Y168958D01*
X515633Y168667D01*
X515717Y168375D01*
X515925Y168167D01*
X516258Y168042D01*
X516550Y168000D01*
G01X518942Y168292D02*
X519233Y168083D01*
X519567Y168000D01*
X519900Y168083D01*
X520192Y168333D01*
X520400Y168708D01*
X520483Y169083D01*
Y169542D01*
X520400Y169917D01*
X520192Y170250D01*
X519942Y170417D01*
X519650Y170500D01*
X519317Y170417D01*
X519067Y170250D01*
X518900Y170000D01*
X518817Y169667D01*
X518900Y169375D01*
X519108Y169083D01*
X519358Y168917D01*
X519650Y168875D01*
X519983Y168958D01*
X520233Y169167D01*
X520483Y169542D01*
G01X548454Y206953D02*
X548204Y207078D01*
X547912Y207161D01*
X547579D01*
X547204Y207036D01*
X546912Y206828D01*
X546704Y206578D01*
X546537Y206161D01*
X546495Y205786D01*
X546579Y205411D01*
X546704Y205161D01*
X546954Y204911D01*
X547245Y204744D01*
X547537Y204661D01*
X547829D01*
X548120Y204744D01*
X548370Y204869D01*
X548579Y205036D01*
G01X551137Y204661D02*
Y207161D01*
X549595Y205369D01*
X551679D01*
G01X553737Y204661D02*
Y207161D01*
X553237Y206661D01*
G01Y204661D02*
X554237D01*
G01X556045Y206744D02*
X556295Y206994D01*
X556587Y207119D01*
X556920Y207161D01*
X557337Y207078D01*
X557629Y206869D01*
X557712Y206619D01*
X557670Y206369D01*
X557504Y206161D01*
X556670Y205744D01*
X556295Y205453D01*
X556045Y205036D01*
X555962Y204661D01*
X557712D01*
G01X508591Y234661D02*
Y237161D01*
X509632D01*
X509966Y237036D01*
X510174Y236869D01*
X510257Y236536D01*
X510174Y236203D01*
X509924Y235994D01*
X509632Y235869D01*
X508591D01*
G01X509632D02*
X510257Y234661D01*
G01X512441D02*
X512524Y235203D01*
X512649Y235661D01*
X512816Y236078D01*
X513024Y236536D01*
X513357Y237161D01*
X511691D01*
G01X514707Y235036D02*
X514957Y234828D01*
X515249Y234703D01*
X515624Y234661D01*
X515999Y234744D01*
X516291Y234911D01*
X516499Y235203D01*
X516541Y235536D01*
X516457Y235869D01*
X516249Y236078D01*
X515957Y236244D01*
X515666Y236286D01*
X515374Y236244D01*
X514999Y236078D01*
X515124Y237161D01*
X516249D01*
G01X518724Y234661D02*
Y237161D01*
X518224Y236661D01*
G01Y234661D02*
X519224D01*
G01X517274Y242661D02*
Y246661D01*
X509874D01*
G01X558987Y208661D02*
Y212661D01*
X551587D01*
G01X542500Y222350D02*
X542458Y222017D01*
X542292Y221725D01*
X542042Y221475D01*
X541750Y221308D01*
X541417Y221225D01*
X541083D01*
X540750Y221308D01*
X540458Y221475D01*
X540208Y221725D01*
X540042Y222017D01*
X540000Y222350D01*
X540042Y222683D01*
X540208Y222975D01*
X540458Y223225D01*
X540750Y223392D01*
X541083Y223475D01*
X541417D01*
X541750Y223392D01*
X542042Y223225D01*
X542292Y222975D01*
X542458Y222683D01*
X542500Y222350D01*
G01X541833Y222683D02*
X542500Y223183D01*
G01Y225450D02*
X540000D01*
X540500Y224950D01*
G01X542500D02*
Y225950D01*
G01Y228467D02*
X541958Y228550D01*
X541500Y228675D01*
X541083Y228842D01*
X540625Y229050D01*
X540000Y229383D01*
Y227717D01*
G01Y231650D02*
X540083Y231317D01*
X540292Y231067D01*
X540542Y230900D01*
X540875Y230775D01*
X541250Y230733D01*
X541625Y230775D01*
X541958Y230900D01*
X542208Y231067D01*
X542417Y231317D01*
X542500Y231650D01*
X542417Y231983D01*
X542208Y232233D01*
X541958Y232400D01*
X541625Y232525D01*
X541250Y232567D01*
X540875Y232525D01*
X540542Y232400D01*
X540292Y232233D01*
X540083Y231983D01*
X540000Y231650D01*
G01X544587Y237661D02*
X546687Y235861D01*
X544587Y233661D01*
G01X544487Y230061D02*
X563687D01*
Y241261D01*
X544487D01*
Y230061D01*
X544887D01*
G01X510341Y232953D02*
X510091Y233078D01*
X509799Y233161D01*
X509466D01*
X509091Y233036D01*
X508799Y232828D01*
X508591Y232578D01*
X508424Y232161D01*
X508382Y231786D01*
X508466Y231411D01*
X508591Y231161D01*
X508841Y230911D01*
X509132Y230744D01*
X509424Y230661D01*
X509716D01*
X510007Y230744D01*
X510257Y230869D01*
X510466Y231036D01*
G01X511607Y231161D02*
X511857Y230869D01*
X512191Y230703D01*
X512566Y230661D01*
X512899Y230703D01*
X513232Y230911D01*
X513441Y231161D01*
X513482Y231411D01*
X513399Y231703D01*
X513107Y231911D01*
X512816Y231994D01*
X512441D01*
G01X512816D02*
X513066Y232119D01*
X513274Y232328D01*
X513357Y232578D01*
X513274Y232828D01*
X513066Y233036D01*
X512691Y233161D01*
X512316Y233119D01*
X511941Y232953D01*
G01X514916Y230953D02*
X515207Y230744D01*
X515541Y230661D01*
X515874Y230744D01*
X516166Y230994D01*
X516374Y231369D01*
X516457Y231744D01*
Y232203D01*
X516374Y232578D01*
X516166Y232911D01*
X515916Y233078D01*
X515624Y233161D01*
X515291Y233078D01*
X515041Y232911D01*
X514874Y232661D01*
X514791Y232328D01*
X514874Y232036D01*
X515082Y231744D01*
X515332Y231578D01*
X515624Y231536D01*
X515957Y231619D01*
X516207Y231828D01*
X516457Y232203D01*
G01X517932Y231703D02*
X518224Y231994D01*
X518474Y232161D01*
X518807Y232244D01*
X519099Y232161D01*
X519307Y231994D01*
X519474Y231744D01*
X519516Y231453D01*
X519474Y231203D01*
X519307Y230953D01*
X519057Y230744D01*
X518766Y230661D01*
X518432Y230744D01*
X518141Y230994D01*
X517974Y231369D01*
X517932Y231786D01*
X518016Y232328D01*
X518141Y232619D01*
X518349Y232911D01*
X518641Y233119D01*
X518932Y233161D01*
X519224Y233078D01*
X519432Y232869D01*
G01X541054Y215953D02*
X540804Y216078D01*
X540512Y216161D01*
X540179D01*
X539804Y216036D01*
X539512Y215828D01*
X539304Y215578D01*
X539137Y215161D01*
X539095Y214786D01*
X539179Y214411D01*
X539304Y214161D01*
X539554Y213911D01*
X539845Y213744D01*
X540137Y213661D01*
X540429D01*
X540720Y213744D01*
X540970Y213869D01*
X541179Y214036D01*
G01X543737Y213661D02*
Y216161D01*
X542195Y214369D01*
X544279D01*
G01X546337Y213661D02*
Y216161D01*
X545837Y215661D01*
G01Y213661D02*
X546837D01*
G01X548520Y214161D02*
X548770Y213869D01*
X549104Y213703D01*
X549479Y213661D01*
X549812Y213703D01*
X550145Y213911D01*
X550354Y214161D01*
X550395Y214411D01*
X550312Y214703D01*
X550020Y214911D01*
X549729Y214994D01*
X549354D01*
G01X549729D02*
X549979Y215119D01*
X550187Y215328D01*
X550270Y215578D01*
X550187Y215828D01*
X549979Y216036D01*
X549604Y216161D01*
X549229Y216119D01*
X548854Y215953D01*
G01X554167Y265692D02*
X553917Y265817D01*
X553625Y265900D01*
X553292D01*
X552917Y265775D01*
X552625Y265567D01*
X552417Y265317D01*
X552250Y264900D01*
X552208Y264525D01*
X552292Y264150D01*
X552417Y263900D01*
X552667Y263650D01*
X552958Y263483D01*
X553250Y263400D01*
X553542D01*
X553833Y263483D01*
X554083Y263608D01*
X554292Y263775D01*
G01X556850Y263400D02*
Y265900D01*
X555308Y264108D01*
X557392D01*
G01X559450Y265900D02*
X559117Y265817D01*
X558867Y265608D01*
X558700Y265358D01*
X558575Y265025D01*
X558533Y264650D01*
X558575Y264275D01*
X558700Y263942D01*
X558867Y263692D01*
X559117Y263483D01*
X559450Y263400D01*
X559783Y263483D01*
X560033Y263692D01*
X560200Y263942D01*
X560325Y264275D01*
X560367Y264650D01*
X560325Y265025D01*
X560200Y265358D01*
X560033Y265608D01*
X559783Y265817D01*
X559450Y265900D01*
G01X562550Y263400D02*
X562842Y263442D01*
X563175Y263567D01*
X563383Y263775D01*
X563467Y264067D01*
X563383Y264358D01*
X563133Y264608D01*
X562758Y264733D01*
X562342D01*
X562092Y264817D01*
X561883Y265025D01*
X561800Y265317D01*
X561925Y265608D01*
X562217Y265817D01*
X562550Y265900D01*
X562883Y265817D01*
X563175Y265608D01*
X563300Y265317D01*
X563217Y265025D01*
X563008Y264817D01*
X562758Y264733D01*
X562342D01*
X561967Y264608D01*
X561717Y264358D01*
X561633Y264067D01*
X561717Y263775D01*
X561925Y263567D01*
X562258Y263442D01*
X562550Y263400D01*
G01X517121Y496142D02*
Y510142D01*
G01X518706Y482105D02*
X518373Y482147D01*
X518081Y482313D01*
X517831Y482563D01*
X517664Y482855D01*
X517581Y483188D01*
Y483522D01*
X517664Y483855D01*
X517831Y484147D01*
X518081Y484397D01*
X518373Y484563D01*
X518706Y484605D01*
X519039Y484563D01*
X519331Y484397D01*
X519581Y484147D01*
X519748Y483855D01*
X519831Y483522D01*
Y483188D01*
X519748Y482855D01*
X519581Y482563D01*
X519331Y482313D01*
X519039Y482147D01*
X518706Y482105D01*
G01X519039Y482772D02*
X519539Y482105D01*
G01X521014Y484188D02*
X521264Y484438D01*
X521556Y484563D01*
X521889Y484605D01*
X522306Y484522D01*
X522598Y484313D01*
X522681Y484063D01*
X522639Y483813D01*
X522473Y483605D01*
X521639Y483188D01*
X521264Y482897D01*
X521014Y482480D01*
X520931Y482105D01*
X522681D01*
G01X525406D02*
Y484605D01*
X523864Y482813D01*
X525948D01*
G01X527089Y482605D02*
X527339Y482313D01*
X527673Y482147D01*
X528048Y482105D01*
X528381Y482147D01*
X528714Y482355D01*
X528923Y482605D01*
X528964Y482855D01*
X528881Y483147D01*
X528589Y483355D01*
X528298Y483438D01*
X527923D01*
G01X528298D02*
X528548Y483563D01*
X528756Y483772D01*
X528839Y484022D01*
X528756Y484272D01*
X528548Y484480D01*
X528173Y484605D01*
X527798Y484563D01*
X527423Y484397D01*
G01X531356Y496105D02*
Y510105D01*
G01X518356Y496105D02*
X531356D01*
G01X518356Y510105D02*
Y496105D01*
G01X540350Y473017D02*
X537850D01*
Y474058D01*
X537975Y474392D01*
X538142Y474600D01*
X538475Y474683D01*
X538808Y474600D01*
X539017Y474350D01*
X539142Y474058D01*
Y473017D01*
G01Y474058D02*
X540350Y474683D01*
G01X539850Y476033D02*
X540142Y476283D01*
X540308Y476617D01*
X540350Y476992D01*
X540308Y477325D01*
X540100Y477658D01*
X539850Y477867D01*
X539600Y477908D01*
X539308Y477825D01*
X539100Y477533D01*
X539017Y477242D01*
Y476867D01*
G01Y477242D02*
X538892Y477492D01*
X538683Y477700D01*
X538433Y477783D01*
X538183Y477700D01*
X537975Y477492D01*
X537850Y477117D01*
X537892Y476742D01*
X538058Y476367D01*
G01X537850Y480050D02*
X537933Y479717D01*
X538142Y479467D01*
X538392Y479300D01*
X538725Y479175D01*
X539100Y479133D01*
X539475Y479175D01*
X539808Y479300D01*
X540058Y479467D01*
X540267Y479717D01*
X540350Y480050D01*
X540267Y480383D01*
X540058Y480633D01*
X539808Y480800D01*
X539475Y480925D01*
X539100Y480967D01*
X538725Y480925D01*
X538392Y480800D01*
X538142Y480633D01*
X537933Y480383D01*
X537850Y480050D01*
G01X540058Y482442D02*
X540267Y482733D01*
X540350Y483067D01*
X540267Y483400D01*
X540017Y483692D01*
X539642Y483900D01*
X539267Y483983D01*
X538808D01*
X538433Y483900D01*
X538100Y483692D01*
X537933Y483442D01*
X537850Y483150D01*
X537933Y482817D01*
X538100Y482567D01*
X538350Y482400D01*
X538683Y482317D01*
X538975Y482400D01*
X539267Y482608D01*
X539433Y482858D01*
X539475Y483150D01*
X539392Y483483D01*
X539183Y483733D01*
X538808Y483983D01*
G01X535350Y473017D02*
X532850D01*
Y474058D01*
X532975Y474392D01*
X533142Y474600D01*
X533475Y474683D01*
X533808Y474600D01*
X534017Y474350D01*
X534142Y474058D01*
Y473017D01*
G01Y474058D02*
X535350Y474683D01*
G01X534850Y476033D02*
X535142Y476283D01*
X535308Y476617D01*
X535350Y476992D01*
X535308Y477325D01*
X535100Y477658D01*
X534850Y477867D01*
X534600Y477908D01*
X534308Y477825D01*
X534100Y477533D01*
X534017Y477242D01*
Y476867D01*
G01Y477242D02*
X533892Y477492D01*
X533683Y477700D01*
X533433Y477783D01*
X533183Y477700D01*
X532975Y477492D01*
X532850Y477117D01*
X532892Y476742D01*
X533058Y476367D01*
G01X532850Y480050D02*
X532933Y479717D01*
X533142Y479467D01*
X533392Y479300D01*
X533725Y479175D01*
X534100Y479133D01*
X534475Y479175D01*
X534808Y479300D01*
X535058Y479467D01*
X535267Y479717D01*
X535350Y480050D01*
X535267Y480383D01*
X535058Y480633D01*
X534808Y480800D01*
X534475Y480925D01*
X534100Y480967D01*
X533725Y480925D01*
X533392Y480800D01*
X533142Y480633D01*
X532933Y480383D01*
X532850Y480050D01*
G01Y483150D02*
X532933Y482817D01*
X533142Y482567D01*
X533392Y482400D01*
X533725Y482275D01*
X534100Y482233D01*
X534475Y482275D01*
X534808Y482400D01*
X535058Y482567D01*
X535267Y482817D01*
X535350Y483150D01*
X535267Y483483D01*
X535058Y483733D01*
X534808Y483900D01*
X534475Y484025D01*
X534100Y484067D01*
X533725Y484025D01*
X533392Y483900D01*
X533142Y483733D01*
X532933Y483483D01*
X532850Y483150D01*
G01X515517Y526167D02*
Y528667D01*
X516558D01*
X516892Y528542D01*
X517100Y528375D01*
X517183Y528042D01*
X517100Y527709D01*
X516850Y527500D01*
X516558Y527375D01*
X515517D01*
G01X516558D02*
X517183Y526167D01*
G01X519450D02*
Y528667D01*
X518950Y528167D01*
G01Y526167D02*
X519950D01*
G01X522550Y528667D02*
X522217Y528584D01*
X521967Y528375D01*
X521800Y528125D01*
X521675Y527792D01*
X521633Y527417D01*
X521675Y527042D01*
X521800Y526709D01*
X521967Y526459D01*
X522217Y526250D01*
X522550Y526167D01*
X522883Y526250D01*
X523133Y526459D01*
X523300Y526709D01*
X523425Y527042D01*
X523467Y527417D01*
X523425Y527792D01*
X523300Y528125D01*
X523133Y528375D01*
X522883Y528584D01*
X522550Y528667D01*
G01X526150Y526167D02*
Y528667D01*
X524608Y526875D01*
X526692D01*
G01X527958Y528250D02*
X528208Y528500D01*
X528500Y528625D01*
X528833Y528667D01*
X529250Y528584D01*
X529542Y528375D01*
X529625Y528125D01*
X529583Y527875D01*
X529417Y527667D01*
X528583Y527250D01*
X528208Y526959D01*
X527958Y526542D01*
X527875Y526167D01*
X529625D01*
G01X547079Y526531D02*
Y530531D01*
X539679D01*
G01X515346Y529831D02*
Y532331D01*
X516387D01*
X516721Y532206D01*
X516929Y532039D01*
X517012Y531706D01*
X516929Y531373D01*
X516679Y531164D01*
X516387Y531039D01*
X515346D01*
G01X516387D02*
X517012Y529831D01*
G01X519279D02*
Y532331D01*
X518779Y531831D01*
G01Y529831D02*
X519779D01*
G01X522379Y532331D02*
X522046Y532248D01*
X521796Y532039D01*
X521629Y531789D01*
X521504Y531456D01*
X521462Y531081D01*
X521504Y530706D01*
X521629Y530373D01*
X521796Y530123D01*
X522046Y529914D01*
X522379Y529831D01*
X522712Y529914D01*
X522962Y530123D01*
X523129Y530373D01*
X523254Y530706D01*
X523296Y531081D01*
X523254Y531456D01*
X523129Y531789D01*
X522962Y532039D01*
X522712Y532248D01*
X522379Y532331D01*
G01X525979Y529831D02*
Y532331D01*
X524437Y530539D01*
X526521D01*
G01X527662Y530331D02*
X527912Y530039D01*
X528246Y529873D01*
X528621Y529831D01*
X528954Y529873D01*
X529287Y530081D01*
X529496Y530331D01*
X529537Y530581D01*
X529454Y530873D01*
X529162Y531081D01*
X528871Y531164D01*
X528496D01*
G01X528871D02*
X529121Y531289D01*
X529329Y531498D01*
X529412Y531748D01*
X529329Y531998D01*
X529121Y532206D01*
X528746Y532331D01*
X528371Y532289D01*
X527996Y532123D01*
G01X547079Y530831D02*
Y534831D01*
X539679D01*
G01X538279Y511298D02*
X535779D01*
Y512339D01*
X535904Y512673D01*
X536071Y512881D01*
X536404Y512964D01*
X536737Y512881D01*
X536946Y512631D01*
X537071Y512339D01*
Y511298D01*
G01Y512339D02*
X538279Y512964D01*
G01Y515231D02*
X535779D01*
X536279Y514731D01*
G01X538279D02*
Y515731D01*
G01X535779Y518331D02*
X535862Y517998D01*
X536071Y517748D01*
X536321Y517581D01*
X536654Y517456D01*
X537029Y517414D01*
X537404Y517456D01*
X537737Y517581D01*
X537987Y517748D01*
X538196Y517998D01*
X538279Y518331D01*
X538196Y518664D01*
X537987Y518914D01*
X537737Y519081D01*
X537404Y519206D01*
X537029Y519248D01*
X536654Y519206D01*
X536321Y519081D01*
X536071Y518914D01*
X535862Y518664D01*
X535779Y518331D01*
G01X538279Y521931D02*
X535779D01*
X537571Y520389D01*
Y522473D01*
G01X537904Y523614D02*
X538112Y523864D01*
X538237Y524156D01*
X538279Y524531D01*
X538196Y524906D01*
X538029Y525198D01*
X537737Y525406D01*
X537404Y525448D01*
X537071Y525364D01*
X536862Y525156D01*
X536696Y524864D01*
X536654Y524573D01*
X536696Y524281D01*
X536862Y523906D01*
X535779Y524031D01*
Y525156D01*
G01X547279Y514631D02*
X551279D01*
Y522031D01*
G01X542279Y511298D02*
X539779D01*
Y512339D01*
X539904Y512673D01*
X540071Y512881D01*
X540404Y512964D01*
X540737Y512881D01*
X540946Y512631D01*
X541071Y512339D01*
Y511298D01*
G01Y512339D02*
X542279Y512964D01*
G01Y515231D02*
X539779D01*
X540279Y514731D01*
G01X542279D02*
Y515731D01*
G01X539779Y518331D02*
X539862Y517998D01*
X540071Y517748D01*
X540321Y517581D01*
X540654Y517456D01*
X541029Y517414D01*
X541404Y517456D01*
X541737Y517581D01*
X541987Y517748D01*
X542196Y517998D01*
X542279Y518331D01*
X542196Y518664D01*
X541987Y518914D01*
X541737Y519081D01*
X541404Y519206D01*
X541029Y519248D01*
X540654Y519206D01*
X540321Y519081D01*
X540071Y518914D01*
X539862Y518664D01*
X539779Y518331D01*
G01X541904Y520514D02*
X542112Y520764D01*
X542237Y521056D01*
X542279Y521431D01*
X542196Y521806D01*
X542029Y522098D01*
X541737Y522306D01*
X541404Y522348D01*
X541071Y522264D01*
X540862Y522056D01*
X540696Y521764D01*
X540654Y521473D01*
X540696Y521181D01*
X540862Y520806D01*
X539779Y520931D01*
Y522056D01*
G01X542279Y524531D02*
X539779D01*
X540279Y524031D01*
G01X542279D02*
Y525031D01*
G01X551279Y514631D02*
X555279D01*
Y522031D01*
G01X546279Y511298D02*
X543779D01*
Y512339D01*
X543904Y512673D01*
X544071Y512881D01*
X544404Y512964D01*
X544737Y512881D01*
X544946Y512631D01*
X545071Y512339D01*
Y511298D01*
G01Y512339D02*
X546279Y512964D01*
G01Y515231D02*
X543779D01*
X544279Y514731D01*
G01X546279D02*
Y515731D01*
G01X543779Y518331D02*
X543862Y517998D01*
X544071Y517748D01*
X544321Y517581D01*
X544654Y517456D01*
X545029Y517414D01*
X545404Y517456D01*
X545737Y517581D01*
X545987Y517748D01*
X546196Y517998D01*
X546279Y518331D01*
X546196Y518664D01*
X545987Y518914D01*
X545737Y519081D01*
X545404Y519206D01*
X545029Y519248D01*
X544654Y519206D01*
X544321Y519081D01*
X544071Y518914D01*
X543862Y518664D01*
X543779Y518331D01*
G01X545904Y520514D02*
X546112Y520764D01*
X546237Y521056D01*
X546279Y521431D01*
X546196Y521806D01*
X546029Y522098D01*
X545737Y522306D01*
X545404Y522348D01*
X545071Y522264D01*
X544862Y522056D01*
X544696Y521764D01*
X544654Y521473D01*
X544696Y521181D01*
X544862Y520806D01*
X543779Y520931D01*
Y522056D01*
G01X545904Y523614D02*
X546112Y523864D01*
X546237Y524156D01*
X546279Y524531D01*
X546196Y524906D01*
X546029Y525198D01*
X545737Y525406D01*
X545404Y525448D01*
X545071Y525364D01*
X544862Y525156D01*
X544696Y524864D01*
X544654Y524573D01*
X544696Y524281D01*
X544862Y523906D01*
X543779Y524031D01*
Y525156D01*
G01X559279Y522031D02*
X555279D01*
Y514631D01*
G01X510500Y537467D02*
X508000D01*
Y538508D01*
X508125Y538842D01*
X508292Y539050D01*
X508625Y539133D01*
X508958Y539050D01*
X509167Y538800D01*
X509292Y538508D01*
Y537467D01*
G01Y538508D02*
X510500Y539133D01*
G01Y541400D02*
X508000D01*
X508500Y540900D01*
G01X510500D02*
Y541900D01*
G01X508000Y544500D02*
X508083Y544167D01*
X508292Y543917D01*
X508542Y543750D01*
X508875Y543625D01*
X509250Y543583D01*
X509625Y543625D01*
X509958Y543750D01*
X510208Y543917D01*
X510417Y544167D01*
X510500Y544500D01*
X510417Y544833D01*
X510208Y545083D01*
X509958Y545250D01*
X509625Y545375D01*
X509250Y545417D01*
X508875Y545375D01*
X508542Y545250D01*
X508292Y545083D01*
X508083Y544833D01*
X508000Y544500D01*
G01Y547600D02*
X508083Y547267D01*
X508292Y547017D01*
X508542Y546850D01*
X508875Y546725D01*
X509250Y546683D01*
X509625Y546725D01*
X509958Y546850D01*
X510208Y547017D01*
X510417Y547267D01*
X510500Y547600D01*
X510417Y547933D01*
X510208Y548183D01*
X509958Y548350D01*
X509625Y548475D01*
X509250Y548517D01*
X508875Y548475D01*
X508542Y548350D01*
X508292Y548183D01*
X508083Y547933D01*
X508000Y547600D01*
G01X509458Y549908D02*
X509167Y550200D01*
X509000Y550450D01*
X508917Y550783D01*
X509000Y551075D01*
X509167Y551283D01*
X509417Y551450D01*
X509708Y551492D01*
X509958Y551450D01*
X510208Y551283D01*
X510417Y551033D01*
X510500Y550742D01*
X510417Y550408D01*
X510167Y550117D01*
X509792Y549950D01*
X509375Y549908D01*
X508833Y549992D01*
X508542Y550117D01*
X508250Y550325D01*
X508042Y550617D01*
X508000Y550908D01*
X508083Y551200D01*
X508292Y551408D01*
G01X527579Y546981D02*
X523579D01*
Y539581D01*
G01X516494Y522378D02*
Y524878D01*
X517535D01*
X517869Y524753D01*
X518077Y524586D01*
X518160Y524253D01*
X518077Y523920D01*
X517827Y523711D01*
X517535Y523586D01*
X516494D01*
G01X517535D02*
X518160Y522378D01*
G01X519510Y522753D02*
X519760Y522545D01*
X520052Y522420D01*
X520427Y522378D01*
X520802Y522461D01*
X521094Y522628D01*
X521302Y522920D01*
X521344Y523253D01*
X521260Y523586D01*
X521052Y523795D01*
X520760Y523961D01*
X520469Y524003D01*
X520177Y523961D01*
X519802Y523795D01*
X519927Y524878D01*
X521052D01*
G01X523527Y522378D02*
Y524878D01*
X523027Y524378D01*
G01Y522378D02*
X524027D01*
G01X525919Y522670D02*
X526210Y522461D01*
X526544Y522378D01*
X526877Y522461D01*
X527169Y522711D01*
X527377Y523086D01*
X527460Y523461D01*
Y523920D01*
X527377Y524295D01*
X527169Y524628D01*
X526919Y524795D01*
X526627Y524878D01*
X526294Y524795D01*
X526044Y524628D01*
X525877Y524378D01*
X525794Y524045D01*
X525877Y523753D01*
X526085Y523461D01*
X526335Y523295D01*
X526627Y523253D01*
X526960Y523336D01*
X527210Y523545D01*
X527460Y523920D01*
G01X530677Y510878D02*
Y514878D01*
X523277D01*
G01X516450Y510874D02*
Y514874D01*
X509050D01*
G01X531356Y510105D02*
X518356D01*
G01X513000Y537983D02*
X514792D01*
X515167Y538150D01*
X515417Y538483D01*
X515500Y538900D01*
X515417Y539317D01*
X515167Y539650D01*
X514792Y539817D01*
X513000D01*
G01X515000Y541083D02*
X515292Y541333D01*
X515458Y541667D01*
X515500Y542042D01*
X515458Y542375D01*
X515250Y542708D01*
X515000Y542917D01*
X514750Y542958D01*
X514458Y542875D01*
X514250Y542583D01*
X514167Y542292D01*
Y541917D01*
G01Y542292D02*
X514042Y542542D01*
X513833Y542750D01*
X513583Y542833D01*
X513333Y542750D01*
X513125Y542542D01*
X513000Y542167D01*
X513042Y541792D01*
X513208Y541417D01*
G01X513417Y544308D02*
X513167Y544558D01*
X513042Y544850D01*
X513000Y545183D01*
X513083Y545600D01*
X513292Y545892D01*
X513542Y545975D01*
X513792Y545933D01*
X514000Y545767D01*
X514417Y544933D01*
X514708Y544558D01*
X515125Y544308D01*
X515500Y544225D01*
Y545975D01*
G01X546821Y539656D02*
X533421D01*
G01X546821Y549656D02*
Y539656D01*
G01X533421Y549656D02*
X546821D01*
G01X533421Y539656D02*
Y549656D01*
G01X554829Y547751D02*
X557829D01*
G01X555829Y537911D02*
X557829D01*
G01X555279Y561631D02*
X559279D01*
Y569031D01*
G01X540967Y585500D02*
Y588000D01*
X542008D01*
X542342Y587875D01*
X542550Y587708D01*
X542633Y587375D01*
X542550Y587042D01*
X542300Y586833D01*
X542008Y586708D01*
X540967D01*
G01X542008D02*
X542633Y585500D01*
G01X544900D02*
Y588000D01*
X544400Y587500D01*
G01Y585500D02*
X545400D01*
G01X548000Y588000D02*
X547667Y587917D01*
X547417Y587708D01*
X547250Y587458D01*
X547125Y587125D01*
X547083Y586750D01*
X547125Y586375D01*
X547250Y586042D01*
X547417Y585792D01*
X547667Y585583D01*
X548000Y585500D01*
X548333Y585583D01*
X548583Y585792D01*
X548750Y586042D01*
X548875Y586375D01*
X548917Y586750D01*
X548875Y587125D01*
X548750Y587458D01*
X548583Y587708D01*
X548333Y587917D01*
X548000Y588000D01*
G01X551600Y585500D02*
Y588000D01*
X550058Y586208D01*
X552142D01*
G01X554200Y585500D02*
Y588000D01*
X553700Y587500D01*
G01Y585500D02*
X554700D01*
G01X549579Y564531D02*
Y568531D01*
X542179D01*
G01X540967Y581000D02*
Y583500D01*
X542008D01*
X542342Y583375D01*
X542550Y583208D01*
X542633Y582875D01*
X542550Y582542D01*
X542300Y582333D01*
X542008Y582208D01*
X540967D01*
G01X542008D02*
X542633Y581000D01*
G01X544900D02*
Y583500D01*
X544400Y583000D01*
G01Y581000D02*
X545400D01*
G01X548000Y583500D02*
X547667Y583417D01*
X547417Y583208D01*
X547250Y582958D01*
X547125Y582625D01*
X547083Y582250D01*
X547125Y581875D01*
X547250Y581542D01*
X547417Y581292D01*
X547667Y581083D01*
X548000Y581000D01*
X548333Y581083D01*
X548583Y581292D01*
X548750Y581542D01*
X548875Y581875D01*
X548917Y582250D01*
X548875Y582625D01*
X548750Y582958D01*
X548583Y583208D01*
X548333Y583417D01*
X548000Y583500D01*
G01X551600Y581000D02*
Y583500D01*
X550058Y581708D01*
X552142D01*
G01X554200Y581000D02*
X554492Y581042D01*
X554825Y581167D01*
X555033Y581375D01*
X555117Y581667D01*
X555033Y581958D01*
X554783Y582208D01*
X554408Y582333D01*
X553992D01*
X553742Y582417D01*
X553533Y582625D01*
X553450Y582917D01*
X553575Y583208D01*
X553867Y583417D01*
X554200Y583500D01*
X554533Y583417D01*
X554825Y583208D01*
X554950Y582917D01*
X554867Y582625D01*
X554658Y582417D01*
X554408Y582333D01*
X553992D01*
X553617Y582208D01*
X553367Y581958D01*
X553283Y581667D01*
X553367Y581375D01*
X553575Y581167D01*
X553908Y581042D01*
X554200Y581000D01*
G01X549579Y559531D02*
Y563531D01*
X542179D01*
G01X525950Y576500D02*
X525617Y576542D01*
X525325Y576708D01*
X525075Y576958D01*
X524908Y577250D01*
X524825Y577583D01*
Y577917D01*
X524908Y578250D01*
X525075Y578542D01*
X525325Y578792D01*
X525617Y578958D01*
X525950Y579000D01*
X526283Y578958D01*
X526575Y578792D01*
X526825Y578542D01*
X526992Y578250D01*
X527075Y577917D01*
Y577583D01*
X526992Y577250D01*
X526825Y576958D01*
X526575Y576708D01*
X526283Y576542D01*
X525950Y576500D01*
G01X526283Y577167D02*
X526783Y576500D01*
G01X528258Y577542D02*
X528550Y577833D01*
X528800Y578000D01*
X529133Y578083D01*
X529425Y578000D01*
X529633Y577833D01*
X529800Y577583D01*
X529842Y577292D01*
X529800Y577042D01*
X529633Y576792D01*
X529383Y576583D01*
X529092Y576500D01*
X528758Y576583D01*
X528467Y576833D01*
X528300Y577208D01*
X528258Y577625D01*
X528342Y578167D01*
X528467Y578458D01*
X528675Y578750D01*
X528967Y578958D01*
X529258Y579000D01*
X529550Y578917D01*
X529758Y578708D01*
G01X523345Y556070D02*
X530945D01*
G01X523345Y566870D02*
Y556070D01*
G01X530945Y566870D02*
X523345D01*
G01X530945Y556070D02*
Y566870D01*
G01X524846Y581031D02*
Y583531D01*
X525887D01*
X526221Y583406D01*
X526429Y583239D01*
X526512Y582906D01*
X526429Y582573D01*
X526179Y582364D01*
X525887Y582239D01*
X524846D01*
G01X525887D02*
X526512Y581031D01*
G01X528779D02*
Y583531D01*
X528279Y583031D01*
G01Y581031D02*
X529279D01*
G01X531879Y583531D02*
X531546Y583448D01*
X531296Y583239D01*
X531129Y582989D01*
X531004Y582656D01*
X530962Y582281D01*
X531004Y581906D01*
X531129Y581573D01*
X531296Y581323D01*
X531546Y581114D01*
X531879Y581031D01*
X532212Y581114D01*
X532462Y581323D01*
X532629Y581573D01*
X532754Y581906D01*
X532796Y582281D01*
X532754Y582656D01*
X532629Y582989D01*
X532462Y583239D01*
X532212Y583448D01*
X531879Y583531D01*
G01X535479Y581031D02*
Y583531D01*
X533937Y581739D01*
X536021D01*
G01X537287Y582073D02*
X537579Y582364D01*
X537829Y582531D01*
X538162Y582614D01*
X538454Y582531D01*
X538662Y582364D01*
X538829Y582114D01*
X538871Y581823D01*
X538829Y581573D01*
X538662Y581323D01*
X538412Y581114D01*
X538121Y581031D01*
X537787Y581114D01*
X537496Y581364D01*
X537329Y581739D01*
X537287Y582156D01*
X537371Y582698D01*
X537496Y582989D01*
X537704Y583281D01*
X537996Y583489D01*
X538287Y583531D01*
X538579Y583448D01*
X538787Y583239D01*
G01X522000Y568967D02*
X519500D01*
Y570008D01*
X519625Y570342D01*
X519792Y570550D01*
X520125Y570633D01*
X520458Y570550D01*
X520667Y570300D01*
X520792Y570008D01*
Y568967D01*
G01Y570008D02*
X522000Y570633D01*
G01Y572900D02*
X519500D01*
X520000Y572400D01*
G01X522000D02*
Y573400D01*
G01X519917Y575208D02*
X519667Y575458D01*
X519542Y575750D01*
X519500Y576083D01*
X519583Y576500D01*
X519792Y576792D01*
X520042Y576875D01*
X520292Y576833D01*
X520500Y576667D01*
X520917Y575833D01*
X521208Y575458D01*
X521625Y575208D01*
X522000Y575125D01*
Y576875D01*
G01X521708Y578392D02*
X521917Y578683D01*
X522000Y579017D01*
X521917Y579350D01*
X521667Y579642D01*
X521292Y579850D01*
X520917Y579933D01*
X520458D01*
X520083Y579850D01*
X519750Y579642D01*
X519583Y579392D01*
X519500Y579100D01*
X519583Y578767D01*
X519750Y578517D01*
X520000Y578350D01*
X520333Y578267D01*
X520625Y578350D01*
X520917Y578558D01*
X521083Y578808D01*
X521125Y579100D01*
X521042Y579433D01*
X520833Y579683D01*
X520458Y579933D01*
G01X522000Y582700D02*
X519500D01*
X521292Y581158D01*
Y583242D01*
G01X527114Y574523D02*
X526864Y574648D01*
X526572Y574731D01*
X526239D01*
X525864Y574606D01*
X525572Y574398D01*
X525364Y574148D01*
X525197Y573731D01*
X525155Y573356D01*
X525239Y572981D01*
X525364Y572731D01*
X525614Y572481D01*
X525905Y572314D01*
X526197Y572231D01*
X526489D01*
X526780Y572314D01*
X527030Y572439D01*
X527239Y572606D01*
G01X528589Y572523D02*
X528880Y572314D01*
X529214Y572231D01*
X529547Y572314D01*
X529839Y572564D01*
X530047Y572939D01*
X530130Y573314D01*
Y573773D01*
X530047Y574148D01*
X529839Y574481D01*
X529589Y574648D01*
X529297Y574731D01*
X528964Y574648D01*
X528714Y574481D01*
X528547Y574231D01*
X528464Y573898D01*
X528547Y573606D01*
X528755Y573314D01*
X529005Y573148D01*
X529297Y573106D01*
X529630Y573189D01*
X529880Y573398D01*
X530130Y573773D01*
G01X532897Y572231D02*
Y574731D01*
X531355Y572939D01*
X533439D01*
G01X542708Y572317D02*
X542583Y572067D01*
X542500Y571775D01*
Y571442D01*
X542625Y571067D01*
X542833Y570775D01*
X543083Y570567D01*
X543500Y570400D01*
X543875Y570358D01*
X544250Y570442D01*
X544500Y570567D01*
X544750Y570817D01*
X544917Y571108D01*
X545000Y571400D01*
Y571692D01*
X544917Y571983D01*
X544792Y572233D01*
X544625Y572442D01*
G01X542917Y573708D02*
X542667Y573958D01*
X542542Y574250D01*
X542500Y574583D01*
X542583Y575000D01*
X542792Y575292D01*
X543042Y575375D01*
X543292Y575333D01*
X543500Y575167D01*
X543917Y574333D01*
X544208Y573958D01*
X544625Y573708D01*
X545000Y573625D01*
Y575375D01*
G01Y577517D02*
X544458Y577600D01*
X544000Y577725D01*
X543583Y577892D01*
X543125Y578100D01*
X542500Y578433D01*
Y576767D01*
G01X510017Y563931D02*
Y580031D01*
G01X517017Y563931D02*
X510017D01*
G01X517017Y580031D02*
Y563931D01*
G01X510017Y580031D02*
X517017D01*
G01X541404Y644017D02*
Y646517D01*
X542445D01*
X542779Y646392D01*
X542987Y646225D01*
X543070Y645892D01*
X542987Y645559D01*
X542737Y645350D01*
X542445Y645225D01*
X541404D01*
G01X542445D02*
X543070Y644017D01*
G01X544420Y644392D02*
X544670Y644184D01*
X544962Y644059D01*
X545337Y644017D01*
X545712Y644100D01*
X546004Y644267D01*
X546212Y644559D01*
X546254Y644892D01*
X546170Y645225D01*
X545962Y645434D01*
X545670Y645600D01*
X545379Y645642D01*
X545087Y645600D01*
X544712Y645434D01*
X544837Y646517D01*
X545962D01*
G01X548437D02*
X548104Y646434D01*
X547854Y646225D01*
X547687Y645975D01*
X547562Y645642D01*
X547520Y645267D01*
X547562Y644892D01*
X547687Y644559D01*
X547854Y644309D01*
X548104Y644100D01*
X548437Y644017D01*
X548770Y644100D01*
X549020Y644309D01*
X549187Y644559D01*
X549312Y644892D01*
X549354Y645267D01*
X549312Y645642D01*
X549187Y645975D01*
X549020Y646225D01*
X548770Y646434D01*
X548437Y646517D01*
G01X550745Y645059D02*
X551037Y645350D01*
X551287Y645517D01*
X551620Y645600D01*
X551912Y645517D01*
X552120Y645350D01*
X552287Y645100D01*
X552329Y644809D01*
X552287Y644559D01*
X552120Y644309D01*
X551870Y644100D01*
X551579Y644017D01*
X551245Y644100D01*
X550954Y644350D01*
X550787Y644725D01*
X550745Y645142D01*
X550829Y645684D01*
X550954Y645975D01*
X551162Y646267D01*
X551454Y646475D01*
X551745Y646517D01*
X552037Y646434D01*
X552245Y646225D01*
G01X541617Y640000D02*
Y642500D01*
X542658D01*
X542992Y642375D01*
X543200Y642208D01*
X543283Y641875D01*
X543200Y641542D01*
X542950Y641333D01*
X542658Y641208D01*
X541617D01*
G01X542658D02*
X543283Y640000D01*
G01X544633Y640375D02*
X544883Y640167D01*
X545175Y640042D01*
X545550Y640000D01*
X545925Y640083D01*
X546217Y640250D01*
X546425Y640542D01*
X546467Y640875D01*
X546383Y641208D01*
X546175Y641417D01*
X545883Y641583D01*
X545592Y641625D01*
X545300Y641583D01*
X544925Y641417D01*
X545050Y642500D01*
X546175D01*
G01X548650D02*
X548317Y642417D01*
X548067Y642208D01*
X547900Y641958D01*
X547775Y641625D01*
X547733Y641250D01*
X547775Y640875D01*
X547900Y640542D01*
X548067Y640292D01*
X548317Y640083D01*
X548650Y640000D01*
X548983Y640083D01*
X549233Y640292D01*
X549400Y640542D01*
X549525Y640875D01*
X549567Y641250D01*
X549525Y641625D01*
X549400Y641958D01*
X549233Y642208D01*
X548983Y642417D01*
X548650Y642500D01*
G01X551042Y640292D02*
X551333Y640083D01*
X551667Y640000D01*
X552000Y640083D01*
X552292Y640333D01*
X552500Y640708D01*
X552583Y641083D01*
Y641542D01*
X552500Y641917D01*
X552292Y642250D01*
X552042Y642417D01*
X551750Y642500D01*
X551417Y642417D01*
X551167Y642250D01*
X551000Y642000D01*
X550917Y641667D01*
X551000Y641375D01*
X551208Y641083D01*
X551458Y640917D01*
X551750Y640875D01*
X552083Y640958D01*
X552333Y641167D01*
X552583Y641542D01*
G01X541617Y648000D02*
Y650500D01*
X542658D01*
X542992Y650375D01*
X543200Y650208D01*
X543283Y649875D01*
X543200Y649542D01*
X542950Y649333D01*
X542658Y649208D01*
X541617D01*
G01X542658D02*
X543283Y648000D01*
G01X544633Y648375D02*
X544883Y648167D01*
X545175Y648042D01*
X545550Y648000D01*
X545925Y648083D01*
X546217Y648250D01*
X546425Y648542D01*
X546467Y648875D01*
X546383Y649208D01*
X546175Y649417D01*
X545883Y649583D01*
X545592Y649625D01*
X545300Y649583D01*
X544925Y649417D01*
X545050Y650500D01*
X546175D01*
G01X548650Y648000D02*
Y650500D01*
X548150Y650000D01*
G01Y648000D02*
X549150D01*
G01X551750D02*
Y650500D01*
X551250Y650000D01*
G01Y648000D02*
X552250D01*
G01X536017Y631500D02*
Y634000D01*
X537058D01*
X537392Y633875D01*
X537600Y633708D01*
X537683Y633375D01*
X537600Y633042D01*
X537350Y632833D01*
X537058Y632708D01*
X536017D01*
G01X537058D02*
X537683Y631500D01*
G01X539033Y631875D02*
X539283Y631667D01*
X539575Y631542D01*
X539950Y631500D01*
X540325Y631583D01*
X540617Y631750D01*
X540825Y632042D01*
X540867Y632375D01*
X540783Y632708D01*
X540575Y632917D01*
X540283Y633083D01*
X539992Y633125D01*
X539700Y633083D01*
X539325Y632917D01*
X539450Y634000D01*
X540575D01*
G01X543050Y631500D02*
Y634000D01*
X542550Y633500D01*
G01Y631500D02*
X543550D01*
G01X545358Y633583D02*
X545608Y633833D01*
X545900Y633958D01*
X546233Y634000D01*
X546650Y633917D01*
X546942Y633708D01*
X547025Y633458D01*
X546983Y633208D01*
X546817Y633000D01*
X545983Y632583D01*
X545608Y632292D01*
X545358Y631875D01*
X545275Y631500D01*
X547025D01*
G01X551487Y634317D02*
Y630317D01*
X558887D01*
G01X528500Y636517D02*
X526000D01*
Y637558D01*
X526125Y637892D01*
X526292Y638100D01*
X526625Y638183D01*
X526958Y638100D01*
X527167Y637850D01*
X527292Y637558D01*
Y636517D01*
G01Y637558D02*
X528500Y638183D01*
G01X528125Y639533D02*
X528333Y639783D01*
X528458Y640075D01*
X528500Y640450D01*
X528417Y640825D01*
X528250Y641117D01*
X527958Y641325D01*
X527625Y641367D01*
X527292Y641283D01*
X527083Y641075D01*
X526917Y640783D01*
X526875Y640492D01*
X526917Y640200D01*
X527083Y639825D01*
X526000Y639950D01*
Y641075D01*
G01X528500Y643550D02*
X526000D01*
X526500Y643050D01*
G01X528500D02*
Y644050D01*
G01Y647150D02*
X526000D01*
X527792Y645608D01*
Y647692D01*
G01X554787Y634717D02*
X558787D01*
Y642117D01*
G01X536500Y637017D02*
X534000D01*
Y638058D01*
X534125Y638392D01*
X534292Y638600D01*
X534625Y638683D01*
X534958Y638600D01*
X535167Y638350D01*
X535292Y638058D01*
Y637017D01*
G01Y638058D02*
X536500Y638683D01*
G01X536125Y640033D02*
X536333Y640283D01*
X536458Y640575D01*
X536500Y640950D01*
X536417Y641325D01*
X536250Y641617D01*
X535958Y641825D01*
X535625Y641867D01*
X535292Y641783D01*
X535083Y641575D01*
X534917Y641283D01*
X534875Y640992D01*
X534917Y640700D01*
X535083Y640325D01*
X534000Y640450D01*
Y641575D01*
G01X536500Y644050D02*
X534000D01*
X534500Y643550D01*
G01X536500D02*
Y644550D01*
G01X536125Y646233D02*
X536333Y646483D01*
X536458Y646775D01*
X536500Y647150D01*
X536417Y647525D01*
X536250Y647817D01*
X535958Y648025D01*
X535625Y648067D01*
X535292Y647983D01*
X535083Y647775D01*
X534917Y647483D01*
X534875Y647192D01*
X534917Y646900D01*
X535083Y646525D01*
X534000Y646650D01*
Y647775D01*
G01X540500Y644400D02*
X540458Y644067D01*
X540292Y643775D01*
X540042Y643525D01*
X539750Y643358D01*
X539417Y643275D01*
X539083D01*
X538750Y643358D01*
X538458Y643525D01*
X538208Y643775D01*
X538042Y644067D01*
X538000Y644400D01*
X538042Y644733D01*
X538208Y645025D01*
X538458Y645275D01*
X538750Y645442D01*
X539083Y645525D01*
X539417D01*
X539750Y645442D01*
X540042Y645275D01*
X540292Y645025D01*
X540458Y644733D01*
X540500Y644400D01*
G01X539833Y644733D02*
X540500Y645233D01*
G01X540208Y646792D02*
X540417Y647083D01*
X540500Y647417D01*
X540417Y647750D01*
X540167Y648042D01*
X539792Y648250D01*
X539417Y648333D01*
X538958D01*
X538583Y648250D01*
X538250Y648042D01*
X538083Y647792D01*
X538000Y647500D01*
X538083Y647167D01*
X538250Y646917D01*
X538500Y646750D01*
X538833Y646667D01*
X539125Y646750D01*
X539417Y646958D01*
X539583Y647208D01*
X539625Y647500D01*
X539542Y647833D01*
X539333Y648083D01*
X538958Y648333D01*
G01X540500Y650517D02*
X539958Y650600D01*
X539500Y650725D01*
X539083Y650892D01*
X538625Y651100D01*
X538000Y651433D01*
Y649767D01*
G01X532500Y636983D02*
X530000D01*
Y637817D01*
X530125Y638150D01*
X530292Y638400D01*
X530542Y638608D01*
X530833Y638775D01*
X531250Y638817D01*
X531667Y638775D01*
X531958Y638608D01*
X532208Y638400D01*
X532375Y638150D01*
X532500Y637817D01*
Y636983D01*
G01Y641000D02*
X530000D01*
X530500Y640500D01*
G01X532500D02*
Y641500D01*
G01X531458Y643308D02*
X531167Y643600D01*
X531000Y643850D01*
X530917Y644183D01*
X531000Y644475D01*
X531167Y644683D01*
X531417Y644850D01*
X531708Y644892D01*
X531958Y644850D01*
X532208Y644683D01*
X532417Y644433D01*
X532500Y644142D01*
X532417Y643808D01*
X532167Y643517D01*
X531792Y643350D01*
X531375Y643308D01*
X530833Y643392D01*
X530542Y643517D01*
X530250Y643725D01*
X530042Y644017D01*
X530000Y644308D01*
X530083Y644600D01*
X530292Y644808D01*
G01X508591Y684917D02*
Y687417D01*
X509632D01*
X509966Y687292D01*
X510174Y687125D01*
X510257Y686792D01*
X510174Y686459D01*
X509924Y686250D01*
X509632Y686125D01*
X508591D01*
G01X509632D02*
X510257Y684917D01*
G01X513024D02*
Y687417D01*
X511482Y685625D01*
X513566D01*
G01X515541Y684917D02*
X515624Y685459D01*
X515749Y685917D01*
X515916Y686334D01*
X516124Y686792D01*
X516457Y687417D01*
X514791D01*
G01X517807Y685292D02*
X518057Y685084D01*
X518349Y684959D01*
X518724Y684917D01*
X519099Y685000D01*
X519391Y685167D01*
X519599Y685459D01*
X519641Y685792D01*
X519557Y686125D01*
X519349Y686334D01*
X519057Y686500D01*
X518766Y686542D01*
X518474Y686500D01*
X518099Y686334D01*
X518224Y687417D01*
X519349D01*
G01X517274Y695417D02*
Y699417D01*
X509874D01*
G01X547704Y653717D02*
Y656217D01*
X548745D01*
X549079Y656092D01*
X549287Y655925D01*
X549370Y655592D01*
X549287Y655259D01*
X549037Y655050D01*
X548745Y654925D01*
X547704D01*
G01X548745D02*
X549370Y653717D01*
G01X550720Y654092D02*
X550970Y653884D01*
X551262Y653759D01*
X551637Y653717D01*
X552012Y653800D01*
X552304Y653967D01*
X552512Y654259D01*
X552554Y654592D01*
X552470Y654925D01*
X552262Y655134D01*
X551970Y655300D01*
X551679Y655342D01*
X551387Y655300D01*
X551012Y655134D01*
X551137Y656217D01*
X552262D01*
G01X554737D02*
X554404Y656134D01*
X554154Y655925D01*
X553987Y655675D01*
X553862Y655342D01*
X553820Y654967D01*
X553862Y654592D01*
X553987Y654259D01*
X554154Y654009D01*
X554404Y653800D01*
X554737Y653717D01*
X555070Y653800D01*
X555320Y654009D01*
X555487Y654259D01*
X555612Y654592D01*
X555654Y654967D01*
X555612Y655342D01*
X555487Y655675D01*
X555320Y655925D01*
X555070Y656134D01*
X554737Y656217D01*
G01X556920Y654092D02*
X557170Y653884D01*
X557462Y653759D01*
X557837Y653717D01*
X558212Y653800D01*
X558504Y653967D01*
X558712Y654259D01*
X558754Y654592D01*
X558670Y654925D01*
X558462Y655134D01*
X558170Y655300D01*
X557879Y655342D01*
X557587Y655300D01*
X557212Y655134D01*
X557337Y656217D01*
X558462D01*
G01X539304Y662417D02*
Y664917D01*
X540345D01*
X540679Y664792D01*
X540887Y664625D01*
X540970Y664292D01*
X540887Y663959D01*
X540637Y663750D01*
X540345Y663625D01*
X539304D01*
G01X540345D02*
X540970Y662417D01*
G01X542320Y662792D02*
X542570Y662584D01*
X542862Y662459D01*
X543237Y662417D01*
X543612Y662500D01*
X543904Y662667D01*
X544112Y662959D01*
X544154Y663292D01*
X544070Y663625D01*
X543862Y663834D01*
X543570Y664000D01*
X543279Y664042D01*
X542987Y664000D01*
X542612Y663834D01*
X542737Y664917D01*
X543862D01*
G01X546337Y662417D02*
Y664917D01*
X545837Y664417D01*
G01Y662417D02*
X546837D01*
G01X548520Y662917D02*
X548770Y662625D01*
X549104Y662459D01*
X549479Y662417D01*
X549812Y662459D01*
X550145Y662667D01*
X550354Y662917D01*
X550395Y663167D01*
X550312Y663459D01*
X550020Y663667D01*
X549729Y663750D01*
X549354D01*
G01X549729D02*
X549979Y663875D01*
X550187Y664084D01*
X550270Y664334D01*
X550187Y664584D01*
X549979Y664792D01*
X549604Y664917D01*
X549229Y664875D01*
X548854Y664709D01*
G01X558987Y661417D02*
Y665417D01*
X551587D01*
G01X542500Y675900D02*
X542458Y675567D01*
X542292Y675275D01*
X542042Y675025D01*
X541750Y674858D01*
X541417Y674775D01*
X541083D01*
X540750Y674858D01*
X540458Y675025D01*
X540208Y675275D01*
X540042Y675567D01*
X540000Y675900D01*
X540042Y676233D01*
X540208Y676525D01*
X540458Y676775D01*
X540750Y676942D01*
X541083Y677025D01*
X541417D01*
X541750Y676942D01*
X542042Y676775D01*
X542292Y676525D01*
X542458Y676233D01*
X542500Y675900D01*
G01X541833Y676233D02*
X542500Y676733D01*
G01X542208Y678292D02*
X542417Y678583D01*
X542500Y678917D01*
X542417Y679250D01*
X542167Y679542D01*
X541792Y679750D01*
X541417Y679833D01*
X540958D01*
X540583Y679750D01*
X540250Y679542D01*
X540083Y679292D01*
X540000Y679000D01*
X540083Y678667D01*
X540250Y678417D01*
X540500Y678250D01*
X540833Y678167D01*
X541125Y678250D01*
X541417Y678458D01*
X541583Y678708D01*
X541625Y679000D01*
X541542Y679333D01*
X541333Y679583D01*
X540958Y679833D01*
G01X542500Y682100D02*
X542458Y682392D01*
X542333Y682725D01*
X542125Y682933D01*
X541833Y683017D01*
X541542Y682933D01*
X541292Y682683D01*
X541167Y682308D01*
Y681892D01*
X541083Y681642D01*
X540875Y681433D01*
X540583Y681350D01*
X540292Y681475D01*
X540083Y681767D01*
X540000Y682100D01*
X540083Y682433D01*
X540292Y682725D01*
X540583Y682850D01*
X540875Y682767D01*
X541083Y682558D01*
X541167Y682308D01*
Y681892D01*
X541292Y681517D01*
X541542Y681267D01*
X541833Y681183D01*
X542125Y681267D01*
X542333Y681475D01*
X542458Y681808D01*
X542500Y682100D01*
G01X544587Y690417D02*
X546687Y688617D01*
X544587Y686417D01*
G01X544487Y682817D02*
X563687D01*
Y694017D01*
X544487D01*
Y682817D01*
X544887D01*
G01X541054Y668709D02*
X540804Y668834D01*
X540512Y668917D01*
X540179D01*
X539804Y668792D01*
X539512Y668584D01*
X539304Y668334D01*
X539137Y667917D01*
X539095Y667542D01*
X539179Y667167D01*
X539304Y666917D01*
X539554Y666667D01*
X539845Y666500D01*
X540137Y666417D01*
X540429D01*
X540720Y666500D01*
X540970Y666625D01*
X541179Y666792D01*
G01X542445Y668500D02*
X542695Y668750D01*
X542987Y668875D01*
X543320Y668917D01*
X543737Y668834D01*
X544029Y668625D01*
X544112Y668375D01*
X544070Y668125D01*
X543904Y667917D01*
X543070Y667500D01*
X542695Y667209D01*
X542445Y666792D01*
X542362Y666417D01*
X544112D01*
G01X545420Y666792D02*
X545670Y666584D01*
X545962Y666459D01*
X546337Y666417D01*
X546712Y666500D01*
X547004Y666667D01*
X547212Y666959D01*
X547254Y667292D01*
X547170Y667625D01*
X546962Y667834D01*
X546670Y668000D01*
X546379Y668042D01*
X546087Y668000D01*
X545712Y667834D01*
X545837Y668917D01*
X546962D01*
G01X549354Y666417D02*
X549437Y666959D01*
X549562Y667417D01*
X549729Y667834D01*
X549937Y668292D01*
X550270Y668917D01*
X548604D01*
G01X549454Y660209D02*
X549204Y660334D01*
X548912Y660417D01*
X548579D01*
X548204Y660292D01*
X547912Y660084D01*
X547704Y659834D01*
X547537Y659417D01*
X547495Y659042D01*
X547579Y658667D01*
X547704Y658417D01*
X547954Y658167D01*
X548245Y658000D01*
X548537Y657917D01*
X548829D01*
X549120Y658000D01*
X549370Y658125D01*
X549579Y658292D01*
G01X550845Y660000D02*
X551095Y660250D01*
X551387Y660375D01*
X551720Y660417D01*
X552137Y660334D01*
X552429Y660125D01*
X552512Y659875D01*
X552470Y659625D01*
X552304Y659417D01*
X551470Y659000D01*
X551095Y658709D01*
X550845Y658292D01*
X550762Y657917D01*
X552512D01*
G01X553820Y658292D02*
X554070Y658084D01*
X554362Y657959D01*
X554737Y657917D01*
X555112Y658000D01*
X555404Y658167D01*
X555612Y658459D01*
X555654Y658792D01*
X555570Y659125D01*
X555362Y659334D01*
X555070Y659500D01*
X554779Y659542D01*
X554487Y659500D01*
X554112Y659334D01*
X554237Y660417D01*
X555362D01*
G01X557045Y658959D02*
X557337Y659250D01*
X557587Y659417D01*
X557920Y659500D01*
X558212Y659417D01*
X558420Y659250D01*
X558587Y659000D01*
X558629Y658709D01*
X558587Y658459D01*
X558420Y658209D01*
X558170Y658000D01*
X557879Y657917D01*
X557545Y658000D01*
X557254Y658250D01*
X557087Y658625D01*
X557045Y659042D01*
X557129Y659584D01*
X557254Y659875D01*
X557462Y660167D01*
X557754Y660375D01*
X558045Y660417D01*
X558337Y660334D01*
X558545Y660125D01*
G01X510341Y683209D02*
X510091Y683334D01*
X509799Y683417D01*
X509466D01*
X509091Y683292D01*
X508799Y683084D01*
X508591Y682834D01*
X508424Y682417D01*
X508382Y682042D01*
X508466Y681667D01*
X508591Y681417D01*
X508841Y681167D01*
X509132Y681000D01*
X509424Y680917D01*
X509716D01*
X510007Y681000D01*
X510257Y681125D01*
X510466Y681292D01*
G01X511732Y683000D02*
X511982Y683250D01*
X512274Y683375D01*
X512607Y683417D01*
X513024Y683334D01*
X513316Y683125D01*
X513399Y682875D01*
X513357Y682625D01*
X513191Y682417D01*
X512357Y682000D01*
X511982Y681709D01*
X511732Y681292D01*
X511649Y680917D01*
X513399D01*
G01X514707Y681417D02*
X514957Y681125D01*
X515291Y680959D01*
X515666Y680917D01*
X515999Y680959D01*
X516332Y681167D01*
X516541Y681417D01*
X516582Y681667D01*
X516499Y681959D01*
X516207Y682167D01*
X515916Y682250D01*
X515541D01*
G01X515916D02*
X516166Y682375D01*
X516374Y682584D01*
X516457Y682834D01*
X516374Y683084D01*
X516166Y683292D01*
X515791Y683417D01*
X515416Y683375D01*
X515041Y683209D01*
G01X518641Y680917D02*
X518724Y681459D01*
X518849Y681917D01*
X519016Y682334D01*
X519224Y682792D01*
X519557Y683417D01*
X517891D01*
G01X514892Y741849D02*
X510892D01*
Y734449D01*
G01X519017Y702900D02*
Y705400D01*
X520058D01*
X520392Y705275D01*
X520600Y705108D01*
X520683Y704775D01*
X520600Y704442D01*
X520350Y704233D01*
X520058Y704108D01*
X519017D01*
G01X520058D02*
X520683Y702900D01*
G01X523450D02*
Y705400D01*
X521908Y703608D01*
X523992D01*
G01X525967Y702900D02*
X526050Y703442D01*
X526175Y703900D01*
X526342Y704317D01*
X526550Y704775D01*
X526883Y705400D01*
X525217D01*
G01X529150D02*
X528817Y705317D01*
X528567Y705108D01*
X528400Y704858D01*
X528275Y704525D01*
X528233Y704150D01*
X528275Y703775D01*
X528400Y703442D01*
X528567Y703192D01*
X528817Y702983D01*
X529150Y702900D01*
X529483Y702983D01*
X529733Y703192D01*
X529900Y703442D01*
X530025Y703775D01*
X530067Y704150D01*
X530025Y704525D01*
X529900Y704858D01*
X529733Y705108D01*
X529483Y705317D01*
X529150Y705400D01*
G01X520823Y716280D02*
Y712280D01*
X528223D01*
G01X533846Y723116D02*
X533804Y722783D01*
X533638Y722491D01*
X533388Y722241D01*
X533096Y722074D01*
X532763Y721991D01*
X532429D01*
X532096Y722074D01*
X531804Y722241D01*
X531554Y722491D01*
X531388Y722783D01*
X531346Y723116D01*
X531388Y723449D01*
X531554Y723741D01*
X531804Y723991D01*
X532096Y724158D01*
X532429Y724241D01*
X532763D01*
X533096Y724158D01*
X533388Y723991D01*
X533638Y723741D01*
X533804Y723449D01*
X533846Y723116D01*
G01X533179Y723449D02*
X533846Y723949D01*
G01X531763Y725424D02*
X531513Y725674D01*
X531388Y725966D01*
X531346Y726299D01*
X531429Y726716D01*
X531638Y727008D01*
X531888Y727091D01*
X532138Y727049D01*
X532346Y726883D01*
X532763Y726049D01*
X533054Y725674D01*
X533471Y725424D01*
X533846Y725341D01*
Y727091D01*
G01X532804Y728524D02*
X532513Y728816D01*
X532346Y729066D01*
X532263Y729399D01*
X532346Y729691D01*
X532513Y729899D01*
X532763Y730066D01*
X533054Y730108D01*
X533304Y730066D01*
X533554Y729899D01*
X533763Y729649D01*
X533846Y729358D01*
X533763Y729024D01*
X533513Y728733D01*
X533138Y728566D01*
X532721Y728524D01*
X532179Y728608D01*
X531888Y728733D01*
X531596Y728941D01*
X531388Y729233D01*
X531346Y729524D01*
X531429Y729816D01*
X531638Y730024D01*
G01X533846Y732333D02*
X533304Y732416D01*
X532846Y732541D01*
X532429Y732708D01*
X531971Y732916D01*
X531346Y733249D01*
Y731583D01*
G01X515846Y735766D02*
Y721766D01*
G01X528846Y735766D02*
X515846D01*
G01X528846Y721766D02*
Y735766D01*
G01X515846Y721766D02*
X528846D01*
G01X533850Y738036D02*
X533808Y737703D01*
X533642Y737411D01*
X533392Y737161D01*
X533100Y736994D01*
X532767Y736911D01*
X532433D01*
X532100Y736994D01*
X531808Y737161D01*
X531558Y737411D01*
X531392Y737703D01*
X531350Y738036D01*
X531392Y738369D01*
X531558Y738661D01*
X531808Y738911D01*
X532100Y739078D01*
X532433Y739161D01*
X532767D01*
X533100Y739078D01*
X533392Y738911D01*
X533642Y738661D01*
X533808Y738369D01*
X533850Y738036D01*
G01X533183Y738369D02*
X533850Y738869D01*
G01X531767Y740344D02*
X531517Y740594D01*
X531392Y740886D01*
X531350Y741219D01*
X531433Y741636D01*
X531642Y741928D01*
X531892Y742011D01*
X532142Y741969D01*
X532350Y741803D01*
X532767Y740969D01*
X533058Y740594D01*
X533475Y740344D01*
X533850Y740261D01*
Y742011D01*
G01X533350Y743319D02*
X533642Y743569D01*
X533808Y743903D01*
X533850Y744278D01*
X533808Y744611D01*
X533600Y744944D01*
X533350Y745153D01*
X533100Y745194D01*
X532808Y745111D01*
X532600Y744819D01*
X532517Y744528D01*
Y744153D01*
G01Y744528D02*
X532392Y744778D01*
X532183Y744986D01*
X531933Y745069D01*
X531683Y744986D01*
X531475Y744778D01*
X531350Y744403D01*
X531392Y744028D01*
X531558Y743653D01*
G01X533850Y747336D02*
X531350D01*
X531850Y746836D01*
G01X533850D02*
Y747836D01*
G01X515850Y750686D02*
Y736686D01*
G01X528850D02*
Y750686D01*
G01X515850Y736686D02*
X528850D01*
G01X551267Y715292D02*
X551017Y715417D01*
X550725Y715500D01*
X550392D01*
X550017Y715375D01*
X549725Y715167D01*
X549517Y714917D01*
X549350Y714500D01*
X549308Y714125D01*
X549392Y713750D01*
X549517Y713500D01*
X549767Y713250D01*
X550058Y713083D01*
X550350Y713000D01*
X550642D01*
X550933Y713083D01*
X551183Y713208D01*
X551392Y713375D01*
G01X552658Y715083D02*
X552908Y715333D01*
X553200Y715458D01*
X553533Y715500D01*
X553950Y715417D01*
X554242Y715208D01*
X554325Y714958D01*
X554283Y714708D01*
X554117Y714500D01*
X553283Y714083D01*
X552908Y713792D01*
X552658Y713375D01*
X552575Y713000D01*
X554325D01*
G01X555633Y713375D02*
X555883Y713167D01*
X556175Y713042D01*
X556550Y713000D01*
X556925Y713083D01*
X557217Y713250D01*
X557425Y713542D01*
X557467Y713875D01*
X557383Y714208D01*
X557175Y714417D01*
X556883Y714583D01*
X556592Y714625D01*
X556300Y714583D01*
X555925Y714417D01*
X556050Y715500D01*
X557175D01*
G01X558858Y715083D02*
X559108Y715333D01*
X559400Y715458D01*
X559733Y715500D01*
X560150Y715417D01*
X560442Y715208D01*
X560525Y714958D01*
X560483Y714708D01*
X560317Y714500D01*
X559483Y714083D01*
X559108Y713792D01*
X558858Y713375D01*
X558775Y713000D01*
X560525D01*
G01X528850Y750686D02*
X515850D01*
G01X557763Y948278D02*
X555263D01*
Y949319D01*
X555388Y949653D01*
X555555Y949861D01*
X555888Y949944D01*
X556221Y949861D01*
X556430Y949611D01*
X556555Y949319D01*
Y948278D01*
G01Y949319D02*
X557763Y949944D01*
G01X555680Y951419D02*
X555430Y951669D01*
X555305Y951961D01*
X555263Y952294D01*
X555346Y952711D01*
X555555Y953003D01*
X555805Y953086D01*
X556055Y953044D01*
X556263Y952878D01*
X556680Y952044D01*
X556971Y951669D01*
X557388Y951419D01*
X557763Y951336D01*
Y953086D01*
G01X555680Y954519D02*
X555430Y954769D01*
X555305Y955061D01*
X555263Y955394D01*
X555346Y955811D01*
X555555Y956103D01*
X555805Y956186D01*
X556055Y956144D01*
X556263Y955978D01*
X556680Y955144D01*
X556971Y954769D01*
X557388Y954519D01*
X557763Y954436D01*
Y956186D01*
G01X555680Y957619D02*
X555430Y957869D01*
X555305Y958161D01*
X555263Y958494D01*
X555346Y958911D01*
X555555Y959203D01*
X555805Y959286D01*
X556055Y959244D01*
X556263Y959078D01*
X556680Y958244D01*
X556971Y957869D01*
X557388Y957619D01*
X557763Y957536D01*
Y959286D01*
G01X545917Y1079000D02*
Y1081500D01*
X546958D01*
X547292Y1081375D01*
X547500Y1081208D01*
X547583Y1080875D01*
X547500Y1080542D01*
X547250Y1080333D01*
X546958Y1080208D01*
X545917D01*
G01X546958D02*
X547583Y1079000D01*
G01X549058Y1081083D02*
X549308Y1081333D01*
X549600Y1081458D01*
X549933Y1081500D01*
X550350Y1081417D01*
X550642Y1081208D01*
X550725Y1080958D01*
X550683Y1080708D01*
X550517Y1080500D01*
X549683Y1080083D01*
X549308Y1079792D01*
X549058Y1079375D01*
X548975Y1079000D01*
X550725D01*
G01X552033Y1079500D02*
X552283Y1079208D01*
X552617Y1079042D01*
X552992Y1079000D01*
X553325Y1079042D01*
X553658Y1079250D01*
X553867Y1079500D01*
X553908Y1079750D01*
X553825Y1080042D01*
X553533Y1080250D01*
X553242Y1080333D01*
X552867D01*
G01X553242D02*
X553492Y1080458D01*
X553700Y1080667D01*
X553783Y1080917D01*
X553700Y1081167D01*
X553492Y1081375D01*
X553117Y1081500D01*
X552742Y1081458D01*
X552367Y1081292D01*
G01X555258Y1080042D02*
X555550Y1080333D01*
X555800Y1080500D01*
X556133Y1080583D01*
X556425Y1080500D01*
X556633Y1080333D01*
X556800Y1080083D01*
X556842Y1079792D01*
X556800Y1079542D01*
X556633Y1079292D01*
X556383Y1079083D01*
X556092Y1079000D01*
X555758Y1079083D01*
X555467Y1079333D01*
X555300Y1079708D01*
X555258Y1080125D01*
X555342Y1080667D01*
X555467Y1080958D01*
X555675Y1081250D01*
X555967Y1081458D01*
X556258Y1081500D01*
X556550Y1081417D01*
X556758Y1081208D01*
G01X544130Y1098682D02*
Y1101182D01*
X545171D01*
X545505Y1101057D01*
X545713Y1100890D01*
X545796Y1100557D01*
X545713Y1100224D01*
X545463Y1100015D01*
X545171Y1099890D01*
X544130D01*
G01X545171D02*
X545796Y1098682D01*
G01X547271Y1100765D02*
X547521Y1101015D01*
X547813Y1101140D01*
X548146Y1101182D01*
X548563Y1101099D01*
X548855Y1100890D01*
X548938Y1100640D01*
X548896Y1100390D01*
X548730Y1100182D01*
X547896Y1099765D01*
X547521Y1099474D01*
X547271Y1099057D01*
X547188Y1098682D01*
X548938D01*
G01X550371Y1100765D02*
X550621Y1101015D01*
X550913Y1101140D01*
X551246Y1101182D01*
X551663Y1101099D01*
X551955Y1100890D01*
X552038Y1100640D01*
X551996Y1100390D01*
X551830Y1100182D01*
X550996Y1099765D01*
X550621Y1099474D01*
X550371Y1099057D01*
X550288Y1098682D01*
X552038D01*
G01X553555Y1098974D02*
X553846Y1098765D01*
X554180Y1098682D01*
X554513Y1098765D01*
X554805Y1099015D01*
X555013Y1099390D01*
X555096Y1099765D01*
Y1100224D01*
X555013Y1100599D01*
X554805Y1100932D01*
X554555Y1101099D01*
X554263Y1101182D01*
X553930Y1101099D01*
X553680Y1100932D01*
X553513Y1100682D01*
X553430Y1100349D01*
X553513Y1100057D01*
X553721Y1099765D01*
X553971Y1099599D01*
X554263Y1099557D01*
X554596Y1099640D01*
X554846Y1099849D01*
X555096Y1100224D01*
G01X551487Y1087173D02*
Y1083173D01*
X558887D01*
G01X542545Y1107230D02*
Y1109730D01*
X543586D01*
X543920Y1109605D01*
X544128Y1109438D01*
X544211Y1109105D01*
X544128Y1108772D01*
X543878Y1108563D01*
X543586Y1108438D01*
X542545D01*
G01X543586D02*
X544211Y1107230D01*
G01X545686Y1109313D02*
X545936Y1109563D01*
X546228Y1109688D01*
X546561Y1109730D01*
X546978Y1109647D01*
X547270Y1109438D01*
X547353Y1109188D01*
X547311Y1108938D01*
X547145Y1108730D01*
X546311Y1108313D01*
X545936Y1108022D01*
X545686Y1107605D01*
X545603Y1107230D01*
X547353D01*
G01X548661Y1107730D02*
X548911Y1107438D01*
X549245Y1107272D01*
X549620Y1107230D01*
X549953Y1107272D01*
X550286Y1107480D01*
X550495Y1107730D01*
X550536Y1107980D01*
X550453Y1108272D01*
X550161Y1108480D01*
X549870Y1108563D01*
X549495D01*
G01X549870D02*
X550120Y1108688D01*
X550328Y1108897D01*
X550411Y1109147D01*
X550328Y1109397D01*
X550120Y1109605D01*
X549745Y1109730D01*
X549370Y1109688D01*
X548995Y1109522D01*
G01X552595Y1107230D02*
X552678Y1107772D01*
X552803Y1108230D01*
X552970Y1108647D01*
X553178Y1109105D01*
X553511Y1109730D01*
X551845D01*
G01X558987Y1114173D02*
Y1118173D01*
X551587D01*
G01X547900Y1086217D02*
X545400D01*
Y1087258D01*
X545525Y1087592D01*
X545692Y1087800D01*
X546025Y1087883D01*
X546358Y1087800D01*
X546567Y1087550D01*
X546692Y1087258D01*
Y1086217D01*
G01Y1087258D02*
X547900Y1087883D01*
G01X545817Y1089358D02*
X545567Y1089608D01*
X545442Y1089900D01*
X545400Y1090233D01*
X545483Y1090650D01*
X545692Y1090942D01*
X545942Y1091025D01*
X546192Y1090983D01*
X546400Y1090817D01*
X546817Y1089983D01*
X547108Y1089608D01*
X547525Y1089358D01*
X547900Y1089275D01*
Y1091025D01*
G01X547400Y1092333D02*
X547692Y1092583D01*
X547858Y1092917D01*
X547900Y1093292D01*
X547858Y1093625D01*
X547650Y1093958D01*
X547400Y1094167D01*
X547150Y1094208D01*
X546858Y1094125D01*
X546650Y1093833D01*
X546567Y1093542D01*
Y1093167D01*
G01Y1093542D02*
X546442Y1093792D01*
X546233Y1094000D01*
X545983Y1094083D01*
X545733Y1094000D01*
X545525Y1093792D01*
X545400Y1093417D01*
X545442Y1093042D01*
X545608Y1092667D01*
G01X547900Y1096350D02*
X547858Y1096642D01*
X547733Y1096975D01*
X547525Y1097183D01*
X547233Y1097267D01*
X546942Y1097183D01*
X546692Y1096933D01*
X546567Y1096558D01*
Y1096142D01*
X546483Y1095892D01*
X546275Y1095683D01*
X545983Y1095600D01*
X545692Y1095725D01*
X545483Y1096017D01*
X545400Y1096350D01*
X545483Y1096683D01*
X545692Y1096975D01*
X545983Y1097100D01*
X546275Y1097017D01*
X546483Y1096808D01*
X546567Y1096558D01*
Y1096142D01*
X546692Y1095767D01*
X546942Y1095517D01*
X547233Y1095433D01*
X547525Y1095517D01*
X547733Y1095725D01*
X547858Y1096058D01*
X547900Y1096350D01*
G01X554787Y1087573D02*
X558787D01*
Y1094973D01*
G01X542833Y1128900D02*
X542791Y1128567D01*
X542625Y1128275D01*
X542375Y1128025D01*
X542083Y1127858D01*
X541750Y1127775D01*
X541416D01*
X541083Y1127858D01*
X540791Y1128025D01*
X540541Y1128275D01*
X540375Y1128567D01*
X540333Y1128900D01*
X540375Y1129233D01*
X540541Y1129525D01*
X540791Y1129775D01*
X541083Y1129942D01*
X541416Y1130025D01*
X541750D01*
X542083Y1129942D01*
X542375Y1129775D01*
X542625Y1129525D01*
X542791Y1129233D01*
X542833Y1128900D01*
G01X542166Y1129233D02*
X542833Y1129733D01*
G01X540750Y1131208D02*
X540500Y1131458D01*
X540375Y1131750D01*
X540333Y1132083D01*
X540416Y1132500D01*
X540625Y1132792D01*
X540875Y1132875D01*
X541125Y1132833D01*
X541333Y1132667D01*
X541750Y1131833D01*
X542041Y1131458D01*
X542458Y1131208D01*
X542833Y1131125D01*
Y1132875D01*
G01X541791Y1134308D02*
X541500Y1134600D01*
X541333Y1134850D01*
X541250Y1135183D01*
X541333Y1135475D01*
X541500Y1135683D01*
X541750Y1135850D01*
X542041Y1135892D01*
X542291Y1135850D01*
X542541Y1135683D01*
X542750Y1135433D01*
X542833Y1135142D01*
X542750Y1134808D01*
X542500Y1134517D01*
X542125Y1134350D01*
X541708Y1134308D01*
X541166Y1134392D01*
X540875Y1134517D01*
X540583Y1134725D01*
X540375Y1135017D01*
X540333Y1135308D01*
X540416Y1135600D01*
X540625Y1135808D01*
G01X520700Y1102466D02*
X520367Y1102508D01*
X520075Y1102674D01*
X519825Y1102924D01*
X519658Y1103216D01*
X519575Y1103549D01*
Y1103883D01*
X519658Y1104216D01*
X519825Y1104508D01*
X520075Y1104758D01*
X520367Y1104924D01*
X520700Y1104966D01*
X521033Y1104924D01*
X521325Y1104758D01*
X521575Y1104508D01*
X521742Y1104216D01*
X521825Y1103883D01*
Y1103549D01*
X521742Y1103216D01*
X521575Y1102924D01*
X521325Y1102674D01*
X521033Y1102508D01*
X520700Y1102466D01*
G01X521033Y1103133D02*
X521533Y1102466D01*
G01X523800D02*
Y1104966D01*
X523300Y1104466D01*
G01Y1102466D02*
X524300D01*
G01X526900D02*
X527192Y1102508D01*
X527525Y1102633D01*
X527733Y1102841D01*
X527817Y1103133D01*
X527733Y1103424D01*
X527483Y1103674D01*
X527108Y1103799D01*
X526692D01*
X526442Y1103883D01*
X526233Y1104091D01*
X526150Y1104383D01*
X526275Y1104674D01*
X526567Y1104883D01*
X526900Y1104966D01*
X527233Y1104883D01*
X527525Y1104674D01*
X527650Y1104383D01*
X527567Y1104091D01*
X527358Y1103883D01*
X527108Y1103799D01*
X526692D01*
X526317Y1103674D01*
X526067Y1103424D01*
X525983Y1103133D01*
X526067Y1102841D01*
X526275Y1102633D01*
X526608Y1102508D01*
X526900Y1102466D01*
G01X532674Y1121073D02*
X530574Y1122873D01*
X532674Y1125073D01*
G01X532774Y1128673D02*
X513574D01*
Y1117473D01*
X532774D01*
Y1128673D01*
X532374D01*
G01X544295Y1113522D02*
X544045Y1113647D01*
X543753Y1113730D01*
X543420D01*
X543045Y1113605D01*
X542753Y1113397D01*
X542545Y1113147D01*
X542378Y1112730D01*
X542336Y1112355D01*
X542420Y1111980D01*
X542545Y1111730D01*
X542795Y1111480D01*
X543086Y1111313D01*
X543378Y1111230D01*
X543670D01*
X543961Y1111313D01*
X544211Y1111438D01*
X544420Y1111605D01*
G01X546478Y1111230D02*
Y1113730D01*
X545978Y1113230D01*
G01Y1111230D02*
X546978D01*
G01X549578Y1113730D02*
X549245Y1113647D01*
X548995Y1113438D01*
X548828Y1113188D01*
X548703Y1112855D01*
X548661Y1112480D01*
X548703Y1112105D01*
X548828Y1111772D01*
X548995Y1111522D01*
X549245Y1111313D01*
X549578Y1111230D01*
X549911Y1111313D01*
X550161Y1111522D01*
X550328Y1111772D01*
X550453Y1112105D01*
X550495Y1112480D01*
X550453Y1112855D01*
X550328Y1113188D01*
X550161Y1113438D01*
X549911Y1113647D01*
X549578Y1113730D01*
G01X552678Y1111230D02*
Y1113730D01*
X552178Y1113230D01*
G01Y1111230D02*
X553178D01*
G01X545880Y1105174D02*
X545630Y1105299D01*
X545338Y1105382D01*
X545005D01*
X544630Y1105257D01*
X544338Y1105049D01*
X544130Y1104799D01*
X543963Y1104382D01*
X543921Y1104007D01*
X544005Y1103632D01*
X544130Y1103382D01*
X544380Y1103132D01*
X544671Y1102965D01*
X544963Y1102882D01*
X545255D01*
X545546Y1102965D01*
X545796Y1103090D01*
X546005Y1103257D01*
G01X548063Y1102882D02*
Y1105382D01*
X547563Y1104882D01*
G01Y1102882D02*
X548563D01*
G01X551163Y1105382D02*
X550830Y1105299D01*
X550580Y1105090D01*
X550413Y1104840D01*
X550288Y1104507D01*
X550246Y1104132D01*
X550288Y1103757D01*
X550413Y1103424D01*
X550580Y1103174D01*
X550830Y1102965D01*
X551163Y1102882D01*
X551496Y1102965D01*
X551746Y1103174D01*
X551913Y1103424D01*
X552038Y1103757D01*
X552080Y1104132D01*
X552038Y1104507D01*
X551913Y1104840D01*
X551746Y1105090D01*
X551496Y1105299D01*
X551163Y1105382D01*
G01X554263D02*
X553930Y1105299D01*
X553680Y1105090D01*
X553513Y1104840D01*
X553388Y1104507D01*
X553346Y1104132D01*
X553388Y1103757D01*
X553513Y1103424D01*
X553680Y1103174D01*
X553930Y1102965D01*
X554263Y1102882D01*
X554596Y1102965D01*
X554846Y1103174D01*
X555013Y1103424D01*
X555138Y1103757D01*
X555180Y1104132D01*
X555138Y1104507D01*
X555013Y1104840D01*
X554846Y1105090D01*
X554596Y1105299D01*
X554263Y1105382D01*
G01X521051Y1165084D02*
Y1161084D01*
X528451D01*
G01X511774Y1159473D02*
X519774D01*
Y1141873D01*
X511774D01*
Y1159473D01*
G01X534000Y1171350D02*
X533958Y1171017D01*
X533792Y1170725D01*
X533542Y1170475D01*
X533250Y1170308D01*
X532917Y1170225D01*
X532583D01*
X532250Y1170308D01*
X531958Y1170475D01*
X531708Y1170725D01*
X531542Y1171017D01*
X531500Y1171350D01*
X531542Y1171683D01*
X531708Y1171975D01*
X531958Y1172225D01*
X532250Y1172392D01*
X532583Y1172475D01*
X532917D01*
X533250Y1172392D01*
X533542Y1172225D01*
X533792Y1171975D01*
X533958Y1171683D01*
X534000Y1171350D01*
G01X533333Y1171683D02*
X534000Y1172183D01*
G01X531917Y1173658D02*
X531667Y1173908D01*
X531542Y1174200D01*
X531500Y1174533D01*
X531583Y1174950D01*
X531792Y1175242D01*
X532042Y1175325D01*
X532292Y1175283D01*
X532500Y1175117D01*
X532917Y1174283D01*
X533208Y1173908D01*
X533625Y1173658D01*
X534000Y1173575D01*
Y1175325D01*
G01X533708Y1176842D02*
X533917Y1177133D01*
X534000Y1177467D01*
X533917Y1177800D01*
X533667Y1178092D01*
X533292Y1178300D01*
X532917Y1178383D01*
X532458D01*
X532083Y1178300D01*
X531750Y1178092D01*
X531583Y1177842D01*
X531500Y1177550D01*
X531583Y1177217D01*
X531750Y1176967D01*
X532000Y1176800D01*
X532333Y1176717D01*
X532625Y1176800D01*
X532917Y1177008D01*
X533083Y1177258D01*
X533125Y1177550D01*
X533042Y1177883D01*
X532833Y1178133D01*
X532458Y1178383D01*
G01X534000Y1180650D02*
X531500D01*
X532000Y1180150D01*
G01X534000D02*
Y1181150D01*
G01X516148Y1183366D02*
Y1169366D01*
G01X529148D02*
Y1183366D01*
G01X516148Y1169366D02*
X529148D01*
G01X549793Y1167782D02*
X549543Y1167907D01*
X549251Y1167990D01*
X548918D01*
X548543Y1167865D01*
X548251Y1167657D01*
X548043Y1167407D01*
X547876Y1166990D01*
X547834Y1166615D01*
X547918Y1166240D01*
X548043Y1165990D01*
X548293Y1165740D01*
X548584Y1165573D01*
X548876Y1165490D01*
X549168D01*
X549459Y1165573D01*
X549709Y1165698D01*
X549918Y1165865D01*
G01X551268Y1165782D02*
X551559Y1165573D01*
X551893Y1165490D01*
X552226Y1165573D01*
X552518Y1165823D01*
X552726Y1166198D01*
X552809Y1166573D01*
Y1167032D01*
X552726Y1167407D01*
X552518Y1167740D01*
X552268Y1167907D01*
X551976Y1167990D01*
X551643Y1167907D01*
X551393Y1167740D01*
X551226Y1167490D01*
X551143Y1167157D01*
X551226Y1166865D01*
X551434Y1166573D01*
X551684Y1166407D01*
X551976Y1166365D01*
X552309Y1166448D01*
X552559Y1166657D01*
X552809Y1167032D01*
G01X554993Y1165490D02*
X555076Y1166032D01*
X555201Y1166490D01*
X555368Y1166907D01*
X555576Y1167365D01*
X555909Y1167990D01*
X554243D01*
G01X526817Y1140559D02*
X526567Y1140684D01*
X526275Y1140767D01*
X525942D01*
X525567Y1140642D01*
X525275Y1140434D01*
X525067Y1140184D01*
X524900Y1139767D01*
X524858Y1139392D01*
X524942Y1139017D01*
X525067Y1138767D01*
X525317Y1138517D01*
X525608Y1138350D01*
X525900Y1138267D01*
X526192D01*
X526483Y1138350D01*
X526733Y1138475D01*
X526942Y1138642D01*
G01X529000Y1138267D02*
X529292Y1138309D01*
X529625Y1138434D01*
X529833Y1138642D01*
X529917Y1138934D01*
X529833Y1139225D01*
X529583Y1139475D01*
X529208Y1139600D01*
X528792D01*
X528542Y1139684D01*
X528333Y1139892D01*
X528250Y1140184D01*
X528375Y1140475D01*
X528667Y1140684D01*
X529000Y1140767D01*
X529333Y1140684D01*
X529625Y1140475D01*
X529750Y1140184D01*
X529667Y1139892D01*
X529458Y1139684D01*
X529208Y1139600D01*
X528792D01*
X528417Y1139475D01*
X528167Y1139225D01*
X528083Y1138934D01*
X528167Y1138642D01*
X528375Y1138434D01*
X528708Y1138309D01*
X529000Y1138267D01*
G01X532100Y1140767D02*
X531767Y1140684D01*
X531517Y1140475D01*
X531350Y1140225D01*
X531225Y1139892D01*
X531183Y1139517D01*
X531225Y1139142D01*
X531350Y1138809D01*
X531517Y1138559D01*
X531767Y1138350D01*
X532100Y1138267D01*
X532433Y1138350D01*
X532683Y1138559D01*
X532850Y1138809D01*
X532975Y1139142D01*
X533017Y1139517D01*
X532975Y1139892D01*
X532850Y1140225D01*
X532683Y1140475D01*
X532433Y1140684D01*
X532100Y1140767D01*
G01X520574Y1149973D02*
X526074D01*
G01X520574Y1141973D02*
Y1149973D01*
G01X526074Y1141973D02*
X520574D01*
G01X538174D02*
X532674D01*
G01X538174Y1149973D02*
Y1141973D01*
G01X532674Y1149973D02*
X538174D01*
G01X544587Y1143173D02*
X546687Y1141373D01*
X544587Y1139173D01*
G01X544487Y1135573D02*
X563687D01*
Y1146773D01*
X544487D01*
Y1135573D01*
X544887D01*
G01X528417Y1158159D02*
X528167Y1158284D01*
X527875Y1158367D01*
X527542D01*
X527167Y1158242D01*
X526875Y1158034D01*
X526667Y1157784D01*
X526500Y1157367D01*
X526458Y1156992D01*
X526542Y1156617D01*
X526667Y1156367D01*
X526917Y1156117D01*
X527208Y1155950D01*
X527500Y1155867D01*
X527792D01*
X528083Y1155950D01*
X528333Y1156075D01*
X528542Y1156242D01*
G01X530517Y1155867D02*
X530600Y1156409D01*
X530725Y1156867D01*
X530892Y1157284D01*
X531100Y1157742D01*
X531433Y1158367D01*
X529767D01*
G01X532992Y1156159D02*
X533283Y1155950D01*
X533617Y1155867D01*
X533950Y1155950D01*
X534242Y1156200D01*
X534450Y1156575D01*
X534533Y1156950D01*
Y1157409D01*
X534450Y1157784D01*
X534242Y1158117D01*
X533992Y1158284D01*
X533700Y1158367D01*
X533367Y1158284D01*
X533117Y1158117D01*
X532950Y1157867D01*
X532867Y1157534D01*
X532950Y1157242D01*
X533158Y1156950D01*
X533408Y1156784D01*
X533700Y1156742D01*
X534033Y1156825D01*
X534283Y1157034D01*
X534533Y1157409D01*
G01X530017Y1185400D02*
Y1187900D01*
X531058D01*
X531392Y1187775D01*
X531600Y1187608D01*
X531683Y1187275D01*
X531600Y1186942D01*
X531350Y1186733D01*
X531058Y1186608D01*
X530017D01*
G01X531058D02*
X531683Y1185400D01*
G01X533033Y1185775D02*
X533283Y1185567D01*
X533575Y1185442D01*
X533950Y1185400D01*
X534325Y1185483D01*
X534617Y1185650D01*
X534825Y1185942D01*
X534867Y1186275D01*
X534783Y1186608D01*
X534575Y1186817D01*
X534283Y1186983D01*
X533992Y1187025D01*
X533700Y1186983D01*
X533325Y1186817D01*
X533450Y1187900D01*
X534575D01*
G01X536967Y1185400D02*
X537050Y1185942D01*
X537175Y1186400D01*
X537342Y1186817D01*
X537550Y1187275D01*
X537883Y1187900D01*
X536217D01*
G01X540150D02*
X539817Y1187817D01*
X539567Y1187608D01*
X539400Y1187358D01*
X539275Y1187025D01*
X539233Y1186650D01*
X539275Y1186275D01*
X539400Y1185942D01*
X539567Y1185692D01*
X539817Y1185483D01*
X540150Y1185400D01*
X540483Y1185483D01*
X540733Y1185692D01*
X540900Y1185942D01*
X541025Y1186275D01*
X541067Y1186650D01*
X541025Y1187025D01*
X540900Y1187358D01*
X540733Y1187608D01*
X540483Y1187817D01*
X540150Y1187900D01*
G01X520917Y1188666D02*
Y1184666D01*
X528317D01*
G01X529148Y1183366D02*
X516148D01*
G01X517850Y1205500D02*
X517517Y1205542D01*
X517225Y1205708D01*
X516975Y1205958D01*
X516808Y1206250D01*
X516725Y1206583D01*
Y1206917D01*
X516808Y1207250D01*
X516975Y1207542D01*
X517225Y1207792D01*
X517517Y1207958D01*
X517850Y1208000D01*
X518183Y1207958D01*
X518475Y1207792D01*
X518725Y1207542D01*
X518892Y1207250D01*
X518975Y1206917D01*
Y1206583D01*
X518892Y1206250D01*
X518725Y1205958D01*
X518475Y1205708D01*
X518183Y1205542D01*
X517850Y1205500D01*
G01X518183Y1206167D02*
X518683Y1205500D01*
G01X520158Y1207583D02*
X520408Y1207833D01*
X520700Y1207958D01*
X521033Y1208000D01*
X521450Y1207917D01*
X521742Y1207708D01*
X521825Y1207458D01*
X521783Y1207208D01*
X521617Y1207000D01*
X520783Y1206583D01*
X520408Y1206292D01*
X520158Y1205875D01*
X520075Y1205500D01*
X521825D01*
G01X523133Y1205875D02*
X523383Y1205667D01*
X523675Y1205542D01*
X524050Y1205500D01*
X524425Y1205583D01*
X524717Y1205750D01*
X524925Y1206042D01*
X524967Y1206375D01*
X524883Y1206708D01*
X524675Y1206917D01*
X524383Y1207083D01*
X524092Y1207125D01*
X523800Y1207083D01*
X523425Y1206917D01*
X523550Y1208000D01*
X524675D01*
G01X526233Y1205875D02*
X526483Y1205667D01*
X526775Y1205542D01*
X527150Y1205500D01*
X527525Y1205583D01*
X527817Y1205750D01*
X528025Y1206042D01*
X528067Y1206375D01*
X527983Y1206708D01*
X527775Y1206917D01*
X527483Y1207083D01*
X527192Y1207125D01*
X526900Y1207083D01*
X526525Y1206917D01*
X526650Y1208000D01*
X527775D01*
G01X516013Y1203432D02*
Y1189432D01*
G01X529013Y1203432D02*
X516013D01*
G01X529013Y1189432D02*
Y1203432D01*
G01X516013Y1189432D02*
X529013D01*
G01X514103Y1204674D02*
X511603D01*
Y1205715D01*
X511728Y1206049D01*
X511895Y1206257D01*
X512228Y1206340D01*
X512561Y1206257D01*
X512770Y1206007D01*
X512895Y1205715D01*
Y1204674D01*
G01Y1205715D02*
X514103Y1206340D01*
G01X512020Y1207815D02*
X511770Y1208065D01*
X511645Y1208357D01*
X511603Y1208690D01*
X511686Y1209107D01*
X511895Y1209399D01*
X512145Y1209482D01*
X512395Y1209440D01*
X512603Y1209274D01*
X513020Y1208440D01*
X513311Y1208065D01*
X513728Y1207815D01*
X514103Y1207732D01*
Y1209482D01*
G01X513728Y1210790D02*
X513936Y1211040D01*
X514061Y1211332D01*
X514103Y1211707D01*
X514020Y1212082D01*
X513853Y1212374D01*
X513561Y1212582D01*
X513228Y1212624D01*
X512895Y1212540D01*
X512686Y1212332D01*
X512520Y1212040D01*
X512478Y1211749D01*
X512520Y1211457D01*
X512686Y1211082D01*
X511603Y1211207D01*
Y1212332D01*
G01X514103Y1214807D02*
X511603D01*
X512103Y1214307D01*
G01X514103D02*
Y1215307D01*
G01X590974Y221492D02*
X596024D01*
Y320192D01*
X620674D01*
Y135792D01*
X596024D01*
Y194492D01*
X590974D01*
Y221492D01*
G01X566900Y164017D02*
X564400D01*
Y165058D01*
X564525Y165392D01*
X564692Y165600D01*
X565025Y165683D01*
X565358Y165600D01*
X565567Y165350D01*
X565692Y165058D01*
Y164017D01*
G01Y165058D02*
X566900Y165683D01*
G01Y167867D02*
X566358Y167950D01*
X565900Y168075D01*
X565483Y168242D01*
X565025Y168450D01*
X564400Y168783D01*
Y167117D01*
G01X566608Y170342D02*
X566817Y170633D01*
X566900Y170967D01*
X566817Y171300D01*
X566567Y171592D01*
X566192Y171800D01*
X565817Y171883D01*
X565358D01*
X564983Y171800D01*
X564650Y171592D01*
X564483Y171342D01*
X564400Y171050D01*
X564483Y170717D01*
X564650Y170467D01*
X564900Y170300D01*
X565233Y170217D01*
X565525Y170300D01*
X565817Y170508D01*
X565983Y170758D01*
X566025Y171050D01*
X565942Y171383D01*
X565733Y171633D01*
X565358Y171883D01*
G01X566900Y174150D02*
X564400D01*
X564900Y173650D01*
G01X566900D02*
Y174650D01*
G01X582587Y162510D02*
Y165010D01*
X583628D01*
X583962Y164885D01*
X584170Y164718D01*
X584253Y164385D01*
X584170Y164052D01*
X583920Y163843D01*
X583628Y163718D01*
X582587D01*
G01X583628D02*
X584253Y162510D01*
G01X586437D02*
X586520Y163052D01*
X586645Y163510D01*
X586812Y163927D01*
X587020Y164385D01*
X587353Y165010D01*
X585687D01*
G01X589620Y162510D02*
X589912Y162552D01*
X590245Y162677D01*
X590453Y162885D01*
X590537Y163177D01*
X590453Y163468D01*
X590203Y163718D01*
X589828Y163843D01*
X589412D01*
X589162Y163927D01*
X588953Y164135D01*
X588870Y164427D01*
X588995Y164718D01*
X589287Y164927D01*
X589620Y165010D01*
X589953Y164927D01*
X590245Y164718D01*
X590370Y164427D01*
X590287Y164135D01*
X590078Y163927D01*
X589828Y163843D01*
X589412D01*
X589037Y163718D01*
X588787Y163468D01*
X588703Y163177D01*
X588787Y162885D01*
X588995Y162677D01*
X589328Y162552D01*
X589620Y162510D01*
G01X591803Y162885D02*
X592053Y162677D01*
X592345Y162552D01*
X592720Y162510D01*
X593095Y162593D01*
X593387Y162760D01*
X593595Y163052D01*
X593637Y163385D01*
X593553Y163718D01*
X593345Y163927D01*
X593053Y164093D01*
X592762Y164135D01*
X592470Y164093D01*
X592095Y163927D01*
X592220Y165010D01*
X593345D01*
G01X571687Y183361D02*
X567687D01*
Y175961D01*
G01X591087Y174661D02*
Y178661D01*
X583687D01*
G01X582587Y166210D02*
Y168710D01*
X583628D01*
X583962Y168585D01*
X584170Y168418D01*
X584253Y168085D01*
X584170Y167752D01*
X583920Y167543D01*
X583628Y167418D01*
X582587D01*
G01X583628D02*
X584253Y166210D01*
G01X586437D02*
X586520Y166752D01*
X586645Y167210D01*
X586812Y167627D01*
X587020Y168085D01*
X587353Y168710D01*
X585687D01*
G01X589620Y166210D02*
X589912Y166252D01*
X590245Y166377D01*
X590453Y166585D01*
X590537Y166877D01*
X590453Y167168D01*
X590203Y167418D01*
X589828Y167543D01*
X589412D01*
X589162Y167627D01*
X588953Y167835D01*
X588870Y168127D01*
X588995Y168418D01*
X589287Y168627D01*
X589620Y168710D01*
X589953Y168627D01*
X590245Y168418D01*
X590370Y168127D01*
X590287Y167835D01*
X590078Y167627D01*
X589828Y167543D01*
X589412D01*
X589037Y167418D01*
X588787Y167168D01*
X588703Y166877D01*
X588787Y166585D01*
X588995Y166377D01*
X589328Y166252D01*
X589620Y166210D01*
G01X591928Y168293D02*
X592178Y168543D01*
X592470Y168668D01*
X592803Y168710D01*
X593220Y168627D01*
X593512Y168418D01*
X593595Y168168D01*
X593553Y167918D01*
X593387Y167710D01*
X592553Y167293D01*
X592178Y167002D01*
X591928Y166585D01*
X591845Y166210D01*
X593595D01*
G01X591087Y179361D02*
Y183361D01*
X583687D01*
G01X582587Y169910D02*
Y172410D01*
X583628D01*
X583962Y172285D01*
X584170Y172118D01*
X584253Y171785D01*
X584170Y171452D01*
X583920Y171243D01*
X583628Y171118D01*
X582587D01*
G01X583628D02*
X584253Y169910D01*
G01X586437D02*
X586520Y170452D01*
X586645Y170910D01*
X586812Y171327D01*
X587020Y171785D01*
X587353Y172410D01*
X585687D01*
G01X589620Y169910D02*
X589912Y169952D01*
X590245Y170077D01*
X590453Y170285D01*
X590537Y170577D01*
X590453Y170868D01*
X590203Y171118D01*
X589828Y171243D01*
X589412D01*
X589162Y171327D01*
X588953Y171535D01*
X588870Y171827D01*
X588995Y172118D01*
X589287Y172327D01*
X589620Y172410D01*
X589953Y172327D01*
X590245Y172118D01*
X590370Y171827D01*
X590287Y171535D01*
X590078Y171327D01*
X589828Y171243D01*
X589412D01*
X589037Y171118D01*
X588787Y170868D01*
X588703Y170577D01*
X588787Y170285D01*
X588995Y170077D01*
X589328Y169952D01*
X589620Y169910D01*
G01X592637D02*
X592720Y170452D01*
X592845Y170910D01*
X593012Y171327D01*
X593220Y171785D01*
X593553Y172410D01*
X591887D01*
G01X583687Y193161D02*
Y189161D01*
X591087D01*
G01X559487Y206861D02*
Y202861D01*
X566887D01*
G01X569752Y172176D02*
X569419Y172218D01*
X569127Y172384D01*
X568877Y172634D01*
X568710Y172926D01*
X568627Y173259D01*
Y173593D01*
X568710Y173926D01*
X568877Y174218D01*
X569127Y174468D01*
X569419Y174634D01*
X569752Y174676D01*
X570085Y174634D01*
X570377Y174468D01*
X570627Y174218D01*
X570794Y173926D01*
X570877Y173593D01*
Y173259D01*
X570794Y172926D01*
X570627Y172634D01*
X570377Y172384D01*
X570085Y172218D01*
X569752Y172176D01*
G01X570085Y172843D02*
X570585Y172176D01*
G01X572852D02*
Y174676D01*
X572352Y174176D01*
G01Y172176D02*
X573352D01*
G01X575160Y173218D02*
X575452Y173509D01*
X575702Y173676D01*
X576035Y173759D01*
X576327Y173676D01*
X576535Y173509D01*
X576702Y173259D01*
X576744Y172968D01*
X576702Y172718D01*
X576535Y172468D01*
X576285Y172259D01*
X575994Y172176D01*
X575660Y172259D01*
X575369Y172509D01*
X575202Y172884D01*
X575160Y173301D01*
X575244Y173843D01*
X575369Y174134D01*
X575577Y174426D01*
X575869Y174634D01*
X576160Y174676D01*
X576452Y174593D01*
X576660Y174384D01*
G01X578344Y172468D02*
X578635Y172259D01*
X578969Y172176D01*
X579302Y172259D01*
X579594Y172509D01*
X579802Y172884D01*
X579885Y173259D01*
Y173718D01*
X579802Y174093D01*
X579594Y174426D01*
X579344Y174593D01*
X579052Y174676D01*
X578719Y174593D01*
X578469Y174426D01*
X578302Y174176D01*
X578219Y173843D01*
X578302Y173551D01*
X578510Y173259D01*
X578760Y173093D01*
X579052Y173051D01*
X579385Y173134D01*
X579635Y173343D01*
X579885Y173718D01*
G01X582987Y197861D02*
X571587D01*
G01X582987Y184461D02*
Y197861D01*
G01X571587Y184461D02*
X582987D01*
G01X571587Y197861D02*
Y184461D01*
G01X562000Y166483D02*
X559500D01*
Y167317D01*
X559625Y167650D01*
X559792Y167900D01*
X560042Y168108D01*
X560333Y168275D01*
X560750Y168317D01*
X561167Y168275D01*
X561458Y168108D01*
X561708Y167900D01*
X561875Y167650D01*
X562000Y167317D01*
Y166483D01*
G01X559917Y169708D02*
X559667Y169958D01*
X559542Y170250D01*
X559500Y170583D01*
X559583Y171000D01*
X559792Y171292D01*
X560042Y171375D01*
X560292Y171333D01*
X560500Y171167D01*
X560917Y170333D01*
X561208Y169958D01*
X561625Y169708D01*
X562000Y169625D01*
Y171375D01*
G01Y173600D02*
X561958Y173892D01*
X561833Y174225D01*
X561625Y174433D01*
X561333Y174517D01*
X561042Y174433D01*
X560792Y174183D01*
X560667Y173808D01*
Y173392D01*
X560583Y173142D01*
X560375Y172933D01*
X560083Y172850D01*
X559792Y172975D01*
X559583Y173267D01*
X559500Y173600D01*
X559583Y173933D01*
X559792Y174225D01*
X560083Y174350D01*
X560375Y174267D01*
X560583Y174058D01*
X560667Y173808D01*
Y173392D01*
X560792Y173017D01*
X561042Y172767D01*
X561333Y172683D01*
X561625Y172767D01*
X561833Y172975D01*
X561958Y173308D01*
X562000Y173600D01*
G01X566787Y192161D02*
Y176061D01*
G01X559787Y192161D02*
X566787D01*
G01X559787Y176061D02*
Y192161D01*
G01X566787Y176061D02*
X559787D01*
G01X589087Y223261D02*
X569887D01*
Y212061D01*
X589087D01*
Y223261D01*
X588687D01*
G01X562487Y250661D02*
Y258661D01*
X580087D01*
Y250661D01*
X562487D01*
G01X591000Y255517D02*
X588500D01*
Y256558D01*
X588625Y256892D01*
X588792Y257100D01*
X589125Y257183D01*
X589458Y257100D01*
X589667Y256850D01*
X589792Y256558D01*
Y255517D01*
G01Y256558D02*
X591000Y257183D01*
G01Y259367D02*
X590458Y259450D01*
X590000Y259575D01*
X589583Y259742D01*
X589125Y259950D01*
X588500Y260283D01*
Y258617D01*
G01X591000Y262467D02*
X590458Y262550D01*
X590000Y262675D01*
X589583Y262842D01*
X589125Y263050D01*
X588500Y263383D01*
Y261717D01*
G01X590500Y264733D02*
X590792Y264983D01*
X590958Y265317D01*
X591000Y265692D01*
X590958Y266025D01*
X590750Y266358D01*
X590500Y266567D01*
X590250Y266608D01*
X589958Y266525D01*
X589750Y266233D01*
X589667Y265942D01*
Y265567D01*
G01Y265942D02*
X589542Y266192D01*
X589333Y266400D01*
X589083Y266483D01*
X588833Y266400D01*
X588625Y266192D01*
X588500Y265817D01*
X588542Y265442D01*
X588708Y265067D01*
G01X586287Y253961D02*
X594287D01*
Y236361D01*
X586287D01*
Y253961D01*
G01X584587Y236161D02*
X579087D01*
G01X584587Y244161D02*
Y236161D01*
G01X579087Y244161D02*
X584587D01*
G01X566987D02*
X572487D01*
G01X566987Y236161D02*
Y244161D01*
G01X572487Y236161D02*
X566987D01*
G01X593000Y224850D02*
X592958Y224517D01*
X592792Y224225D01*
X592542Y223975D01*
X592250Y223808D01*
X591917Y223725D01*
X591583D01*
X591250Y223808D01*
X590958Y223975D01*
X590708Y224225D01*
X590542Y224517D01*
X590500Y224850D01*
X590542Y225183D01*
X590708Y225475D01*
X590958Y225725D01*
X591250Y225892D01*
X591583Y225975D01*
X591917D01*
X592250Y225892D01*
X592542Y225725D01*
X592792Y225475D01*
X592958Y225183D01*
X593000Y224850D01*
G01X592333Y225183D02*
X593000Y225683D01*
G01Y227950D02*
X590500D01*
X591000Y227450D01*
G01X593000D02*
Y228450D01*
G01X591958Y230258D02*
X591667Y230550D01*
X591500Y230800D01*
X591417Y231133D01*
X591500Y231425D01*
X591667Y231633D01*
X591917Y231800D01*
X592208Y231842D01*
X592458Y231800D01*
X592708Y231633D01*
X592917Y231383D01*
X593000Y231092D01*
X592917Y230758D01*
X592667Y230467D01*
X592292Y230300D01*
X591875Y230258D01*
X591333Y230342D01*
X591042Y230467D01*
X590750Y230675D01*
X590542Y230967D01*
X590500Y231258D01*
X590583Y231550D01*
X590792Y231758D01*
G01X593000Y234150D02*
X592958Y234442D01*
X592833Y234775D01*
X592625Y234983D01*
X592333Y235067D01*
X592042Y234983D01*
X591792Y234733D01*
X591667Y234358D01*
Y233942D01*
X591583Y233692D01*
X591375Y233483D01*
X591083Y233400D01*
X590792Y233525D01*
X590583Y233817D01*
X590500Y234150D01*
X590583Y234483D01*
X590792Y234775D01*
X591083Y234900D01*
X591375Y234817D01*
X591583Y234608D01*
X591667Y234358D01*
Y233942D01*
X591792Y233567D01*
X592042Y233317D01*
X592333Y233233D01*
X592625Y233317D01*
X592833Y233525D01*
X592958Y233858D01*
X593000Y234150D01*
G01X588987Y215661D02*
X586887Y217461D01*
X588987Y219661D01*
G01X568517Y271500D02*
Y274000D01*
X569558D01*
X569892Y273875D01*
X570100Y273708D01*
X570183Y273375D01*
X570100Y273042D01*
X569850Y272833D01*
X569558Y272708D01*
X568517D01*
G01X569558D02*
X570183Y271500D01*
G01X572367D02*
X572450Y272042D01*
X572575Y272500D01*
X572742Y272917D01*
X572950Y273375D01*
X573283Y274000D01*
X571617D01*
G01X575467Y271500D02*
X575550Y272042D01*
X575675Y272500D01*
X575842Y272917D01*
X576050Y273375D01*
X576383Y274000D01*
X574717D01*
G01X577733Y271875D02*
X577983Y271667D01*
X578275Y271542D01*
X578650Y271500D01*
X579025Y271583D01*
X579317Y271750D01*
X579525Y272042D01*
X579567Y272375D01*
X579483Y272708D01*
X579275Y272917D01*
X578983Y273083D01*
X578692Y273125D01*
X578400Y273083D01*
X578025Y272917D01*
X578150Y274000D01*
X579275D01*
G01X584208Y280767D02*
X584083Y280517D01*
X584000Y280225D01*
Y279892D01*
X584125Y279517D01*
X584333Y279225D01*
X584583Y279017D01*
X585000Y278850D01*
X585375Y278808D01*
X585750Y278892D01*
X586000Y279017D01*
X586250Y279267D01*
X586417Y279558D01*
X586500Y279850D01*
Y280142D01*
X586417Y280433D01*
X586292Y280683D01*
X586125Y280892D01*
G01X586500Y283450D02*
X584000D01*
X585792Y281908D01*
Y283992D01*
G01X584000Y286050D02*
X584083Y285717D01*
X584292Y285467D01*
X584542Y285300D01*
X584875Y285175D01*
X585250Y285133D01*
X585625Y285175D01*
X585958Y285300D01*
X586208Y285467D01*
X586417Y285717D01*
X586500Y286050D01*
X586417Y286383D01*
X586208Y286633D01*
X585958Y286800D01*
X585625Y286925D01*
X585250Y286967D01*
X584875Y286925D01*
X584542Y286800D01*
X584292Y286633D01*
X584083Y286383D01*
X584000Y286050D01*
G01X586208Y288442D02*
X586417Y288733D01*
X586500Y289067D01*
X586417Y289400D01*
X586167Y289692D01*
X585792Y289900D01*
X585417Y289983D01*
X584958D01*
X584583Y289900D01*
X584250Y289692D01*
X584083Y289442D01*
X584000Y289150D01*
X584083Y288817D01*
X584250Y288567D01*
X584500Y288400D01*
X584833Y288317D01*
X585125Y288400D01*
X585417Y288608D01*
X585583Y288858D01*
X585625Y289150D01*
X585542Y289483D01*
X585333Y289733D01*
X584958Y289983D01*
G01X570267Y265792D02*
X570017Y265917D01*
X569725Y266000D01*
X569392D01*
X569017Y265875D01*
X568725Y265667D01*
X568517Y265417D01*
X568350Y265000D01*
X568308Y264625D01*
X568392Y264250D01*
X568517Y264000D01*
X568767Y263750D01*
X569058Y263583D01*
X569350Y263500D01*
X569642D01*
X569933Y263583D01*
X570183Y263708D01*
X570392Y263875D01*
G01X572950Y263500D02*
Y266000D01*
X571408Y264208D01*
X573492D01*
G01X575550Y266000D02*
X575217Y265917D01*
X574967Y265708D01*
X574800Y265458D01*
X574675Y265125D01*
X574633Y264750D01*
X574675Y264375D01*
X574800Y264042D01*
X574967Y263792D01*
X575217Y263583D01*
X575550Y263500D01*
X575883Y263583D01*
X576133Y263792D01*
X576300Y264042D01*
X576425Y264375D01*
X576467Y264750D01*
X576425Y265125D01*
X576300Y265458D01*
X576133Y265708D01*
X575883Y265917D01*
X575550Y266000D01*
G01X577733Y263875D02*
X577983Y263667D01*
X578275Y263542D01*
X578650Y263500D01*
X579025Y263583D01*
X579317Y263750D01*
X579525Y264042D01*
X579567Y264375D01*
X579483Y264708D01*
X579275Y264917D01*
X578983Y265083D01*
X578692Y265125D01*
X578400Y265083D01*
X578025Y264917D01*
X578150Y266000D01*
X579275D01*
G01X570267Y269792D02*
X570017Y269917D01*
X569725Y270000D01*
X569392D01*
X569017Y269875D01*
X568725Y269667D01*
X568517Y269417D01*
X568350Y269000D01*
X568308Y268625D01*
X568392Y268250D01*
X568517Y268000D01*
X568767Y267750D01*
X569058Y267583D01*
X569350Y267500D01*
X569642D01*
X569933Y267583D01*
X570183Y267708D01*
X570392Y267875D01*
G01X572950Y267500D02*
Y270000D01*
X571408Y268208D01*
X573492D01*
G01X575550Y270000D02*
X575217Y269917D01*
X574967Y269708D01*
X574800Y269458D01*
X574675Y269125D01*
X574633Y268750D01*
X574675Y268375D01*
X574800Y268042D01*
X574967Y267792D01*
X575217Y267583D01*
X575550Y267500D01*
X575883Y267583D01*
X576133Y267792D01*
X576300Y268042D01*
X576425Y268375D01*
X576467Y268750D01*
X576425Y269125D01*
X576300Y269458D01*
X576133Y269708D01*
X575883Y269917D01*
X575550Y270000D01*
G01X579150Y267500D02*
Y270000D01*
X577608Y268208D01*
X579692D01*
G01X586708Y293267D02*
X586583Y293017D01*
X586500Y292725D01*
Y292392D01*
X586625Y292017D01*
X586833Y291725D01*
X587083Y291517D01*
X587500Y291350D01*
X587875Y291308D01*
X588250Y291392D01*
X588500Y291517D01*
X588750Y291767D01*
X588917Y292058D01*
X589000Y292350D01*
Y292642D01*
X588917Y292933D01*
X588792Y293183D01*
X588625Y293392D01*
G01X589000Y295950D02*
X586500D01*
X588292Y294408D01*
Y296492D01*
G01X589000Y298550D02*
X586500D01*
X587000Y298050D01*
G01X589000D02*
Y299050D01*
G01Y301650D02*
X586500D01*
X587000Y301150D01*
G01X589000D02*
Y302150D01*
G01X597149Y329492D02*
Y331992D01*
G01X598899D02*
Y329492D01*
G01Y330742D02*
X597149D01*
G01X600207Y329492D02*
Y331992D01*
X601041D01*
X601374Y331867D01*
X601624Y331700D01*
X601832Y331450D01*
X601999Y331159D01*
X602041Y330742D01*
X601999Y330325D01*
X601832Y330034D01*
X601624Y329784D01*
X601374Y329617D01*
X601041Y329492D01*
X600207D01*
G01X603307D02*
Y331992D01*
X604141D01*
X604474Y331867D01*
X604724Y331700D01*
X604932Y331450D01*
X605099Y331159D01*
X605141Y330742D01*
X605099Y330325D01*
X604932Y330034D01*
X604724Y329784D01*
X604474Y329617D01*
X604141Y329492D01*
X603307D01*
G01X606449Y329825D02*
X606782Y329617D01*
X607157Y329492D01*
X607491D01*
X607824Y329617D01*
X608074Y329825D01*
X608199Y330117D01*
X608116Y330409D01*
X607907Y330659D01*
X607532Y330825D01*
X607032Y330909D01*
X606741Y331075D01*
X606616Y331367D01*
X606699Y331659D01*
X606907Y331867D01*
X607199Y331992D01*
X607491D01*
X607782Y331909D01*
X608032Y331700D01*
G01X609382Y329492D02*
X610424Y331992D01*
X611466Y329492D01*
G01X611091Y330367D02*
X609757D01*
G01X612649Y329825D02*
X612982Y329617D01*
X613357Y329492D01*
X613691D01*
X614024Y329617D01*
X614274Y329825D01*
X614399Y330117D01*
X614316Y330409D01*
X614107Y330659D01*
X613732Y330825D01*
X613232Y330909D01*
X612941Y331075D01*
X612816Y331367D01*
X612899Y331659D01*
X613107Y331867D01*
X613399Y331992D01*
X613691D01*
X613982Y331909D01*
X614232Y331700D01*
G01X615832Y331575D02*
X616082Y331825D01*
X616374Y331950D01*
X616707Y331992D01*
X617124Y331909D01*
X617416Y331700D01*
X617499Y331450D01*
X617457Y331200D01*
X617291Y330992D01*
X616457Y330575D01*
X616082Y330284D01*
X615832Y329867D01*
X615749Y329492D01*
X617499D01*
G01X619724D02*
X620016Y329534D01*
X620349Y329659D01*
X620557Y329867D01*
X620641Y330159D01*
X620557Y330450D01*
X620307Y330700D01*
X619932Y330825D01*
X619516D01*
X619266Y330909D01*
X619057Y331117D01*
X618974Y331409D01*
X619099Y331700D01*
X619391Y331909D01*
X619724Y331992D01*
X620057Y331909D01*
X620349Y331700D01*
X620474Y331409D01*
X620391Y331117D01*
X620182Y330909D01*
X619932Y330825D01*
X619516D01*
X619141Y330700D01*
X618891Y330450D01*
X618807Y330159D01*
X618891Y329867D01*
X619099Y329659D01*
X619432Y329534D01*
X619724Y329492D01*
G01X557458Y357500D02*
Y360000D01*
X559042D01*
G01X558458Y358792D02*
X557458D01*
G01X560517Y360000D02*
Y357500D01*
X562183D01*
G01X565283D02*
X563617D01*
Y360000D01*
X565283D01*
G01X564617Y358792D02*
X563617D01*
G01X566633Y357500D02*
Y360000D01*
X567467D01*
X567800Y359875D01*
X568050Y359708D01*
X568258Y359458D01*
X568425Y359167D01*
X568467Y358750D01*
X568425Y358333D01*
X568258Y358042D01*
X568050Y357792D01*
X567800Y357625D01*
X567467Y357500D01*
X566633D01*
G01X570650D02*
Y360000D01*
X570150Y359500D01*
G01Y357500D02*
X571150D01*
G01X573667D02*
X573750Y358042D01*
X573875Y358500D01*
X574042Y358917D01*
X574250Y359375D01*
X574583Y360000D01*
X572917D01*
G01X562529Y366054D02*
Y377254D01*
X571329D01*
Y366054D01*
X562529D01*
G01X587279Y487798D02*
X584779D01*
Y488839D01*
X584904Y489173D01*
X585071Y489381D01*
X585404Y489464D01*
X585737Y489381D01*
X585946Y489131D01*
X586071Y488839D01*
Y487798D01*
G01Y488839D02*
X587279Y489464D01*
G01Y491731D02*
X584779D01*
X585279Y491231D01*
G01X587279D02*
Y492231D01*
G01X584779Y494831D02*
X584862Y494498D01*
X585071Y494248D01*
X585321Y494081D01*
X585654Y493956D01*
X586029Y493914D01*
X586404Y493956D01*
X586737Y494081D01*
X586987Y494248D01*
X587196Y494498D01*
X587279Y494831D01*
X587196Y495164D01*
X586987Y495414D01*
X586737Y495581D01*
X586404Y495706D01*
X586029Y495748D01*
X585654Y495706D01*
X585321Y495581D01*
X585071Y495414D01*
X584862Y495164D01*
X584779Y494831D01*
G01X586904Y497014D02*
X587112Y497264D01*
X587237Y497556D01*
X587279Y497931D01*
X587196Y498306D01*
X587029Y498598D01*
X586737Y498806D01*
X586404Y498848D01*
X586071Y498764D01*
X585862Y498556D01*
X585696Y498264D01*
X585654Y497973D01*
X585696Y497681D01*
X585862Y497306D01*
X584779Y497431D01*
Y498556D01*
G01Y501031D02*
X584862Y500698D01*
X585071Y500448D01*
X585321Y500281D01*
X585654Y500156D01*
X586029Y500114D01*
X586404Y500156D01*
X586737Y500281D01*
X586987Y500448D01*
X587196Y500698D01*
X587279Y501031D01*
X587196Y501364D01*
X586987Y501614D01*
X586737Y501781D01*
X586404Y501906D01*
X586029Y501948D01*
X585654Y501906D01*
X585321Y501781D01*
X585071Y501614D01*
X584862Y501364D01*
X584779Y501031D01*
G01X582779Y487798D02*
X580279D01*
Y488839D01*
X580404Y489173D01*
X580571Y489381D01*
X580904Y489464D01*
X581237Y489381D01*
X581446Y489131D01*
X581571Y488839D01*
Y487798D01*
G01Y488839D02*
X582779Y489464D01*
G01Y491731D02*
X580279D01*
X580779Y491231D01*
G01X582779D02*
Y492231D01*
G01X580279Y494831D02*
X580362Y494498D01*
X580571Y494248D01*
X580821Y494081D01*
X581154Y493956D01*
X581529Y493914D01*
X581904Y493956D01*
X582237Y494081D01*
X582487Y494248D01*
X582696Y494498D01*
X582779Y494831D01*
X582696Y495164D01*
X582487Y495414D01*
X582237Y495581D01*
X581904Y495706D01*
X581529Y495748D01*
X581154Y495706D01*
X580821Y495581D01*
X580571Y495414D01*
X580362Y495164D01*
X580279Y494831D01*
G01X582404Y497014D02*
X582612Y497264D01*
X582737Y497556D01*
X582779Y497931D01*
X582696Y498306D01*
X582529Y498598D01*
X582237Y498806D01*
X581904Y498848D01*
X581571Y498764D01*
X581362Y498556D01*
X581196Y498264D01*
X581154Y497973D01*
X581196Y497681D01*
X581362Y497306D01*
X580279Y497431D01*
Y498556D01*
G01X582779Y501531D02*
X580279D01*
X582071Y499989D01*
Y502073D01*
G01X581017Y483500D02*
Y486000D01*
X582058D01*
X582392Y485875D01*
X582600Y485708D01*
X582683Y485375D01*
X582600Y485042D01*
X582350Y484833D01*
X582058Y484708D01*
X581017D01*
G01X582058D02*
X582683Y483500D01*
G01X584950D02*
Y486000D01*
X584450Y485500D01*
G01Y483500D02*
X585450D01*
G01X588550D02*
Y486000D01*
X587008Y484208D01*
X589092D01*
G01X590233Y484000D02*
X590483Y483708D01*
X590817Y483542D01*
X591192Y483500D01*
X591525Y483542D01*
X591858Y483750D01*
X592067Y484000D01*
X592108Y484250D01*
X592025Y484542D01*
X591733Y484750D01*
X591442Y484833D01*
X591067D01*
G01X591442D02*
X591692Y484958D01*
X591900Y485167D01*
X591983Y485417D01*
X591900Y485667D01*
X591692Y485875D01*
X591317Y486000D01*
X590942Y485958D01*
X590567Y485792D01*
G01X592000Y487467D02*
X589500D01*
Y488508D01*
X589625Y488842D01*
X589792Y489050D01*
X590125Y489133D01*
X590458Y489050D01*
X590667Y488800D01*
X590792Y488508D01*
Y487467D01*
G01Y488508D02*
X592000Y489133D01*
G01Y491400D02*
X589500D01*
X590000Y490900D01*
G01X592000D02*
Y491900D01*
G01X589500Y494500D02*
X589583Y494167D01*
X589792Y493917D01*
X590042Y493750D01*
X590375Y493625D01*
X590750Y493583D01*
X591125Y493625D01*
X591458Y493750D01*
X591708Y493917D01*
X591917Y494167D01*
X592000Y494500D01*
X591917Y494833D01*
X591708Y495083D01*
X591458Y495250D01*
X591125Y495375D01*
X590750Y495417D01*
X590375Y495375D01*
X590042Y495250D01*
X589792Y495083D01*
X589583Y494833D01*
X589500Y494500D01*
G01X590958Y496808D02*
X590667Y497100D01*
X590500Y497350D01*
X590417Y497683D01*
X590500Y497975D01*
X590667Y498183D01*
X590917Y498350D01*
X591208Y498392D01*
X591458Y498350D01*
X591708Y498183D01*
X591917Y497933D01*
X592000Y497642D01*
X591917Y497308D01*
X591667Y497017D01*
X591292Y496850D01*
X590875Y496808D01*
X590333Y496892D01*
X590042Y497017D01*
X589750Y497225D01*
X589542Y497517D01*
X589500Y497808D01*
X589583Y498100D01*
X589792Y498308D01*
G01X591708Y499992D02*
X591917Y500283D01*
X592000Y500617D01*
X591917Y500950D01*
X591667Y501242D01*
X591292Y501450D01*
X590917Y501533D01*
X590458D01*
X590083Y501450D01*
X589750Y501242D01*
X589583Y500992D01*
X589500Y500700D01*
X589583Y500367D01*
X589750Y500117D01*
X590000Y499950D01*
X590333Y499867D01*
X590625Y499950D01*
X590917Y500158D01*
X591083Y500408D01*
X591125Y500700D01*
X591042Y501033D01*
X590833Y501283D01*
X590458Y501533D01*
G01X559987Y496098D02*
X559862Y495848D01*
X559779Y495556D01*
Y495223D01*
X559904Y494848D01*
X560112Y494556D01*
X560362Y494348D01*
X560779Y494181D01*
X561154Y494139D01*
X561529Y494223D01*
X561779Y494348D01*
X562029Y494598D01*
X562196Y494889D01*
X562279Y495181D01*
Y495473D01*
X562196Y495764D01*
X562071Y496014D01*
X561904Y496223D01*
G01Y497364D02*
X562112Y497614D01*
X562237Y497906D01*
X562279Y498281D01*
X562196Y498656D01*
X562029Y498948D01*
X561737Y499156D01*
X561404Y499198D01*
X561071Y499114D01*
X560862Y498906D01*
X560696Y498614D01*
X560654Y498323D01*
X560696Y498031D01*
X560862Y497656D01*
X559779Y497781D01*
Y498906D01*
G01X562279Y501881D02*
X559779D01*
X561571Y500339D01*
Y502423D01*
G01X561237Y503689D02*
X560946Y503981D01*
X560779Y504231D01*
X560696Y504564D01*
X560779Y504856D01*
X560946Y505064D01*
X561196Y505231D01*
X561487Y505273D01*
X561737Y505231D01*
X561987Y505064D01*
X562196Y504814D01*
X562279Y504523D01*
X562196Y504189D01*
X561946Y503898D01*
X561571Y503731D01*
X561154Y503689D01*
X560612Y503773D01*
X560321Y503898D01*
X560029Y504106D01*
X559821Y504398D01*
X559779Y504689D01*
X559862Y504981D01*
X560071Y505189D01*
G01X569267Y496792D02*
X569017Y496917D01*
X568725Y497000D01*
X568392D01*
X568017Y496875D01*
X567725Y496667D01*
X567517Y496417D01*
X567350Y496000D01*
X567308Y495625D01*
X567392Y495250D01*
X567517Y495000D01*
X567767Y494750D01*
X568058Y494583D01*
X568350Y494500D01*
X568642D01*
X568933Y494583D01*
X569183Y494708D01*
X569392Y494875D01*
G01X570533D02*
X570783Y494667D01*
X571075Y494542D01*
X571450Y494500D01*
X571825Y494583D01*
X572117Y494750D01*
X572325Y495042D01*
X572367Y495375D01*
X572283Y495708D01*
X572075Y495917D01*
X571783Y496083D01*
X571492Y496125D01*
X571200Y496083D01*
X570825Y495917D01*
X570950Y497000D01*
X572075D01*
G01X573633Y494875D02*
X573883Y494667D01*
X574175Y494542D01*
X574550Y494500D01*
X574925Y494583D01*
X575217Y494750D01*
X575425Y495042D01*
X575467Y495375D01*
X575383Y495708D01*
X575175Y495917D01*
X574883Y496083D01*
X574592Y496125D01*
X574300Y496083D01*
X573925Y495917D01*
X574050Y497000D01*
X575175D01*
G01X578150Y494500D02*
Y497000D01*
X576608Y495208D01*
X578692D01*
G01X563708Y496267D02*
X563583Y496017D01*
X563500Y495725D01*
Y495392D01*
X563625Y495017D01*
X563833Y494725D01*
X564083Y494517D01*
X564500Y494350D01*
X564875Y494308D01*
X565250Y494392D01*
X565500Y494517D01*
X565750Y494767D01*
X565917Y495058D01*
X566000Y495350D01*
Y495642D01*
X565917Y495933D01*
X565792Y496183D01*
X565625Y496392D01*
G01Y497533D02*
X565833Y497783D01*
X565958Y498075D01*
X566000Y498450D01*
X565917Y498825D01*
X565750Y499117D01*
X565458Y499325D01*
X565125Y499367D01*
X564792Y499283D01*
X564583Y499075D01*
X564417Y498783D01*
X564375Y498492D01*
X564417Y498200D01*
X564583Y497825D01*
X563500Y497950D01*
Y499075D01*
G01X566000Y502050D02*
X563500D01*
X565292Y500508D01*
Y502592D01*
G01X566000Y505150D02*
X563500D01*
X565292Y503608D01*
Y505692D01*
G01X578279Y514631D02*
X582279D01*
Y522031D01*
G01X577779D02*
X573779D01*
Y514631D01*
G01X591536Y503182D02*
X586336D01*
G01X591536Y510182D02*
X583736D01*
G01X591536Y503182D02*
Y510182D01*
G01X578136Y503182D02*
X586836D01*
G01X578136Y510182D02*
Y503182D01*
G01X584536Y510182D02*
X578136D01*
G01X591474Y524395D02*
Y519195D01*
G01X584474Y524395D02*
Y516595D01*
G01X591474Y524395D02*
X584474D01*
G01X591474Y510995D02*
Y519695D01*
G01X584474Y510995D02*
X591474D01*
G01X584474Y517395D02*
Y510995D01*
G01X586000Y549983D02*
X587792D01*
X588167Y550150D01*
X588417Y550483D01*
X588500Y550900D01*
X588417Y551317D01*
X588167Y551650D01*
X587792Y551817D01*
X586000D01*
G01X586417Y553208D02*
X586167Y553458D01*
X586042Y553750D01*
X586000Y554083D01*
X586083Y554500D01*
X586292Y554792D01*
X586542Y554875D01*
X586792Y554833D01*
X587000Y554667D01*
X587417Y553833D01*
X587708Y553458D01*
X588125Y553208D01*
X588500Y553125D01*
Y554875D01*
G01X588000Y556183D02*
X588292Y556433D01*
X588458Y556767D01*
X588500Y557142D01*
X588458Y557475D01*
X588250Y557808D01*
X588000Y558017D01*
X587750Y558058D01*
X587458Y557975D01*
X587250Y557683D01*
X587167Y557392D01*
Y557017D01*
G01Y557392D02*
X587042Y557642D01*
X586833Y557850D01*
X586583Y557933D01*
X586333Y557850D01*
X586125Y557642D01*
X586000Y557267D01*
X586042Y556892D01*
X586208Y556517D01*
G01X569792Y526881D02*
Y529881D01*
G01X586729Y545783D02*
X583729D01*
G01X585729Y535943D02*
X583729D01*
G01X584629Y533981D02*
Y528981D01*
X579629D01*
G01X556929Y533981D02*
Y528981D01*
X561929D01*
G01X600195Y505661D02*
X599862Y505703D01*
X599570Y505869D01*
X599320Y506119D01*
X599153Y506411D01*
X599070Y506744D01*
Y507078D01*
X599153Y507411D01*
X599320Y507703D01*
X599570Y507953D01*
X599862Y508119D01*
X600195Y508161D01*
X600528Y508119D01*
X600820Y507953D01*
X601070Y507703D01*
X601237Y507411D01*
X601320Y507078D01*
Y506744D01*
X601237Y506411D01*
X601070Y506119D01*
X600820Y505869D01*
X600528Y505703D01*
X600195Y505661D01*
G01X600528Y506328D02*
X601028Y505661D01*
G01X602503Y507744D02*
X602753Y507994D01*
X603045Y508119D01*
X603378Y508161D01*
X603795Y508078D01*
X604087Y507869D01*
X604170Y507619D01*
X604128Y507369D01*
X603962Y507161D01*
X603128Y506744D01*
X602753Y506453D01*
X602503Y506036D01*
X602420Y505661D01*
X604170D01*
G01X606395D02*
Y508161D01*
X605895Y507661D01*
G01Y505661D02*
X606895D01*
G01X608787Y505953D02*
X609078Y505744D01*
X609412Y505661D01*
X609745Y505744D01*
X610037Y505994D01*
X610245Y506369D01*
X610328Y506744D01*
Y507203D01*
X610245Y507578D01*
X610037Y507911D01*
X609787Y508078D01*
X609495Y508161D01*
X609162Y508078D01*
X608912Y507911D01*
X608745Y507661D01*
X608662Y507328D01*
X608745Y507036D01*
X608953Y506744D01*
X609203Y506578D01*
X609495Y506536D01*
X609828Y506619D01*
X610078Y506828D01*
X610328Y507203D01*
G01X598168Y509995D02*
X612168D01*
G01X598168Y522995D02*
Y509995D01*
G01X612168Y522995D02*
X598168D01*
G01X606979Y536831D02*
Y540831D01*
X599579D01*
G01X606979D02*
Y544831D01*
X599579D01*
G01X596500Y513967D02*
X594000D01*
Y515008D01*
X594125Y515342D01*
X594292Y515550D01*
X594625Y515633D01*
X594958Y515550D01*
X595167Y515300D01*
X595292Y515008D01*
Y513967D01*
G01Y515008D02*
X596500Y515633D01*
G01Y517900D02*
X594000D01*
X594500Y517400D01*
G01X596500D02*
Y518400D01*
G01X594000Y521000D02*
X594083Y520667D01*
X594292Y520417D01*
X594542Y520250D01*
X594875Y520125D01*
X595250Y520083D01*
X595625Y520125D01*
X595958Y520250D01*
X596208Y520417D01*
X596417Y520667D01*
X596500Y521000D01*
X596417Y521333D01*
X596208Y521583D01*
X595958Y521750D01*
X595625Y521875D01*
X595250Y521917D01*
X594875Y521875D01*
X594542Y521750D01*
X594292Y521583D01*
X594083Y521333D01*
X594000Y521000D01*
G01X596000Y523183D02*
X596292Y523433D01*
X596458Y523767D01*
X596500Y524142D01*
X596458Y524475D01*
X596250Y524808D01*
X596000Y525017D01*
X595750Y525058D01*
X595458Y524975D01*
X595250Y524683D01*
X595167Y524392D01*
Y524017D01*
G01Y524392D02*
X595042Y524642D01*
X594833Y524850D01*
X594583Y524933D01*
X594333Y524850D01*
X594125Y524642D01*
X594000Y524267D01*
X594042Y523892D01*
X594208Y523517D01*
G01X596500Y527117D02*
X595958Y527200D01*
X595500Y527325D01*
X595083Y527492D01*
X594625Y527700D01*
X594000Y528033D01*
Y526367D01*
G01X596267Y536070D02*
X592267D01*
Y528670D01*
G01X600979Y550331D02*
Y554331D01*
X593579D01*
G01X590974Y674248D02*
X596024D01*
Y772948D01*
X620674D01*
Y588548D01*
X596024D01*
Y647248D01*
X590974D01*
Y674248D01*
G01X559000Y572967D02*
X556500D01*
Y574008D01*
X556625Y574342D01*
X556792Y574550D01*
X557125Y574633D01*
X557458Y574550D01*
X557667Y574300D01*
X557792Y574008D01*
Y572967D01*
G01Y574008D02*
X559000Y574633D01*
G01Y576900D02*
X556500D01*
X557000Y576400D01*
G01X559000D02*
Y577400D01*
G01X556500Y580000D02*
X556583Y579667D01*
X556792Y579417D01*
X557042Y579250D01*
X557375Y579125D01*
X557750Y579083D01*
X558125Y579125D01*
X558458Y579250D01*
X558708Y579417D01*
X558917Y579667D01*
X559000Y580000D01*
X558917Y580333D01*
X558708Y580583D01*
X558458Y580750D01*
X558125Y580875D01*
X557750Y580917D01*
X557375Y580875D01*
X557042Y580750D01*
X556792Y580583D01*
X556583Y580333D01*
X556500Y580000D01*
G01X559000Y583600D02*
X556500D01*
X558292Y582058D01*
Y584142D01*
G01X556500Y586200D02*
X556583Y585867D01*
X556792Y585617D01*
X557042Y585450D01*
X557375Y585325D01*
X557750Y585283D01*
X558125Y585325D01*
X558458Y585450D01*
X558708Y585617D01*
X558917Y585867D01*
X559000Y586200D01*
X558917Y586533D01*
X558708Y586783D01*
X558458Y586950D01*
X558125Y587075D01*
X557750Y587117D01*
X557375Y587075D01*
X557042Y586950D01*
X556792Y586783D01*
X556583Y586533D01*
X556500Y586200D01*
G01X596467Y579500D02*
Y582000D01*
X597508D01*
X597842Y581875D01*
X598050Y581708D01*
X598133Y581375D01*
X598050Y581042D01*
X597800Y580833D01*
X597508Y580708D01*
X596467D01*
G01X597508D02*
X598133Y579500D01*
G01X600400D02*
Y582000D01*
X599900Y581500D01*
G01Y579500D02*
X600900D01*
G01X603500Y582000D02*
X603167Y581917D01*
X602917Y581708D01*
X602750Y581458D01*
X602625Y581125D01*
X602583Y580750D01*
X602625Y580375D01*
X602750Y580042D01*
X602917Y579792D01*
X603167Y579583D01*
X603500Y579500D01*
X603833Y579583D01*
X604083Y579792D01*
X604250Y580042D01*
X604375Y580375D01*
X604417Y580750D01*
X604375Y581125D01*
X604250Y581458D01*
X604083Y581708D01*
X603833Y581917D01*
X603500Y582000D01*
G01X605683Y579875D02*
X605933Y579667D01*
X606225Y579542D01*
X606600Y579500D01*
X606975Y579583D01*
X607267Y579750D01*
X607475Y580042D01*
X607517Y580375D01*
X607433Y580708D01*
X607225Y580917D01*
X606933Y581083D01*
X606642Y581125D01*
X606350Y581083D01*
X605975Y580917D01*
X606100Y582000D01*
X607225D01*
G01X608908Y580542D02*
X609200Y580833D01*
X609450Y581000D01*
X609783Y581083D01*
X610075Y581000D01*
X610283Y580833D01*
X610450Y580583D01*
X610492Y580292D01*
X610450Y580042D01*
X610283Y579792D01*
X610033Y579583D01*
X609742Y579500D01*
X609408Y579583D01*
X609117Y579833D01*
X608950Y580208D01*
X608908Y580625D01*
X608992Y581167D01*
X609117Y581458D01*
X609325Y581750D01*
X609617Y581958D01*
X609908Y582000D01*
X610200Y581917D01*
X610408Y581708D01*
G01X587079Y568331D02*
Y564331D01*
X594479D01*
G01X594500Y583467D02*
X592000D01*
Y584508D01*
X592125Y584842D01*
X592292Y585050D01*
X592625Y585133D01*
X592958Y585050D01*
X593167Y584800D01*
X593292Y584508D01*
Y583467D01*
G01Y584508D02*
X594500Y585133D01*
G01Y587400D02*
X592000D01*
X592500Y586900D01*
G01X594500D02*
Y587900D01*
G01X592000Y590500D02*
X592083Y590167D01*
X592292Y589917D01*
X592542Y589750D01*
X592875Y589625D01*
X593250Y589583D01*
X593625Y589625D01*
X593958Y589750D01*
X594208Y589917D01*
X594417Y590167D01*
X594500Y590500D01*
X594417Y590833D01*
X594208Y591083D01*
X593958Y591250D01*
X593625Y591375D01*
X593250Y591417D01*
X592875Y591375D01*
X592542Y591250D01*
X592292Y591083D01*
X592083Y590833D01*
X592000Y590500D01*
G01X594125Y592683D02*
X594333Y592933D01*
X594458Y593225D01*
X594500Y593600D01*
X594417Y593975D01*
X594250Y594267D01*
X593958Y594475D01*
X593625Y594517D01*
X593292Y594433D01*
X593083Y594225D01*
X592917Y593933D01*
X592875Y593642D01*
X592917Y593350D01*
X593083Y592975D01*
X592000Y593100D01*
Y594225D01*
G01X594500Y596617D02*
X593958Y596700D01*
X593500Y596825D01*
X593083Y596992D01*
X592625Y597200D01*
X592000Y597533D01*
Y595867D01*
G01X590779Y568631D02*
X594779D01*
Y576031D01*
G01X580967Y579500D02*
Y582000D01*
X582008D01*
X582342Y581875D01*
X582550Y581708D01*
X582633Y581375D01*
X582550Y581042D01*
X582300Y580833D01*
X582008Y580708D01*
X580967D01*
G01X582008D02*
X582633Y579500D01*
G01X584900D02*
Y582000D01*
X584400Y581500D01*
G01Y579500D02*
X585400D01*
G01X588000Y582000D02*
X587667Y581917D01*
X587417Y581708D01*
X587250Y581458D01*
X587125Y581125D01*
X587083Y580750D01*
X587125Y580375D01*
X587250Y580042D01*
X587417Y579792D01*
X587667Y579583D01*
X588000Y579500D01*
X588333Y579583D01*
X588583Y579792D01*
X588750Y580042D01*
X588875Y580375D01*
X588917Y580750D01*
X588875Y581125D01*
X588750Y581458D01*
X588583Y581708D01*
X588333Y581917D01*
X588000Y582000D01*
G01X590183Y579875D02*
X590433Y579667D01*
X590725Y579542D01*
X591100Y579500D01*
X591475Y579583D01*
X591767Y579750D01*
X591975Y580042D01*
X592017Y580375D01*
X591933Y580708D01*
X591725Y580917D01*
X591433Y581083D01*
X591142Y581125D01*
X590850Y581083D01*
X590475Y580917D01*
X590600Y582000D01*
X591725D01*
G01X594200Y579500D02*
X594492Y579542D01*
X594825Y579667D01*
X595033Y579875D01*
X595117Y580167D01*
X595033Y580458D01*
X594783Y580708D01*
X594408Y580833D01*
X593992D01*
X593742Y580917D01*
X593533Y581125D01*
X593450Y581417D01*
X593575Y581708D01*
X593867Y581917D01*
X594200Y582000D01*
X594533Y581917D01*
X594825Y581708D01*
X594950Y581417D01*
X594867Y581125D01*
X594658Y580917D01*
X594408Y580833D01*
X593992D01*
X593617Y580708D01*
X593367Y580458D01*
X593283Y580167D01*
X593367Y579875D01*
X593575Y579667D01*
X593908Y579542D01*
X594200Y579500D01*
G01X581479Y564331D02*
Y568331D01*
X574079D01*
G01X582500Y583467D02*
X580000D01*
Y584508D01*
X580125Y584842D01*
X580292Y585050D01*
X580625Y585133D01*
X580958Y585050D01*
X581167Y584800D01*
X581292Y584508D01*
Y583467D01*
G01Y584508D02*
X582500Y585133D01*
G01Y587400D02*
X580000D01*
X580500Y586900D01*
G01X582500D02*
Y587900D01*
G01X580000Y590500D02*
X580083Y590167D01*
X580292Y589917D01*
X580542Y589750D01*
X580875Y589625D01*
X581250Y589583D01*
X581625Y589625D01*
X581958Y589750D01*
X582208Y589917D01*
X582417Y590167D01*
X582500Y590500D01*
X582417Y590833D01*
X582208Y591083D01*
X581958Y591250D01*
X581625Y591375D01*
X581250Y591417D01*
X580875Y591375D01*
X580542Y591250D01*
X580292Y591083D01*
X580083Y590833D01*
X580000Y590500D01*
G01X582125Y592683D02*
X582333Y592933D01*
X582458Y593225D01*
X582500Y593600D01*
X582417Y593975D01*
X582250Y594267D01*
X581958Y594475D01*
X581625Y594517D01*
X581292Y594433D01*
X581083Y594225D01*
X580917Y593933D01*
X580875Y593642D01*
X580917Y593350D01*
X581083Y592975D01*
X580000Y593100D01*
Y594225D01*
G01X582208Y595992D02*
X582417Y596283D01*
X582500Y596617D01*
X582417Y596950D01*
X582167Y597242D01*
X581792Y597450D01*
X581417Y597533D01*
X580958D01*
X580583Y597450D01*
X580250Y597242D01*
X580083Y596992D01*
X580000Y596700D01*
X580083Y596367D01*
X580250Y596117D01*
X580500Y595950D01*
X580833Y595867D01*
X581125Y595950D01*
X581417Y596158D01*
X581583Y596408D01*
X581625Y596700D01*
X581542Y597033D01*
X581333Y597283D01*
X580958Y597533D01*
G01X577718Y568697D02*
X581718D01*
Y576097D01*
G01X565467Y579500D02*
Y582000D01*
X566508D01*
X566842Y581875D01*
X567050Y581708D01*
X567133Y581375D01*
X567050Y581042D01*
X566800Y580833D01*
X566508Y580708D01*
X565467D01*
G01X566508D02*
X567133Y579500D01*
G01X569400D02*
Y582000D01*
X568900Y581500D01*
G01Y579500D02*
X569900D01*
G01X572500Y582000D02*
X572167Y581917D01*
X571917Y581708D01*
X571750Y581458D01*
X571625Y581125D01*
X571583Y580750D01*
X571625Y580375D01*
X571750Y580042D01*
X571917Y579792D01*
X572167Y579583D01*
X572500Y579500D01*
X572833Y579583D01*
X573083Y579792D01*
X573250Y580042D01*
X573375Y580375D01*
X573417Y580750D01*
X573375Y581125D01*
X573250Y581458D01*
X573083Y581708D01*
X572833Y581917D01*
X572500Y582000D01*
G01X574808Y580542D02*
X575100Y580833D01*
X575350Y581000D01*
X575683Y581083D01*
X575975Y581000D01*
X576183Y580833D01*
X576350Y580583D01*
X576392Y580292D01*
X576350Y580042D01*
X576183Y579792D01*
X575933Y579583D01*
X575642Y579500D01*
X575308Y579583D01*
X575017Y579833D01*
X574850Y580208D01*
X574808Y580625D01*
X574892Y581167D01*
X575017Y581458D01*
X575225Y581750D01*
X575517Y581958D01*
X575808Y582000D01*
X576100Y581917D01*
X576308Y581708D01*
G01X578700Y582000D02*
X578367Y581917D01*
X578117Y581708D01*
X577950Y581458D01*
X577825Y581125D01*
X577783Y580750D01*
X577825Y580375D01*
X577950Y580042D01*
X578117Y579792D01*
X578367Y579583D01*
X578700Y579500D01*
X579033Y579583D01*
X579283Y579792D01*
X579450Y580042D01*
X579575Y580375D01*
X579617Y580750D01*
X579575Y581125D01*
X579450Y581458D01*
X579283Y581708D01*
X579033Y581917D01*
X578700Y582000D01*
G01X573479Y564331D02*
Y568331D01*
X566079D01*
G01X573500Y583467D02*
X571000D01*
Y584508D01*
X571125Y584842D01*
X571292Y585050D01*
X571625Y585133D01*
X571958Y585050D01*
X572167Y584800D01*
X572292Y584508D01*
Y583467D01*
G01Y584508D02*
X573500Y585133D01*
G01Y587400D02*
X571000D01*
X571500Y586900D01*
G01X573500D02*
Y587900D01*
G01X571000Y590500D02*
X571083Y590167D01*
X571292Y589917D01*
X571542Y589750D01*
X571875Y589625D01*
X572250Y589583D01*
X572625Y589625D01*
X572958Y589750D01*
X573208Y589917D01*
X573417Y590167D01*
X573500Y590500D01*
X573417Y590833D01*
X573208Y591083D01*
X572958Y591250D01*
X572625Y591375D01*
X572250Y591417D01*
X571875Y591375D01*
X571542Y591250D01*
X571292Y591083D01*
X571083Y590833D01*
X571000Y590500D01*
G01X572458Y592808D02*
X572167Y593100D01*
X572000Y593350D01*
X571917Y593683D01*
X572000Y593975D01*
X572167Y594183D01*
X572417Y594350D01*
X572708Y594392D01*
X572958Y594350D01*
X573208Y594183D01*
X573417Y593933D01*
X573500Y593642D01*
X573417Y593308D01*
X573167Y593017D01*
X572792Y592850D01*
X572375Y592808D01*
X571833Y592892D01*
X571542Y593017D01*
X571250Y593225D01*
X571042Y593517D01*
X571000Y593808D01*
X571083Y594100D01*
X571292Y594308D01*
G01X573500Y596700D02*
X571000D01*
X571500Y596200D01*
G01X573500D02*
Y597200D01*
G01X569540Y568665D02*
X573540D01*
Y576065D01*
G01X569792Y557781D02*
Y555781D01*
G01X556929Y551681D02*
Y556681D01*
X561929D01*
G01X584208Y585767D02*
X584083Y585517D01*
X584000Y585225D01*
Y584892D01*
X584125Y584517D01*
X584333Y584225D01*
X584583Y584017D01*
X585000Y583850D01*
X585375Y583808D01*
X585750Y583892D01*
X586000Y584017D01*
X586250Y584267D01*
X586417Y584558D01*
X586500Y584850D01*
Y585142D01*
X586417Y585433D01*
X586292Y585683D01*
X586125Y585892D01*
G01Y587033D02*
X586333Y587283D01*
X586458Y587575D01*
X586500Y587950D01*
X586417Y588325D01*
X586250Y588617D01*
X585958Y588825D01*
X585625Y588867D01*
X585292Y588783D01*
X585083Y588575D01*
X584917Y588283D01*
X584875Y587992D01*
X584917Y587700D01*
X585083Y587325D01*
X584000Y587450D01*
Y588575D01*
G01X586500Y591550D02*
X584000D01*
X585792Y590008D01*
Y592092D01*
G01X586208Y593442D02*
X586417Y593733D01*
X586500Y594067D01*
X586417Y594400D01*
X586167Y594692D01*
X585792Y594900D01*
X585417Y594983D01*
X584958D01*
X584583Y594900D01*
X584250Y594692D01*
X584083Y594442D01*
X584000Y594150D01*
X584083Y593817D01*
X584250Y593567D01*
X584500Y593400D01*
X584833Y593317D01*
X585125Y593400D01*
X585417Y593608D01*
X585583Y593858D01*
X585625Y594150D01*
X585542Y594483D01*
X585333Y594733D01*
X584958Y594983D01*
G01X567208Y585267D02*
X567083Y585017D01*
X567000Y584725D01*
Y584392D01*
X567125Y584017D01*
X567333Y583725D01*
X567583Y583517D01*
X568000Y583350D01*
X568375Y583308D01*
X568750Y583392D01*
X569000Y583517D01*
X569250Y583767D01*
X569417Y584058D01*
X569500Y584350D01*
Y584642D01*
X569417Y584933D01*
X569292Y585183D01*
X569125Y585392D01*
G01Y586533D02*
X569333Y586783D01*
X569458Y587075D01*
X569500Y587450D01*
X569417Y587825D01*
X569250Y588117D01*
X568958Y588325D01*
X568625Y588367D01*
X568292Y588283D01*
X568083Y588075D01*
X567917Y587783D01*
X567875Y587492D01*
X567917Y587200D01*
X568083Y586825D01*
X567000Y586950D01*
Y588075D01*
G01X569125Y589633D02*
X569333Y589883D01*
X569458Y590175D01*
X569500Y590550D01*
X569417Y590925D01*
X569250Y591217D01*
X568958Y591425D01*
X568625Y591467D01*
X568292Y591383D01*
X568083Y591175D01*
X567917Y590883D01*
X567875Y590592D01*
X567917Y590300D01*
X568083Y589925D01*
X567000Y590050D01*
Y591175D01*
G01Y593650D02*
X567083Y593317D01*
X567292Y593067D01*
X567542Y592900D01*
X567875Y592775D01*
X568250Y592733D01*
X568625Y592775D01*
X568958Y592900D01*
X569208Y593067D01*
X569417Y593317D01*
X569500Y593650D01*
X569417Y593983D01*
X569208Y594233D01*
X568958Y594400D01*
X568625Y594525D01*
X568250Y594567D01*
X567875Y594525D01*
X567542Y594400D01*
X567292Y594233D01*
X567083Y593983D01*
X567000Y593650D01*
G01X575708Y585767D02*
X575583Y585517D01*
X575500Y585225D01*
Y584892D01*
X575625Y584517D01*
X575833Y584225D01*
X576083Y584017D01*
X576500Y583850D01*
X576875Y583808D01*
X577250Y583892D01*
X577500Y584017D01*
X577750Y584267D01*
X577917Y584558D01*
X578000Y584850D01*
Y585142D01*
X577917Y585433D01*
X577792Y585683D01*
X577625Y585892D01*
G01Y587033D02*
X577833Y587283D01*
X577958Y587575D01*
X578000Y587950D01*
X577917Y588325D01*
X577750Y588617D01*
X577458Y588825D01*
X577125Y588867D01*
X576792Y588783D01*
X576583Y588575D01*
X576417Y588283D01*
X576375Y587992D01*
X576417Y587700D01*
X576583Y587325D01*
X575500Y587450D01*
Y588575D01*
G01X578000Y591550D02*
X575500D01*
X577292Y590008D01*
Y592092D01*
G01X578000Y594150D02*
X577958Y594442D01*
X577833Y594775D01*
X577625Y594983D01*
X577333Y595067D01*
X577042Y594983D01*
X576792Y594733D01*
X576667Y594358D01*
Y593942D01*
X576583Y593692D01*
X576375Y593483D01*
X576083Y593400D01*
X575792Y593525D01*
X575583Y593817D01*
X575500Y594150D01*
X575583Y594483D01*
X575792Y594775D01*
X576083Y594900D01*
X576375Y594817D01*
X576583Y594608D01*
X576667Y594358D01*
Y593942D01*
X576792Y593567D01*
X577042Y593317D01*
X577333Y593233D01*
X577625Y593317D01*
X577833Y593525D01*
X577958Y593858D01*
X578000Y594150D01*
G01X588208Y585267D02*
X588083Y585017D01*
X588000Y584725D01*
Y584392D01*
X588125Y584017D01*
X588333Y583725D01*
X588583Y583517D01*
X589000Y583350D01*
X589375Y583308D01*
X589750Y583392D01*
X590000Y583517D01*
X590250Y583767D01*
X590417Y584058D01*
X590500Y584350D01*
Y584642D01*
X590417Y584933D01*
X590292Y585183D01*
X590125Y585392D01*
G01Y586533D02*
X590333Y586783D01*
X590458Y587075D01*
X590500Y587450D01*
X590417Y587825D01*
X590250Y588117D01*
X589958Y588325D01*
X589625Y588367D01*
X589292Y588283D01*
X589083Y588075D01*
X588917Y587783D01*
X588875Y587492D01*
X588917Y587200D01*
X589083Y586825D01*
X588000Y586950D01*
Y588075D01*
G01X590500Y591050D02*
X588000D01*
X589792Y589508D01*
Y591592D01*
G01X590500Y593567D02*
X589958Y593650D01*
X589500Y593775D01*
X589083Y593942D01*
X588625Y594150D01*
X588000Y594483D01*
Y592817D01*
G01X560708Y581267D02*
X560583Y581017D01*
X560500Y580725D01*
Y580392D01*
X560625Y580017D01*
X560833Y579725D01*
X561083Y579517D01*
X561500Y579350D01*
X561875Y579308D01*
X562250Y579392D01*
X562500Y579517D01*
X562750Y579767D01*
X562917Y580058D01*
X563000Y580350D01*
Y580642D01*
X562917Y580933D01*
X562792Y581183D01*
X562625Y581392D01*
G01Y582533D02*
X562833Y582783D01*
X562958Y583075D01*
X563000Y583450D01*
X562917Y583825D01*
X562750Y584117D01*
X562458Y584325D01*
X562125Y584367D01*
X561792Y584283D01*
X561583Y584075D01*
X561417Y583783D01*
X561375Y583492D01*
X561417Y583200D01*
X561583Y582825D01*
X560500Y582950D01*
Y584075D01*
G01X563000Y587050D02*
X560500D01*
X562292Y585508D01*
Y587592D01*
G01X560917Y588858D02*
X560667Y589108D01*
X560542Y589400D01*
X560500Y589733D01*
X560583Y590150D01*
X560792Y590442D01*
X561042Y590525D01*
X561292Y590483D01*
X561500Y590317D01*
X561917Y589483D01*
X562208Y589108D01*
X562625Y588858D01*
X563000Y588775D01*
Y590525D01*
G01X591087Y632017D02*
Y636017D01*
X583687D01*
G01X591087Y627417D02*
Y631417D01*
X583687D01*
G01Y645917D02*
Y641917D01*
X591087D01*
G01X571687Y636117D02*
X567687D01*
Y628717D01*
G01X582987Y637217D02*
Y650617D01*
G01X571587Y637217D02*
X582987D01*
G01X571587Y650617D02*
Y637217D01*
G01X566787Y644917D02*
Y628817D01*
G01X559787Y644917D02*
X566787D01*
G01X559787Y628817D02*
Y644917D01*
G01X566787Y628817D02*
X559787D01*
G01X559487Y659717D02*
Y655717D01*
X566887D01*
G01X586287Y706717D02*
X594287D01*
Y689117D01*
X586287D01*
Y706717D01*
G01X582987Y650617D02*
X571587D01*
G01X584587Y688917D02*
X579087D01*
G01X584587Y696917D02*
Y688917D01*
G01X566987D02*
Y696917D01*
G01X572487Y688917D02*
X566987D01*
G01X593000Y678400D02*
X592958Y678067D01*
X592792Y677775D01*
X592542Y677525D01*
X592250Y677358D01*
X591917Y677275D01*
X591583D01*
X591250Y677358D01*
X590958Y677525D01*
X590708Y677775D01*
X590542Y678067D01*
X590500Y678400D01*
X590542Y678733D01*
X590708Y679025D01*
X590958Y679275D01*
X591250Y679442D01*
X591583Y679525D01*
X591917D01*
X592250Y679442D01*
X592542Y679275D01*
X592792Y679025D01*
X592958Y678733D01*
X593000Y678400D01*
G01X592333Y678733D02*
X593000Y679233D01*
G01X592708Y680792D02*
X592917Y681083D01*
X593000Y681417D01*
X592917Y681750D01*
X592667Y682042D01*
X592292Y682250D01*
X591917Y682333D01*
X591458D01*
X591083Y682250D01*
X590750Y682042D01*
X590583Y681792D01*
X590500Y681500D01*
X590583Y681167D01*
X590750Y680917D01*
X591000Y680750D01*
X591333Y680667D01*
X591625Y680750D01*
X591917Y680958D01*
X592083Y681208D01*
X592125Y681500D01*
X592042Y681833D01*
X591833Y682083D01*
X591458Y682333D01*
G01X591958Y683808D02*
X591667Y684100D01*
X591500Y684350D01*
X591417Y684683D01*
X591500Y684975D01*
X591667Y685183D01*
X591917Y685350D01*
X592208Y685392D01*
X592458Y685350D01*
X592708Y685183D01*
X592917Y684933D01*
X593000Y684642D01*
X592917Y684308D01*
X592667Y684017D01*
X592292Y683850D01*
X591875Y683808D01*
X591333Y683892D01*
X591042Y684017D01*
X590750Y684225D01*
X590542Y684517D01*
X590500Y684808D01*
X590583Y685100D01*
X590792Y685308D01*
G01X588987Y668417D02*
X586887Y670217D01*
X588987Y672417D01*
G01X589087Y676017D02*
X569887D01*
Y664817D01*
X589087D01*
Y676017D01*
X588687D01*
G01X591000Y708517D02*
X588500D01*
Y709558D01*
X588625Y709892D01*
X588792Y710100D01*
X589125Y710183D01*
X589458Y710100D01*
X589667Y709850D01*
X589792Y709558D01*
Y708517D01*
G01Y709558D02*
X591000Y710183D01*
G01Y712950D02*
X588500D01*
X590292Y711408D01*
Y713492D01*
G01X590708Y714842D02*
X590917Y715133D01*
X591000Y715467D01*
X590917Y715800D01*
X590667Y716092D01*
X590292Y716300D01*
X589917Y716383D01*
X589458D01*
X589083Y716300D01*
X588750Y716092D01*
X588583Y715842D01*
X588500Y715550D01*
X588583Y715217D01*
X588750Y714967D01*
X589000Y714800D01*
X589333Y714717D01*
X589625Y714800D01*
X589917Y715008D01*
X590083Y715258D01*
X590125Y715550D01*
X590042Y715883D01*
X589833Y716133D01*
X589458Y716383D01*
G01X591000Y718567D02*
X590458Y718650D01*
X590000Y718775D01*
X589583Y718942D01*
X589125Y719150D01*
X588500Y719483D01*
Y717817D01*
G01X569017Y724500D02*
Y727000D01*
X570058D01*
X570392Y726875D01*
X570600Y726708D01*
X570683Y726375D01*
X570600Y726042D01*
X570350Y725833D01*
X570058Y725708D01*
X569017D01*
G01X570058D02*
X570683Y724500D01*
G01X573450D02*
Y727000D01*
X571908Y725208D01*
X573992D01*
G01X575342Y724792D02*
X575633Y724583D01*
X575967Y724500D01*
X576300Y724583D01*
X576592Y724833D01*
X576800Y725208D01*
X576883Y725583D01*
Y726042D01*
X576800Y726417D01*
X576592Y726750D01*
X576342Y726917D01*
X576050Y727000D01*
X575717Y726917D01*
X575467Y726750D01*
X575300Y726500D01*
X575217Y726167D01*
X575300Y725875D01*
X575508Y725583D01*
X575758Y725417D01*
X576050Y725375D01*
X576383Y725458D01*
X576633Y725667D01*
X576883Y726042D01*
G01X578442Y724792D02*
X578733Y724583D01*
X579067Y724500D01*
X579400Y724583D01*
X579692Y724833D01*
X579900Y725208D01*
X579983Y725583D01*
Y726042D01*
X579900Y726417D01*
X579692Y726750D01*
X579442Y726917D01*
X579150Y727000D01*
X578817Y726917D01*
X578567Y726750D01*
X578400Y726500D01*
X578317Y726167D01*
X578400Y725875D01*
X578608Y725583D01*
X578858Y725417D01*
X579150Y725375D01*
X579483Y725458D01*
X579733Y725667D01*
X579983Y726042D01*
G01X562487Y703417D02*
Y711417D01*
X580087D01*
Y703417D01*
X562487D01*
G01X584208Y733767D02*
X584083Y733517D01*
X584000Y733225D01*
Y732892D01*
X584125Y732517D01*
X584333Y732225D01*
X584583Y732017D01*
X585000Y731850D01*
X585375Y731808D01*
X585750Y731892D01*
X586000Y732017D01*
X586250Y732267D01*
X586417Y732558D01*
X586500Y732850D01*
Y733142D01*
X586417Y733433D01*
X586292Y733683D01*
X586125Y733892D01*
G01X584417Y735158D02*
X584167Y735408D01*
X584042Y735700D01*
X584000Y736033D01*
X584083Y736450D01*
X584292Y736742D01*
X584542Y736825D01*
X584792Y736783D01*
X585000Y736617D01*
X585417Y735783D01*
X585708Y735408D01*
X586125Y735158D01*
X586500Y735075D01*
Y736825D01*
G01X586125Y738133D02*
X586333Y738383D01*
X586458Y738675D01*
X586500Y739050D01*
X586417Y739425D01*
X586250Y739717D01*
X585958Y739925D01*
X585625Y739967D01*
X585292Y739883D01*
X585083Y739675D01*
X584917Y739383D01*
X584875Y739092D01*
X584917Y738800D01*
X585083Y738425D01*
X584000Y738550D01*
Y739675D01*
G01X586500Y742650D02*
X584000D01*
X585792Y741108D01*
Y743192D01*
G01X570054Y718709D02*
X569804Y718834D01*
X569512Y718917D01*
X569179D01*
X568804Y718792D01*
X568512Y718584D01*
X568304Y718334D01*
X568137Y717917D01*
X568095Y717542D01*
X568179Y717167D01*
X568304Y716917D01*
X568554Y716667D01*
X568845Y716500D01*
X569137Y716417D01*
X569429D01*
X569720Y716500D01*
X569970Y716625D01*
X570179Y716792D01*
G01X571445Y718500D02*
X571695Y718750D01*
X571987Y718875D01*
X572320Y718917D01*
X572737Y718834D01*
X573029Y718625D01*
X573112Y718375D01*
X573070Y718125D01*
X572904Y717917D01*
X572070Y717500D01*
X571695Y717209D01*
X571445Y716792D01*
X571362Y716417D01*
X573112D01*
G01X575837D02*
Y718917D01*
X574295Y717125D01*
X576379D01*
G01X577729Y716709D02*
X578020Y716500D01*
X578354Y716417D01*
X578687Y716500D01*
X578979Y716750D01*
X579187Y717125D01*
X579270Y717500D01*
Y717959D01*
X579187Y718334D01*
X578979Y718667D01*
X578729Y718834D01*
X578437Y718917D01*
X578104Y718834D01*
X577854Y718667D01*
X577687Y718417D01*
X577604Y718084D01*
X577687Y717792D01*
X577895Y717500D01*
X578145Y717334D01*
X578437Y717292D01*
X578770Y717375D01*
X579020Y717584D01*
X579270Y717959D01*
G01X579087Y696917D02*
X584587D01*
G01X566987D02*
X572487D01*
G01X586708Y746267D02*
X586583Y746017D01*
X586500Y745725D01*
Y745392D01*
X586625Y745017D01*
X586833Y744725D01*
X587083Y744517D01*
X587500Y744350D01*
X587875Y744308D01*
X588250Y744392D01*
X588500Y744517D01*
X588750Y744767D01*
X588917Y745058D01*
X589000Y745350D01*
Y745642D01*
X588917Y745933D01*
X588792Y746183D01*
X588625Y746392D01*
G01X586917Y747658D02*
X586667Y747908D01*
X586542Y748200D01*
X586500Y748533D01*
X586583Y748950D01*
X586792Y749242D01*
X587042Y749325D01*
X587292Y749283D01*
X587500Y749117D01*
X587917Y748283D01*
X588208Y747908D01*
X588625Y747658D01*
X589000Y747575D01*
Y749325D01*
G01X588625Y750633D02*
X588833Y750883D01*
X588958Y751175D01*
X589000Y751550D01*
X588917Y751925D01*
X588750Y752217D01*
X588458Y752425D01*
X588125Y752467D01*
X587792Y752383D01*
X587583Y752175D01*
X587417Y751883D01*
X587375Y751592D01*
X587417Y751300D01*
X587583Y750925D01*
X586500Y751050D01*
Y752175D01*
G01X588625Y753733D02*
X588833Y753983D01*
X588958Y754275D01*
X589000Y754650D01*
X588917Y755025D01*
X588750Y755317D01*
X588458Y755525D01*
X588125Y755567D01*
X587792Y755483D01*
X587583Y755275D01*
X587417Y754983D01*
X587375Y754692D01*
X587417Y754400D01*
X587583Y754025D01*
X586500Y754150D01*
Y755275D01*
G01X570267Y722792D02*
X570017Y722917D01*
X569725Y723000D01*
X569392D01*
X569017Y722875D01*
X568725Y722667D01*
X568517Y722417D01*
X568350Y722000D01*
X568308Y721625D01*
X568392Y721250D01*
X568517Y721000D01*
X568767Y720750D01*
X569058Y720583D01*
X569350Y720500D01*
X569642D01*
X569933Y720583D01*
X570183Y720708D01*
X570392Y720875D01*
G01X571658Y722583D02*
X571908Y722833D01*
X572200Y722958D01*
X572533Y723000D01*
X572950Y722917D01*
X573242Y722708D01*
X573325Y722458D01*
X573283Y722208D01*
X573117Y722000D01*
X572283Y721583D01*
X571908Y721292D01*
X571658Y720875D01*
X571575Y720500D01*
X573325D01*
G01X576050D02*
Y723000D01*
X574508Y721208D01*
X576592D01*
G01X578650Y720500D02*
X578942Y720542D01*
X579275Y720667D01*
X579483Y720875D01*
X579567Y721167D01*
X579483Y721458D01*
X579233Y721708D01*
X578858Y721833D01*
X578442D01*
X578192Y721917D01*
X577983Y722125D01*
X577900Y722417D01*
X578025Y722708D01*
X578317Y722917D01*
X578650Y723000D01*
X578983Y722917D01*
X579275Y722708D01*
X579400Y722417D01*
X579317Y722125D01*
X579108Y721917D01*
X578858Y721833D01*
X578442D01*
X578067Y721708D01*
X577817Y721458D01*
X577733Y721167D01*
X577817Y720875D01*
X578025Y720667D01*
X578358Y720542D01*
X578650Y720500D01*
G01X595775Y780500D02*
Y783000D01*
G01X597525D02*
Y780500D01*
G01Y781750D02*
X595775D01*
G01X598833Y780500D02*
Y783000D01*
X599667D01*
X600000Y782875D01*
X600250Y782708D01*
X600458Y782458D01*
X600625Y782167D01*
X600667Y781750D01*
X600625Y781333D01*
X600458Y781042D01*
X600250Y780792D01*
X600000Y780625D01*
X599667Y780500D01*
X598833D01*
G01X601933D02*
Y783000D01*
X602767D01*
X603100Y782875D01*
X603350Y782708D01*
X603558Y782458D01*
X603725Y782167D01*
X603767Y781750D01*
X603725Y781333D01*
X603558Y781042D01*
X603350Y780792D01*
X603100Y780625D01*
X602767Y780500D01*
X601933D01*
G01X605075Y780833D02*
X605408Y780625D01*
X605783Y780500D01*
X606117D01*
X606450Y780625D01*
X606700Y780833D01*
X606825Y781125D01*
X606742Y781417D01*
X606533Y781667D01*
X606158Y781833D01*
X605658Y781917D01*
X605367Y782083D01*
X605242Y782375D01*
X605325Y782667D01*
X605533Y782875D01*
X605825Y783000D01*
X606117D01*
X606408Y782917D01*
X606658Y782708D01*
G01X608008Y780500D02*
X609050Y783000D01*
X610092Y780500D01*
G01X609717Y781375D02*
X608383D01*
G01X611275Y780833D02*
X611608Y780625D01*
X611983Y780500D01*
X612317D01*
X612650Y780625D01*
X612900Y780833D01*
X613025Y781125D01*
X612942Y781417D01*
X612733Y781667D01*
X612358Y781833D01*
X611858Y781917D01*
X611567Y782083D01*
X611442Y782375D01*
X611525Y782667D01*
X611733Y782875D01*
X612025Y783000D01*
X612317D01*
X612608Y782917D01*
X612858Y782708D01*
G01X615250Y780500D02*
Y783000D01*
X614750Y782500D01*
G01Y780500D02*
X615750D01*
G01X617558Y781542D02*
X617850Y781833D01*
X618100Y782000D01*
X618433Y782083D01*
X618725Y782000D01*
X618933Y781833D01*
X619100Y781583D01*
X619142Y781292D01*
X619100Y781042D01*
X618933Y780792D01*
X618683Y780583D01*
X618392Y780500D01*
X618058Y780583D01*
X617767Y780833D01*
X617600Y781208D01*
X617558Y781625D01*
X617642Y782167D01*
X617767Y782458D01*
X617975Y782750D01*
X618267Y782958D01*
X618558Y783000D01*
X618850Y782917D01*
X619058Y782708D01*
G01X563877Y835425D02*
Y837925D01*
X565461D01*
G01X564877Y836717D02*
X563877D01*
G01X566936Y837925D02*
Y835425D01*
X568602D01*
G01X571702D02*
X570036D01*
Y837925D01*
X571702D01*
G01X571036Y836717D02*
X570036D01*
G01X573052Y835425D02*
Y837925D01*
X573886D01*
X574219Y837800D01*
X574469Y837633D01*
X574677Y837383D01*
X574844Y837092D01*
X574886Y836675D01*
X574844Y836258D01*
X574677Y835967D01*
X574469Y835717D01*
X574219Y835550D01*
X573886Y835425D01*
X573052D01*
G01X576152Y835800D02*
X576402Y835592D01*
X576694Y835467D01*
X577069Y835425D01*
X577444Y835508D01*
X577736Y835675D01*
X577944Y835967D01*
X577986Y836300D01*
X577902Y836633D01*
X577694Y836842D01*
X577402Y837008D01*
X577111Y837050D01*
X576819Y837008D01*
X576444Y836842D01*
X576569Y837925D01*
X577694D01*
G01X562529Y818809D02*
Y830009D01*
X571329D01*
Y818809D01*
X562529D01*
G01X575943Y948279D02*
X573443D01*
Y949320D01*
X573568Y949654D01*
X573735Y949862D01*
X574068Y949945D01*
X574401Y949862D01*
X574610Y949612D01*
X574735Y949320D01*
Y948279D01*
G01Y949320D02*
X575943Y949945D01*
G01X573860Y951420D02*
X573610Y951670D01*
X573485Y951962D01*
X573443Y952295D01*
X573526Y952712D01*
X573735Y953004D01*
X573985Y953087D01*
X574235Y953045D01*
X574443Y952879D01*
X574860Y952045D01*
X575151Y951670D01*
X575568Y951420D01*
X575943Y951337D01*
Y953087D01*
G01Y955812D02*
X573443D01*
X575235Y954270D01*
Y956354D01*
G01X573443Y958412D02*
X573526Y958079D01*
X573735Y957829D01*
X573985Y957662D01*
X574318Y957537D01*
X574693Y957495D01*
X575068Y957537D01*
X575401Y957662D01*
X575651Y957829D01*
X575860Y958079D01*
X575943Y958412D01*
X575860Y958745D01*
X575651Y958995D01*
X575401Y959162D01*
X575068Y959287D01*
X574693Y959329D01*
X574318Y959287D01*
X573985Y959162D01*
X573735Y958995D01*
X573526Y958745D01*
X573443Y958412D01*
G01X590974Y1127004D02*
X596024D01*
Y1225704D01*
X620674D01*
Y1041304D01*
X596024D01*
Y1100004D01*
X590974D01*
Y1127004D01*
G01X582404Y1071873D02*
Y1074373D01*
X583445D01*
X583779Y1074248D01*
X583987Y1074081D01*
X584070Y1073748D01*
X583987Y1073415D01*
X583737Y1073206D01*
X583445Y1073081D01*
X582404D01*
G01X583445D02*
X584070Y1071873D01*
G01X585545Y1073956D02*
X585795Y1074206D01*
X586087Y1074331D01*
X586420Y1074373D01*
X586837Y1074290D01*
X587129Y1074081D01*
X587212Y1073831D01*
X587170Y1073581D01*
X587004Y1073373D01*
X586170Y1072956D01*
X585795Y1072665D01*
X585545Y1072248D01*
X585462Y1071873D01*
X587212D01*
G01X588520Y1072373D02*
X588770Y1072081D01*
X589104Y1071915D01*
X589479Y1071873D01*
X589812Y1071915D01*
X590145Y1072123D01*
X590354Y1072373D01*
X590395Y1072623D01*
X590312Y1072915D01*
X590020Y1073123D01*
X589729Y1073206D01*
X589354D01*
G01X589729D02*
X589979Y1073331D01*
X590187Y1073540D01*
X590270Y1073790D01*
X590187Y1074040D01*
X589979Y1074248D01*
X589604Y1074373D01*
X589229Y1074331D01*
X588854Y1074165D01*
G01X592537Y1071873D02*
Y1074373D01*
X592037Y1073873D01*
G01Y1071873D02*
X593037D01*
G01X582617Y1067500D02*
Y1070000D01*
X583658D01*
X583992Y1069875D01*
X584200Y1069708D01*
X584283Y1069375D01*
X584200Y1069042D01*
X583950Y1068833D01*
X583658Y1068708D01*
X582617D01*
G01X583658D02*
X584283Y1067500D01*
G01X585758Y1069583D02*
X586008Y1069833D01*
X586300Y1069958D01*
X586633Y1070000D01*
X587050Y1069917D01*
X587342Y1069708D01*
X587425Y1069458D01*
X587383Y1069208D01*
X587217Y1069000D01*
X586383Y1068583D01*
X586008Y1068292D01*
X585758Y1067875D01*
X585675Y1067500D01*
X587425D01*
G01X588733Y1068000D02*
X588983Y1067708D01*
X589317Y1067542D01*
X589692Y1067500D01*
X590025Y1067542D01*
X590358Y1067750D01*
X590567Y1068000D01*
X590608Y1068250D01*
X590525Y1068542D01*
X590233Y1068750D01*
X589942Y1068833D01*
X589567D01*
G01X589942D02*
X590192Y1068958D01*
X590400Y1069167D01*
X590483Y1069417D01*
X590400Y1069667D01*
X590192Y1069875D01*
X589817Y1070000D01*
X589442Y1069958D01*
X589067Y1069792D01*
G01X593250Y1067500D02*
Y1070000D01*
X591708Y1068208D01*
X593792D01*
G01X591087Y1080173D02*
Y1084173D01*
X583687D01*
G01X582617Y1075500D02*
Y1078000D01*
X583658D01*
X583992Y1077875D01*
X584200Y1077708D01*
X584283Y1077375D01*
X584200Y1077042D01*
X583950Y1076833D01*
X583658Y1076708D01*
X582617D01*
G01X583658D02*
X584283Y1075500D01*
G01X585758Y1077583D02*
X586008Y1077833D01*
X586300Y1077958D01*
X586633Y1078000D01*
X587050Y1077917D01*
X587342Y1077708D01*
X587425Y1077458D01*
X587383Y1077208D01*
X587217Y1077000D01*
X586383Y1076583D01*
X586008Y1076292D01*
X585758Y1075875D01*
X585675Y1075500D01*
X587425D01*
G01X588733Y1076000D02*
X588983Y1075708D01*
X589317Y1075542D01*
X589692Y1075500D01*
X590025Y1075542D01*
X590358Y1075750D01*
X590567Y1076000D01*
X590608Y1076250D01*
X590525Y1076542D01*
X590233Y1076750D01*
X589942Y1076833D01*
X589567D01*
G01X589942D02*
X590192Y1076958D01*
X590400Y1077167D01*
X590483Y1077417D01*
X590400Y1077667D01*
X590192Y1077875D01*
X589817Y1078000D01*
X589442Y1077958D01*
X589067Y1077792D01*
G01X591833Y1075875D02*
X592083Y1075667D01*
X592375Y1075542D01*
X592750Y1075500D01*
X593125Y1075583D01*
X593417Y1075750D01*
X593625Y1076042D01*
X593667Y1076375D01*
X593583Y1076708D01*
X593375Y1076917D01*
X593083Y1077083D01*
X592792Y1077125D01*
X592500Y1077083D01*
X592125Y1076917D01*
X592250Y1078000D01*
X593375D01*
G01X570400Y1069017D02*
X567900D01*
Y1070058D01*
X568025Y1070392D01*
X568192Y1070600D01*
X568525Y1070683D01*
X568858Y1070600D01*
X569067Y1070350D01*
X569192Y1070058D01*
Y1069017D01*
G01Y1070058D02*
X570400Y1070683D01*
G01X568317Y1072158D02*
X568067Y1072408D01*
X567942Y1072700D01*
X567900Y1073033D01*
X567983Y1073450D01*
X568192Y1073742D01*
X568442Y1073825D01*
X568692Y1073783D01*
X568900Y1073617D01*
X569317Y1072783D01*
X569608Y1072408D01*
X570025Y1072158D01*
X570400Y1072075D01*
Y1073825D01*
G01X569900Y1075133D02*
X570192Y1075383D01*
X570358Y1075717D01*
X570400Y1076092D01*
X570358Y1076425D01*
X570150Y1076758D01*
X569900Y1076967D01*
X569650Y1077008D01*
X569358Y1076925D01*
X569150Y1076633D01*
X569067Y1076342D01*
Y1075967D01*
G01Y1076342D02*
X568942Y1076592D01*
X568733Y1076800D01*
X568483Y1076883D01*
X568233Y1076800D01*
X568025Y1076592D01*
X567900Y1076217D01*
X567942Y1075842D01*
X568108Y1075467D01*
G01X570108Y1078442D02*
X570317Y1078733D01*
X570400Y1079067D01*
X570317Y1079400D01*
X570067Y1079692D01*
X569692Y1079900D01*
X569317Y1079983D01*
X568858D01*
X568483Y1079900D01*
X568150Y1079692D01*
X567983Y1079442D01*
X567900Y1079150D01*
X567983Y1078817D01*
X568150Y1078567D01*
X568400Y1078400D01*
X568733Y1078317D01*
X569025Y1078400D01*
X569317Y1078608D01*
X569483Y1078858D01*
X569525Y1079150D01*
X569442Y1079483D01*
X569233Y1079733D01*
X568858Y1079983D01*
G01X571687Y1088873D02*
X567687D01*
Y1081473D01*
G01X574400Y1078500D02*
X574067Y1078542D01*
X573775Y1078708D01*
X573525Y1078958D01*
X573358Y1079250D01*
X573275Y1079583D01*
Y1079917D01*
X573358Y1080250D01*
X573525Y1080542D01*
X573775Y1080792D01*
X574067Y1080958D01*
X574400Y1081000D01*
X574733Y1080958D01*
X575025Y1080792D01*
X575275Y1080542D01*
X575442Y1080250D01*
X575525Y1079917D01*
Y1079583D01*
X575442Y1079250D01*
X575275Y1078958D01*
X575025Y1078708D01*
X574733Y1078542D01*
X574400Y1078500D01*
G01X574733Y1079167D02*
X575233Y1078500D01*
G01X576708Y1080583D02*
X576958Y1080833D01*
X577250Y1080958D01*
X577583Y1081000D01*
X578000Y1080917D01*
X578292Y1080708D01*
X578375Y1080458D01*
X578333Y1080208D01*
X578167Y1080000D01*
X577333Y1079583D01*
X576958Y1079292D01*
X576708Y1078875D01*
X576625Y1078500D01*
X578375D01*
G01X579683Y1078875D02*
X579933Y1078667D01*
X580225Y1078542D01*
X580600Y1078500D01*
X580975Y1078583D01*
X581267Y1078750D01*
X581475Y1079042D01*
X581517Y1079375D01*
X581433Y1079708D01*
X581225Y1079917D01*
X580933Y1080083D01*
X580642Y1080125D01*
X580350Y1080083D01*
X579975Y1079917D01*
X580100Y1081000D01*
X581225D01*
G01X564000Y1075033D02*
X561500D01*
Y1075867D01*
X561625Y1076200D01*
X561792Y1076450D01*
X562042Y1076658D01*
X562333Y1076825D01*
X562750Y1076867D01*
X563167Y1076825D01*
X563458Y1076658D01*
X563708Y1076450D01*
X563875Y1076200D01*
X564000Y1075867D01*
Y1075033D01*
G01Y1079550D02*
X561500D01*
X563292Y1078008D01*
Y1080092D01*
G01X566787Y1097673D02*
Y1081573D01*
G01X559787D02*
Y1097673D01*
G01X566787Y1081573D02*
X559787D01*
G01X559387Y1112473D02*
Y1108473D01*
X566787D01*
G01X591087Y1084873D02*
Y1088873D01*
X583687D01*
G01Y1098673D02*
Y1094673D01*
X591087D01*
G01X582987Y1103373D02*
X571587D01*
G01X582987Y1089973D02*
Y1103373D01*
G01X571587Y1089973D02*
X582987D01*
G01X571587Y1103373D02*
Y1089973D01*
G01X559787Y1097673D02*
X566787D01*
G01X593000Y1130900D02*
X592958Y1130567D01*
X592792Y1130275D01*
X592542Y1130025D01*
X592250Y1129858D01*
X591917Y1129775D01*
X591583D01*
X591250Y1129858D01*
X590958Y1130025D01*
X590708Y1130275D01*
X590542Y1130567D01*
X590500Y1130900D01*
X590542Y1131233D01*
X590708Y1131525D01*
X590958Y1131775D01*
X591250Y1131942D01*
X591583Y1132025D01*
X591917D01*
X592250Y1131942D01*
X592542Y1131775D01*
X592792Y1131525D01*
X592958Y1131233D01*
X593000Y1130900D01*
G01X592333Y1131233D02*
X593000Y1131733D01*
G01X590917Y1133208D02*
X590667Y1133458D01*
X590542Y1133750D01*
X590500Y1134083D01*
X590583Y1134500D01*
X590792Y1134792D01*
X591042Y1134875D01*
X591292Y1134833D01*
X591500Y1134667D01*
X591917Y1133833D01*
X592208Y1133458D01*
X592625Y1133208D01*
X593000Y1133125D01*
Y1134875D01*
G01Y1137600D02*
X590500D01*
X592292Y1136058D01*
Y1138142D01*
G01X588987Y1121173D02*
X586887Y1122973D01*
X588987Y1125173D01*
G01X589087Y1128773D02*
X569887D01*
Y1117573D01*
X589087D01*
Y1128773D01*
X588687D01*
G01X594000Y1161017D02*
X591500D01*
Y1162058D01*
X591625Y1162392D01*
X591792Y1162600D01*
X592125Y1162683D01*
X592458Y1162600D01*
X592667Y1162350D01*
X592792Y1162058D01*
Y1161017D01*
G01Y1162058D02*
X594000Y1162683D01*
G01X591917Y1164158D02*
X591667Y1164408D01*
X591542Y1164700D01*
X591500Y1165033D01*
X591583Y1165450D01*
X591792Y1165742D01*
X592042Y1165825D01*
X592292Y1165783D01*
X592500Y1165617D01*
X592917Y1164783D01*
X593208Y1164408D01*
X593625Y1164158D01*
X594000Y1164075D01*
Y1165825D01*
G01X591917Y1167258D02*
X591667Y1167508D01*
X591542Y1167800D01*
X591500Y1168133D01*
X591583Y1168550D01*
X591792Y1168842D01*
X592042Y1168925D01*
X592292Y1168883D01*
X592500Y1168717D01*
X592917Y1167883D01*
X593208Y1167508D01*
X593625Y1167258D01*
X594000Y1167175D01*
Y1168925D01*
G01Y1171150D02*
X591500D01*
X592000Y1170650D01*
G01X594000D02*
Y1171650D01*
G01X586287Y1159473D02*
X594287D01*
Y1141873D01*
X586287D01*
Y1159473D01*
G01X567891Y1168913D02*
Y1171413D01*
X568932D01*
X569266Y1171288D01*
X569474Y1171121D01*
X569557Y1170788D01*
X569474Y1170455D01*
X569224Y1170246D01*
X568932Y1170121D01*
X567891D01*
G01X568932D02*
X569557Y1168913D01*
G01X571032Y1170996D02*
X571282Y1171246D01*
X571574Y1171371D01*
X571907Y1171413D01*
X572324Y1171330D01*
X572616Y1171121D01*
X572699Y1170871D01*
X572657Y1170621D01*
X572491Y1170413D01*
X571657Y1169996D01*
X571282Y1169705D01*
X571032Y1169288D01*
X570949Y1168913D01*
X572699D01*
G01X574132Y1170996D02*
X574382Y1171246D01*
X574674Y1171371D01*
X575007Y1171413D01*
X575424Y1171330D01*
X575716Y1171121D01*
X575799Y1170871D01*
X575757Y1170621D01*
X575591Y1170413D01*
X574757Y1169996D01*
X574382Y1169705D01*
X574132Y1169288D01*
X574049Y1168913D01*
X575799D01*
G01X577107Y1169288D02*
X577357Y1169080D01*
X577649Y1168955D01*
X578024Y1168913D01*
X578399Y1168996D01*
X578691Y1169163D01*
X578899Y1169455D01*
X578941Y1169788D01*
X578857Y1170121D01*
X578649Y1170330D01*
X578357Y1170496D01*
X578066Y1170538D01*
X577774Y1170496D01*
X577399Y1170330D01*
X577524Y1171413D01*
X578649D01*
G01X562487Y1156173D02*
Y1164173D01*
X580087D01*
Y1156173D01*
X562487D01*
G01X583604Y1163465D02*
X583354Y1163590D01*
X583062Y1163673D01*
X582729D01*
X582354Y1163548D01*
X582062Y1163340D01*
X581854Y1163090D01*
X581687Y1162673D01*
X581645Y1162298D01*
X581729Y1161923D01*
X581854Y1161673D01*
X582104Y1161423D01*
X582395Y1161256D01*
X582687Y1161173D01*
X582979D01*
X583270Y1161256D01*
X583520Y1161381D01*
X583729Y1161548D01*
G01X585079Y1161465D02*
X585370Y1161256D01*
X585704Y1161173D01*
X586037Y1161256D01*
X586329Y1161506D01*
X586537Y1161881D01*
X586620Y1162256D01*
Y1162715D01*
X586537Y1163090D01*
X586329Y1163423D01*
X586079Y1163590D01*
X585787Y1163673D01*
X585454Y1163590D01*
X585204Y1163423D01*
X585037Y1163173D01*
X584954Y1162840D01*
X585037Y1162548D01*
X585245Y1162256D01*
X585495Y1162090D01*
X585787Y1162048D01*
X586120Y1162131D01*
X586370Y1162340D01*
X586620Y1162715D01*
G01X587970Y1161673D02*
X588220Y1161381D01*
X588554Y1161215D01*
X588929Y1161173D01*
X589262Y1161215D01*
X589595Y1161423D01*
X589804Y1161673D01*
X589845Y1161923D01*
X589762Y1162215D01*
X589470Y1162423D01*
X589179Y1162506D01*
X588804D01*
G01X589179D02*
X589429Y1162631D01*
X589637Y1162840D01*
X589720Y1163090D01*
X589637Y1163340D01*
X589429Y1163548D01*
X589054Y1163673D01*
X588679Y1163631D01*
X588304Y1163465D01*
G01X584587Y1141673D02*
X579087D01*
G01X584587Y1149673D02*
Y1141673D01*
G01X579087Y1149673D02*
X584587D01*
G01X566987D02*
X572487D01*
G01X566987Y1141673D02*
Y1149673D01*
G01X572487Y1141673D02*
X566987D01*
G01X583317Y1167292D02*
X583067Y1167417D01*
X582775Y1167500D01*
X582442D01*
X582067Y1167375D01*
X581775Y1167167D01*
X581567Y1166917D01*
X581400Y1166500D01*
X581358Y1166125D01*
X581442Y1165750D01*
X581567Y1165500D01*
X581817Y1165250D01*
X582108Y1165083D01*
X582400Y1165000D01*
X582692D01*
X582983Y1165083D01*
X583233Y1165208D01*
X583442Y1165375D01*
G01X584792Y1165292D02*
X585083Y1165083D01*
X585417Y1165000D01*
X585750Y1165083D01*
X586042Y1165333D01*
X586250Y1165708D01*
X586333Y1166083D01*
Y1166542D01*
X586250Y1166917D01*
X586042Y1167250D01*
X585792Y1167417D01*
X585500Y1167500D01*
X585167Y1167417D01*
X584917Y1167250D01*
X584750Y1167000D01*
X584667Y1166667D01*
X584750Y1166375D01*
X584958Y1166083D01*
X585208Y1165917D01*
X585500Y1165875D01*
X585833Y1165958D01*
X586083Y1166167D01*
X586333Y1166542D01*
G01X587808Y1167083D02*
X588058Y1167333D01*
X588350Y1167458D01*
X588683Y1167500D01*
X589100Y1167417D01*
X589392Y1167208D01*
X589475Y1166958D01*
X589433Y1166708D01*
X589267Y1166500D01*
X588433Y1166083D01*
X588058Y1165792D01*
X587808Y1165375D01*
X587725Y1165000D01*
X589475D01*
G01X583708Y1186317D02*
X583583Y1186067D01*
X583500Y1185775D01*
Y1185442D01*
X583625Y1185067D01*
X583833Y1184775D01*
X584083Y1184567D01*
X584500Y1184400D01*
X584875Y1184358D01*
X585250Y1184442D01*
X585500Y1184567D01*
X585750Y1184817D01*
X585917Y1185108D01*
X586000Y1185400D01*
Y1185692D01*
X585917Y1185983D01*
X585792Y1186233D01*
X585625Y1186442D01*
G01X585708Y1187792D02*
X585917Y1188083D01*
X586000Y1188417D01*
X585917Y1188750D01*
X585667Y1189042D01*
X585292Y1189250D01*
X584917Y1189333D01*
X584458D01*
X584083Y1189250D01*
X583750Y1189042D01*
X583583Y1188792D01*
X583500Y1188500D01*
X583583Y1188167D01*
X583750Y1187917D01*
X584000Y1187750D01*
X584333Y1187667D01*
X584625Y1187750D01*
X584917Y1187958D01*
X585083Y1188208D01*
X585125Y1188500D01*
X585042Y1188833D01*
X584833Y1189083D01*
X584458Y1189333D01*
G01X584958Y1190808D02*
X584667Y1191100D01*
X584500Y1191350D01*
X584417Y1191683D01*
X584500Y1191975D01*
X584667Y1192183D01*
X584917Y1192350D01*
X585208Y1192392D01*
X585458Y1192350D01*
X585708Y1192183D01*
X585917Y1191933D01*
X586000Y1191642D01*
X585917Y1191308D01*
X585667Y1191017D01*
X585292Y1190850D01*
X584875Y1190808D01*
X584333Y1190892D01*
X584042Y1191017D01*
X583750Y1191225D01*
X583542Y1191517D01*
X583500Y1191808D01*
X583583Y1192100D01*
X583792Y1192308D01*
G01X586208Y1196317D02*
X586083Y1196067D01*
X586000Y1195775D01*
Y1195442D01*
X586125Y1195067D01*
X586333Y1194775D01*
X586583Y1194567D01*
X587000Y1194400D01*
X587375Y1194358D01*
X587750Y1194442D01*
X588000Y1194567D01*
X588250Y1194817D01*
X588417Y1195108D01*
X588500Y1195400D01*
Y1195692D01*
X588417Y1195983D01*
X588292Y1196233D01*
X588125Y1196442D01*
G01X588208Y1197792D02*
X588417Y1198083D01*
X588500Y1198417D01*
X588417Y1198750D01*
X588167Y1199042D01*
X587792Y1199250D01*
X587417Y1199333D01*
X586958D01*
X586583Y1199250D01*
X586250Y1199042D01*
X586083Y1198792D01*
X586000Y1198500D01*
X586083Y1198167D01*
X586250Y1197917D01*
X586500Y1197750D01*
X586833Y1197667D01*
X587125Y1197750D01*
X587417Y1197958D01*
X587583Y1198208D01*
X587625Y1198500D01*
X587542Y1198833D01*
X587333Y1199083D01*
X586958Y1199333D01*
G01X588208Y1200892D02*
X588417Y1201183D01*
X588500Y1201517D01*
X588417Y1201850D01*
X588167Y1202142D01*
X587792Y1202350D01*
X587417Y1202433D01*
X586958D01*
X586583Y1202350D01*
X586250Y1202142D01*
X586083Y1201892D01*
X586000Y1201600D01*
X586083Y1201267D01*
X586250Y1201017D01*
X586500Y1200850D01*
X586833Y1200767D01*
X587125Y1200850D01*
X587417Y1201058D01*
X587583Y1201308D01*
X587625Y1201600D01*
X587542Y1201933D01*
X587333Y1202183D01*
X586958Y1202433D01*
G01X598699Y1234004D02*
Y1236504D01*
G01X600449D02*
Y1234004D01*
G01Y1235254D02*
X598699D01*
G01X601757Y1234004D02*
Y1236504D01*
X602591D01*
X602924Y1236379D01*
X603174Y1236212D01*
X603382Y1235962D01*
X603549Y1235671D01*
X603591Y1235254D01*
X603549Y1234837D01*
X603382Y1234546D01*
X603174Y1234296D01*
X602924Y1234129D01*
X602591Y1234004D01*
X601757D01*
G01X604857D02*
Y1236504D01*
X605691D01*
X606024Y1236379D01*
X606274Y1236212D01*
X606482Y1235962D01*
X606649Y1235671D01*
X606691Y1235254D01*
X606649Y1234837D01*
X606482Y1234546D01*
X606274Y1234296D01*
X606024Y1234129D01*
X605691Y1234004D01*
X604857D01*
G01X607999Y1234337D02*
X608332Y1234129D01*
X608707Y1234004D01*
X609041D01*
X609374Y1234129D01*
X609624Y1234337D01*
X609749Y1234629D01*
X609666Y1234921D01*
X609457Y1235171D01*
X609082Y1235337D01*
X608582Y1235421D01*
X608291Y1235587D01*
X608166Y1235879D01*
X608249Y1236171D01*
X608457Y1236379D01*
X608749Y1236504D01*
X609041D01*
X609332Y1236421D01*
X609582Y1236212D01*
G01X610932Y1234004D02*
X611974Y1236504D01*
X613016Y1234004D01*
G01X612641Y1234879D02*
X611307D01*
G01X614199Y1234337D02*
X614532Y1234129D01*
X614907Y1234004D01*
X615241D01*
X615574Y1234129D01*
X615824Y1234337D01*
X615949Y1234629D01*
X615866Y1234921D01*
X615657Y1235171D01*
X615282Y1235337D01*
X614782Y1235421D01*
X614491Y1235587D01*
X614366Y1235879D01*
X614449Y1236171D01*
X614657Y1236379D01*
X614949Y1236504D01*
X615241D01*
X615532Y1236421D01*
X615782Y1236212D01*
G01X618674Y1234004D02*
Y1236504D01*
X617132Y1234712D01*
X619216D01*
G01X562529Y1271565D02*
Y1282765D01*
X571329D01*
Y1271565D01*
X562529D01*
G01X559854Y1289200D02*
Y1291700D01*
X560895D01*
X561229Y1291575D01*
X561437Y1291408D01*
X561520Y1291075D01*
X561437Y1290742D01*
X561187Y1290533D01*
X560895Y1290408D01*
X559854D01*
G01X560895D02*
X561520Y1289200D01*
G01X562954Y1291700D02*
Y1289200D01*
X564620D01*
G01X567720D02*
X566054D01*
Y1291700D01*
X567720D01*
G01X567054Y1290492D02*
X566054D01*
G01X569070Y1289200D02*
Y1291700D01*
X569904D01*
X570237Y1291575D01*
X570487Y1291408D01*
X570695Y1291158D01*
X570862Y1290867D01*
X570904Y1290450D01*
X570862Y1290033D01*
X570695Y1289742D01*
X570487Y1289492D01*
X570237Y1289325D01*
X569904Y1289200D01*
X569070D01*
G01X572295Y1291283D02*
X572545Y1291533D01*
X572837Y1291658D01*
X573170Y1291700D01*
X573587Y1291617D01*
X573879Y1291408D01*
X573962Y1291158D01*
X573920Y1290908D01*
X573754Y1290700D01*
X572920Y1290283D01*
X572545Y1289992D01*
X572295Y1289575D01*
X572212Y1289200D01*
X573962D01*
G01X575479Y1289492D02*
X575770Y1289283D01*
X576104Y1289200D01*
X576437Y1289283D01*
X576729Y1289533D01*
X576937Y1289908D01*
X577020Y1290283D01*
Y1290742D01*
X576937Y1291117D01*
X576729Y1291450D01*
X576479Y1291617D01*
X576187Y1291700D01*
X575854Y1291617D01*
X575604Y1291450D01*
X575437Y1291200D01*
X575354Y1290867D01*
X575437Y1290575D01*
X575645Y1290283D01*
X575895Y1290117D01*
X576187Y1290075D01*
X576520Y1290158D01*
X576770Y1290367D01*
X577020Y1290742D01*
G01X620222Y100801D02*
Y103301D01*
X621263D01*
X621597Y103176D01*
X621805Y103009D01*
X621888Y102676D01*
X621805Y102343D01*
X621555Y102134D01*
X621263Y102009D01*
X620222D01*
G01X621263D02*
X621888Y100801D01*
G01X624155D02*
Y103301D01*
X623655Y102801D01*
G01Y100801D02*
X624655D01*
G01X627255D02*
Y103301D01*
X626755Y102801D01*
G01Y100801D02*
X627755D01*
G01X627097Y105633D02*
Y109633D01*
X619697D01*
G01X622848Y111722D02*
Y114222D01*
X623889D01*
X624223Y114097D01*
X624431Y113930D01*
X624514Y113597D01*
X624431Y113264D01*
X624181Y113055D01*
X623889Y112930D01*
X622848D01*
G01X623889D02*
X624514Y111722D01*
G01X625864Y112222D02*
X626114Y111930D01*
X626448Y111764D01*
X626823Y111722D01*
X627156Y111764D01*
X627489Y111972D01*
X627698Y112222D01*
X627739Y112472D01*
X627656Y112764D01*
X627364Y112972D01*
X627073Y113055D01*
X626698D01*
G01X627073D02*
X627323Y113180D01*
X627531Y113389D01*
X627614Y113639D01*
X627531Y113889D01*
X627323Y114097D01*
X626948Y114222D01*
X626573Y114180D01*
X626198Y114014D01*
G01X629798Y111722D02*
X629881Y112264D01*
X630006Y112722D01*
X630173Y113139D01*
X630381Y113597D01*
X630714Y114222D01*
X629048D01*
G01X632981Y111722D02*
X633273Y111764D01*
X633606Y111889D01*
X633814Y112097D01*
X633898Y112389D01*
X633814Y112680D01*
X633564Y112930D01*
X633189Y113055D01*
X632773D01*
X632523Y113139D01*
X632314Y113347D01*
X632231Y113639D01*
X632356Y113930D01*
X632648Y114139D01*
X632981Y114222D01*
X633314Y114139D01*
X633606Y113930D01*
X633731Y113639D01*
X633648Y113347D01*
X633439Y113139D01*
X633189Y113055D01*
X632773D01*
X632398Y112930D01*
X632148Y112680D01*
X632064Y112389D01*
X632148Y112097D01*
X632356Y111889D01*
X632689Y111764D01*
X632981Y111722D01*
G01X617101Y110329D02*
Y114329D01*
X609701D01*
G01X626926Y164684D02*
X626676Y164809D01*
X626384Y164892D01*
X626051D01*
X625676Y164767D01*
X625384Y164559D01*
X625176Y164309D01*
X625009Y163892D01*
X624967Y163517D01*
X625051Y163142D01*
X625176Y162892D01*
X625426Y162642D01*
X625717Y162475D01*
X626009Y162392D01*
X626301D01*
X626592Y162475D01*
X626842Y162600D01*
X627051Y162767D01*
G01X629609Y162392D02*
Y164892D01*
X628067Y163100D01*
X630151D01*
G01X632209Y164892D02*
X631876Y164809D01*
X631626Y164600D01*
X631459Y164350D01*
X631334Y164017D01*
X631292Y163642D01*
X631334Y163267D01*
X631459Y162934D01*
X631626Y162684D01*
X631876Y162475D01*
X632209Y162392D01*
X632542Y162475D01*
X632792Y162684D01*
X632959Y162934D01*
X633084Y163267D01*
X633126Y163642D01*
X633084Y164017D01*
X632959Y164350D01*
X632792Y164600D01*
X632542Y164809D01*
X632209Y164892D01*
G01X634392Y162892D02*
X634642Y162600D01*
X634976Y162434D01*
X635351Y162392D01*
X635684Y162434D01*
X636017Y162642D01*
X636226Y162892D01*
X636267Y163142D01*
X636184Y163434D01*
X635892Y163642D01*
X635601Y163725D01*
X635226D01*
G01X635601D02*
X635851Y163850D01*
X636059Y164059D01*
X636142Y164309D01*
X636059Y164559D01*
X635851Y164767D01*
X635476Y164892D01*
X635101Y164850D01*
X634726Y164684D01*
G01X626767Y168792D02*
X626517Y168917D01*
X626225Y169000D01*
X625892D01*
X625517Y168875D01*
X625225Y168667D01*
X625017Y168417D01*
X624850Y168000D01*
X624808Y167625D01*
X624892Y167250D01*
X625017Y167000D01*
X625267Y166750D01*
X625558Y166583D01*
X625850Y166500D01*
X626142D01*
X626433Y166583D01*
X626683Y166708D01*
X626892Y166875D01*
G01X629450Y166500D02*
Y169000D01*
X627908Y167208D01*
X629992D01*
G01X632050Y169000D02*
X631717Y168917D01*
X631467Y168708D01*
X631300Y168458D01*
X631175Y168125D01*
X631133Y167750D01*
X631175Y167375D01*
X631300Y167042D01*
X631467Y166792D01*
X631717Y166583D01*
X632050Y166500D01*
X632383Y166583D01*
X632633Y166792D01*
X632800Y167042D01*
X632925Y167375D01*
X632967Y167750D01*
X632925Y168125D01*
X632800Y168458D01*
X632633Y168708D01*
X632383Y168917D01*
X632050Y169000D01*
G01X634358Y168583D02*
X634608Y168833D01*
X634900Y168958D01*
X635233Y169000D01*
X635650Y168917D01*
X635942Y168708D01*
X636025Y168458D01*
X635983Y168208D01*
X635817Y168000D01*
X634983Y167583D01*
X634608Y167292D01*
X634358Y166875D01*
X634275Y166500D01*
X636025D01*
G01X631804Y231761D02*
Y234261D01*
X632845D01*
X633179Y234136D01*
X633387Y233969D01*
X633470Y233636D01*
X633387Y233303D01*
X633137Y233094D01*
X632845Y232969D01*
X631804D01*
G01X632845D02*
X633470Y231761D01*
G01X635654D02*
X635737Y232303D01*
X635862Y232761D01*
X636029Y233178D01*
X636237Y233636D01*
X636570Y234261D01*
X634904D01*
G01X638754Y231761D02*
X638837Y232303D01*
X638962Y232761D01*
X639129Y233178D01*
X639337Y233636D01*
X639670Y234261D01*
X638004D01*
G01X642437Y231761D02*
Y234261D01*
X640895Y232469D01*
X642979D01*
G01X641487Y242761D02*
Y246761D01*
X634087D01*
G01X639517Y250000D02*
Y252500D01*
X640558D01*
X640892Y252375D01*
X641100Y252208D01*
X641183Y251875D01*
X641100Y251542D01*
X640850Y251333D01*
X640558Y251208D01*
X639517D01*
G01X640558D02*
X641183Y250000D01*
G01X643367D02*
X643450Y250542D01*
X643575Y251000D01*
X643742Y251417D01*
X643950Y251875D01*
X644283Y252500D01*
X642617D01*
G01X646467Y250000D02*
X646550Y250542D01*
X646675Y251000D01*
X646842Y251417D01*
X647050Y251875D01*
X647383Y252500D01*
X645717D01*
G01X649650Y250000D02*
X649942Y250042D01*
X650275Y250167D01*
X650483Y250375D01*
X650567Y250667D01*
X650483Y250958D01*
X650233Y251208D01*
X649858Y251333D01*
X649442D01*
X649192Y251417D01*
X648983Y251625D01*
X648900Y251917D01*
X649025Y252208D01*
X649317Y252417D01*
X649650Y252500D01*
X649983Y252417D01*
X650275Y252208D01*
X650400Y251917D01*
X650317Y251625D01*
X650108Y251417D01*
X649858Y251333D01*
X649442D01*
X649067Y251208D01*
X648817Y250958D01*
X648733Y250667D01*
X648817Y250375D01*
X649025Y250167D01*
X649358Y250042D01*
X649650Y250000D01*
G01X633554Y229953D02*
X633304Y230078D01*
X633012Y230161D01*
X632679D01*
X632304Y230036D01*
X632012Y229828D01*
X631804Y229578D01*
X631637Y229161D01*
X631595Y228786D01*
X631679Y228411D01*
X631804Y228161D01*
X632054Y227911D01*
X632345Y227744D01*
X632637Y227661D01*
X632929D01*
X633220Y227744D01*
X633470Y227869D01*
X633679Y228036D01*
G01X636237Y227661D02*
Y230161D01*
X634695Y228369D01*
X636779D01*
G01X638837Y227661D02*
Y230161D01*
X638337Y229661D01*
G01Y227661D02*
X639337D01*
G01X641937Y230161D02*
X641604Y230078D01*
X641354Y229869D01*
X641187Y229619D01*
X641062Y229286D01*
X641020Y228911D01*
X641062Y228536D01*
X641187Y228203D01*
X641354Y227953D01*
X641604Y227744D01*
X641937Y227661D01*
X642270Y227744D01*
X642520Y227953D01*
X642687Y228203D01*
X642812Y228536D01*
X642854Y228911D01*
X642812Y229286D01*
X642687Y229619D01*
X642520Y229869D01*
X642270Y230078D01*
X641937Y230161D01*
G01X629000Y263800D02*
X631500D01*
G01X629000Y262842D02*
Y264758D01*
G01X631500Y266067D02*
X629000D01*
Y267067D01*
X629125Y267400D01*
X629417Y267650D01*
X629750Y267733D01*
X630083Y267650D01*
X630333Y267442D01*
X630458Y267067D01*
Y266067D01*
G01X631500Y270000D02*
X629000D01*
X629500Y269500D01*
G01X631500D02*
Y270500D01*
G01Y273600D02*
X629000D01*
X630792Y272058D01*
Y274142D01*
G01X629417Y275408D02*
X629167Y275658D01*
X629042Y275950D01*
X629000Y276283D01*
X629083Y276700D01*
X629292Y276992D01*
X629542Y277075D01*
X629792Y277033D01*
X630000Y276867D01*
X630417Y276033D01*
X630708Y275658D01*
X631125Y275408D01*
X631500Y275325D01*
Y277075D01*
G01X610044Y492098D02*
X610002Y491765D01*
X609836Y491473D01*
X609586Y491223D01*
X609294Y491056D01*
X608961Y490973D01*
X608627D01*
X608294Y491056D01*
X608002Y491223D01*
X607752Y491473D01*
X607586Y491765D01*
X607544Y492098D01*
X607586Y492431D01*
X607752Y492723D01*
X608002Y492973D01*
X608294Y493140D01*
X608627Y493223D01*
X608961D01*
X609294Y493140D01*
X609586Y492973D01*
X609836Y492723D01*
X610002Y492431D01*
X610044Y492098D01*
G01X609377Y492431D02*
X610044Y492931D01*
G01X607961Y494406D02*
X607711Y494656D01*
X607586Y494948D01*
X607544Y495281D01*
X607627Y495698D01*
X607836Y495990D01*
X608086Y496073D01*
X608336Y496031D01*
X608544Y495865D01*
X608961Y495031D01*
X609252Y494656D01*
X609669Y494406D01*
X610044Y494323D01*
Y496073D01*
G01Y498298D02*
X610002Y498590D01*
X609877Y498923D01*
X609669Y499131D01*
X609377Y499215D01*
X609086Y499131D01*
X608836Y498881D01*
X608711Y498506D01*
Y498090D01*
X608627Y497840D01*
X608419Y497631D01*
X608127Y497548D01*
X607836Y497673D01*
X607627Y497965D01*
X607544Y498298D01*
X607627Y498631D01*
X607836Y498923D01*
X608127Y499048D01*
X608419Y498965D01*
X608627Y498756D01*
X608711Y498506D01*
Y498090D01*
X608836Y497715D01*
X609086Y497465D01*
X609377Y497381D01*
X609669Y497465D01*
X609877Y497673D01*
X610002Y498006D01*
X610044Y498298D01*
G01X607544Y501398D02*
X607627Y501065D01*
X607836Y500815D01*
X608086Y500648D01*
X608419Y500523D01*
X608794Y500481D01*
X609169Y500523D01*
X609502Y500648D01*
X609752Y500815D01*
X609961Y501065D01*
X610044Y501398D01*
X609961Y501731D01*
X609752Y501981D01*
X609502Y502148D01*
X609169Y502273D01*
X608794Y502315D01*
X608419Y502273D01*
X608086Y502148D01*
X607836Y501981D01*
X607627Y501731D01*
X607544Y501398D01*
G01X630528Y495805D02*
Y509805D01*
G01X617528Y495805D02*
X630528D01*
G01X617528Y509805D02*
Y495805D01*
G01X614575Y492247D02*
X614533Y491914D01*
X614367Y491622D01*
X614117Y491372D01*
X613825Y491205D01*
X613492Y491122D01*
X613158D01*
X612825Y491205D01*
X612533Y491372D01*
X612283Y491622D01*
X612117Y491914D01*
X612075Y492247D01*
X612117Y492580D01*
X612283Y492872D01*
X612533Y493122D01*
X612825Y493289D01*
X613158Y493372D01*
X613492D01*
X613825Y493289D01*
X614117Y493122D01*
X614367Y492872D01*
X614533Y492580D01*
X614575Y492247D01*
G01X613908Y492580D02*
X614575Y493080D01*
G01X612492Y494555D02*
X612242Y494805D01*
X612117Y495097D01*
X612075Y495430D01*
X612158Y495847D01*
X612367Y496139D01*
X612617Y496222D01*
X612867Y496180D01*
X613075Y496014D01*
X613492Y495180D01*
X613783Y494805D01*
X614200Y494555D01*
X614575Y494472D01*
Y496222D01*
G01Y498947D02*
X612075D01*
X613867Y497405D01*
Y499489D01*
G01X614575Y502047D02*
X612075D01*
X613867Y500505D01*
Y502589D01*
G01X644763Y495768D02*
Y509768D01*
G01X631763Y495768D02*
X644763D01*
G01X631763Y509768D02*
Y495768D01*
G01X647967Y550000D02*
Y552500D01*
X649008D01*
X649342Y552375D01*
X649550Y552208D01*
X649633Y551875D01*
X649550Y551542D01*
X649300Y551333D01*
X649008Y551208D01*
X647967D01*
G01X649008D02*
X649633Y550000D01*
G01X651900D02*
Y552500D01*
X651400Y552000D01*
G01Y550000D02*
X652400D01*
G01X655000Y552500D02*
X654667Y552417D01*
X654417Y552208D01*
X654250Y551958D01*
X654125Y551625D01*
X654083Y551250D01*
X654125Y550875D01*
X654250Y550542D01*
X654417Y550292D01*
X654667Y550083D01*
X655000Y550000D01*
X655333Y550083D01*
X655583Y550292D01*
X655750Y550542D01*
X655875Y550875D01*
X655917Y551250D01*
X655875Y551625D01*
X655750Y551958D01*
X655583Y552208D01*
X655333Y552417D01*
X655000Y552500D01*
G01X657308Y551042D02*
X657600Y551333D01*
X657850Y551500D01*
X658183Y551583D01*
X658475Y551500D01*
X658683Y551333D01*
X658850Y551083D01*
X658892Y550792D01*
X658850Y550542D01*
X658683Y550292D01*
X658433Y550083D01*
X658142Y550000D01*
X657808Y550083D01*
X657517Y550333D01*
X657350Y550708D01*
X657308Y551125D01*
X657392Y551667D01*
X657517Y551958D01*
X657725Y552250D01*
X658017Y552458D01*
X658308Y552500D01*
X658600Y552417D01*
X658808Y552208D01*
G01X661700Y550000D02*
Y552500D01*
X660158Y550708D01*
X662242D01*
G01X646000Y546967D02*
X643500D01*
Y548008D01*
X643625Y548342D01*
X643792Y548550D01*
X644125Y548633D01*
X644458Y548550D01*
X644667Y548300D01*
X644792Y548008D01*
Y546967D01*
G01Y548008D02*
X646000Y548633D01*
G01Y550900D02*
X643500D01*
X644000Y550400D01*
G01X646000D02*
Y551400D01*
G01X643500Y554000D02*
X643583Y553667D01*
X643792Y553417D01*
X644042Y553250D01*
X644375Y553125D01*
X644750Y553083D01*
X645125Y553125D01*
X645458Y553250D01*
X645708Y553417D01*
X645917Y553667D01*
X646000Y554000D01*
X645917Y554333D01*
X645708Y554583D01*
X645458Y554750D01*
X645125Y554875D01*
X644750Y554917D01*
X644375Y554875D01*
X644042Y554750D01*
X643792Y554583D01*
X643583Y554333D01*
X643500Y554000D01*
G01X644958Y556308D02*
X644667Y556600D01*
X644500Y556850D01*
X644417Y557183D01*
X644500Y557475D01*
X644667Y557683D01*
X644917Y557850D01*
X645208Y557892D01*
X645458Y557850D01*
X645708Y557683D01*
X645917Y557433D01*
X646000Y557142D01*
X645917Y556808D01*
X645667Y556517D01*
X645292Y556350D01*
X644875Y556308D01*
X644333Y556392D01*
X644042Y556517D01*
X643750Y556725D01*
X643542Y557017D01*
X643500Y557308D01*
X643583Y557600D01*
X643792Y557808D01*
G01X644958Y559408D02*
X644667Y559700D01*
X644500Y559950D01*
X644417Y560283D01*
X644500Y560575D01*
X644667Y560783D01*
X644917Y560950D01*
X645208Y560992D01*
X645458Y560950D01*
X645708Y560783D01*
X645917Y560533D01*
X646000Y560242D01*
X645917Y559908D01*
X645667Y559617D01*
X645292Y559450D01*
X644875Y559408D01*
X644333Y559492D01*
X644042Y559617D01*
X643750Y559825D01*
X643542Y560117D01*
X643500Y560408D01*
X643583Y560700D01*
X643792Y560908D01*
G01X613910Y557074D02*
X609910D01*
Y549674D01*
G01X644701Y519341D02*
Y521841D01*
X645742D01*
X646076Y521716D01*
X646284Y521549D01*
X646367Y521216D01*
X646284Y520883D01*
X646034Y520674D01*
X645742Y520549D01*
X644701D01*
G01X645742D02*
X646367Y519341D01*
G01X647717Y519716D02*
X647967Y519508D01*
X648259Y519383D01*
X648634Y519341D01*
X649009Y519424D01*
X649301Y519591D01*
X649509Y519883D01*
X649551Y520216D01*
X649467Y520549D01*
X649259Y520758D01*
X648967Y520924D01*
X648676Y520966D01*
X648384Y520924D01*
X648009Y520758D01*
X648134Y521841D01*
X649259D01*
G01X650942Y521424D02*
X651192Y521674D01*
X651484Y521799D01*
X651817Y521841D01*
X652234Y521758D01*
X652526Y521549D01*
X652609Y521299D01*
X652567Y521049D01*
X652401Y520841D01*
X651567Y520424D01*
X651192Y520133D01*
X650942Y519716D01*
X650859Y519341D01*
X652609D01*
G01X655334D02*
Y521841D01*
X653792Y520049D01*
X655876D01*
G01X644084Y510541D02*
Y514541D01*
X636684D01*
G01X629674Y519137D02*
Y521637D01*
X630715D01*
X631049Y521512D01*
X631257Y521345D01*
X631340Y521012D01*
X631257Y520679D01*
X631007Y520470D01*
X630715Y520345D01*
X629674D01*
G01X630715D02*
X631340Y519137D01*
G01X632690Y519512D02*
X632940Y519304D01*
X633232Y519179D01*
X633607Y519137D01*
X633982Y519220D01*
X634274Y519387D01*
X634482Y519679D01*
X634524Y520012D01*
X634440Y520345D01*
X634232Y520554D01*
X633940Y520720D01*
X633649Y520762D01*
X633357Y520720D01*
X632982Y520554D01*
X633107Y521637D01*
X634232D01*
G01X635915Y521220D02*
X636165Y521470D01*
X636457Y521595D01*
X636790Y521637D01*
X637207Y521554D01*
X637499Y521345D01*
X637582Y521095D01*
X637540Y520845D01*
X637374Y520637D01*
X636540Y520220D01*
X636165Y519929D01*
X635915Y519512D01*
X635832Y519137D01*
X637582D01*
G01X638890Y519637D02*
X639140Y519345D01*
X639474Y519179D01*
X639849Y519137D01*
X640182Y519179D01*
X640515Y519387D01*
X640724Y519637D01*
X640765Y519887D01*
X640682Y520179D01*
X640390Y520387D01*
X640099Y520470D01*
X639724D01*
G01X640099D02*
X640349Y520595D01*
X640557Y520804D01*
X640640Y521054D01*
X640557Y521304D01*
X640349Y521512D01*
X639974Y521637D01*
X639599Y521595D01*
X639224Y521429D01*
G01X629857Y510537D02*
Y514537D01*
X622457D01*
G01X630528Y509805D02*
X617528D01*
G01X644763Y509768D02*
X631763D01*
G01X612168Y509995D02*
Y522995D01*
G01X649967Y535000D02*
Y537500D01*
X651008D01*
X651342Y537375D01*
X651550Y537208D01*
X651633Y536875D01*
X651550Y536542D01*
X651300Y536333D01*
X651008Y536208D01*
X649967D01*
G01X651008D02*
X651633Y535000D01*
G01X653900D02*
Y537500D01*
X653400Y537000D01*
G01Y535000D02*
X654400D01*
G01X657000Y537500D02*
X656667Y537417D01*
X656417Y537208D01*
X656250Y536958D01*
X656125Y536625D01*
X656083Y536250D01*
X656125Y535875D01*
X656250Y535542D01*
X656417Y535292D01*
X656667Y535083D01*
X657000Y535000D01*
X657333Y535083D01*
X657583Y535292D01*
X657750Y535542D01*
X657875Y535875D01*
X657917Y536250D01*
X657875Y536625D01*
X657750Y536958D01*
X657583Y537208D01*
X657333Y537417D01*
X657000Y537500D01*
G01X659183Y535375D02*
X659433Y535167D01*
X659725Y535042D01*
X660100Y535000D01*
X660475Y535083D01*
X660767Y535250D01*
X660975Y535542D01*
X661017Y535875D01*
X660933Y536208D01*
X660725Y536417D01*
X660433Y536583D01*
X660142Y536625D01*
X659850Y536583D01*
X659475Y536417D01*
X659600Y537500D01*
X660725D01*
G01X662283Y535500D02*
X662533Y535208D01*
X662867Y535042D01*
X663242Y535000D01*
X663575Y535042D01*
X663908Y535250D01*
X664117Y535500D01*
X664158Y535750D01*
X664075Y536042D01*
X663783Y536250D01*
X663492Y536333D01*
X663117D01*
G01X663492D02*
X663742Y536458D01*
X663950Y536667D01*
X664033Y536917D01*
X663950Y537167D01*
X663742Y537375D01*
X663367Y537500D01*
X662992Y537458D01*
X662617Y537292D01*
G01X611558Y540745D02*
Y536745D01*
X618958D01*
G01X633746Y534831D02*
Y537331D01*
X634787D01*
X635121Y537206D01*
X635329Y537039D01*
X635412Y536706D01*
X635329Y536373D01*
X635079Y536164D01*
X634787Y536039D01*
X633746D01*
G01X634787D02*
X635412Y534831D01*
G01X637679D02*
Y537331D01*
X637179Y536831D01*
G01Y534831D02*
X638179D01*
G01X640779Y537331D02*
X640446Y537248D01*
X640196Y537039D01*
X640029Y536789D01*
X639904Y536456D01*
X639862Y536081D01*
X639904Y535706D01*
X640029Y535373D01*
X640196Y535123D01*
X640446Y534914D01*
X640779Y534831D01*
X641112Y534914D01*
X641362Y535123D01*
X641529Y535373D01*
X641654Y535706D01*
X641696Y536081D01*
X641654Y536456D01*
X641529Y536789D01*
X641362Y537039D01*
X641112Y537248D01*
X640779Y537331D01*
G01X643879Y534831D02*
X644171Y534873D01*
X644504Y534998D01*
X644712Y535206D01*
X644796Y535498D01*
X644712Y535789D01*
X644462Y536039D01*
X644087Y536164D01*
X643671D01*
X643421Y536248D01*
X643212Y536456D01*
X643129Y536748D01*
X643254Y537039D01*
X643546Y537248D01*
X643879Y537331D01*
X644212Y537248D01*
X644504Y537039D01*
X644629Y536748D01*
X644546Y536456D01*
X644337Y536248D01*
X644087Y536164D01*
X643671D01*
X643296Y536039D01*
X643046Y535789D01*
X642962Y535498D01*
X643046Y535206D01*
X643254Y534998D01*
X643587Y534873D01*
X643879Y534831D01*
G01X646979D02*
Y537331D01*
X646479Y536831D01*
G01Y534831D02*
X647479D01*
G01X633746Y538831D02*
Y541331D01*
X634787D01*
X635121Y541206D01*
X635329Y541039D01*
X635412Y540706D01*
X635329Y540373D01*
X635079Y540164D01*
X634787Y540039D01*
X633746D01*
G01X634787D02*
X635412Y538831D01*
G01X637679D02*
Y541331D01*
X637179Y540831D01*
G01Y538831D02*
X638179D01*
G01X640779Y541331D02*
X640446Y541248D01*
X640196Y541039D01*
X640029Y540789D01*
X639904Y540456D01*
X639862Y540081D01*
X639904Y539706D01*
X640029Y539373D01*
X640196Y539123D01*
X640446Y538914D01*
X640779Y538831D01*
X641112Y538914D01*
X641362Y539123D01*
X641529Y539373D01*
X641654Y539706D01*
X641696Y540081D01*
X641654Y540456D01*
X641529Y540789D01*
X641362Y541039D01*
X641112Y541248D01*
X640779Y541331D01*
G01X643796Y538831D02*
X643879Y539373D01*
X644004Y539831D01*
X644171Y540248D01*
X644379Y540706D01*
X644712Y541331D01*
X643046D01*
G01X646979Y538831D02*
X647271Y538873D01*
X647604Y538998D01*
X647812Y539206D01*
X647896Y539498D01*
X647812Y539789D01*
X647562Y540039D01*
X647187Y540164D01*
X646771D01*
X646521Y540248D01*
X646312Y540456D01*
X646229Y540748D01*
X646354Y541039D01*
X646646Y541248D01*
X646979Y541331D01*
X647312Y541248D01*
X647604Y541039D01*
X647729Y540748D01*
X647646Y540456D01*
X647437Y540248D01*
X647187Y540164D01*
X646771D01*
X646396Y540039D01*
X646146Y539789D01*
X646062Y539498D01*
X646146Y539206D01*
X646354Y538998D01*
X646687Y538873D01*
X646979Y538831D01*
G01X621705Y516453D02*
X619205D01*
Y517494D01*
X619330Y517828D01*
X619497Y518036D01*
X619830Y518119D01*
X620163Y518036D01*
X620372Y517786D01*
X620497Y517494D01*
Y516453D01*
G01Y517494D02*
X621705Y518119D01*
G01Y520386D02*
X619205D01*
X619705Y519886D01*
G01X621705D02*
Y520886D01*
G01X619205Y523486D02*
X619288Y523153D01*
X619497Y522903D01*
X619747Y522736D01*
X620080Y522611D01*
X620455Y522569D01*
X620830Y522611D01*
X621163Y522736D01*
X621413Y522903D01*
X621622Y523153D01*
X621705Y523486D01*
X621622Y523819D01*
X621413Y524069D01*
X621163Y524236D01*
X620830Y524361D01*
X620455Y524403D01*
X620080Y524361D01*
X619747Y524236D01*
X619497Y524069D01*
X619288Y523819D01*
X619205Y523486D01*
G01X621205Y525669D02*
X621497Y525919D01*
X621663Y526253D01*
X621705Y526628D01*
X621663Y526961D01*
X621455Y527294D01*
X621205Y527503D01*
X620955Y527544D01*
X620663Y527461D01*
X620455Y527169D01*
X620372Y526878D01*
Y526503D01*
G01Y526878D02*
X620247Y527128D01*
X620038Y527336D01*
X619788Y527419D01*
X619538Y527336D01*
X619330Y527128D01*
X619205Y526753D01*
X619247Y526378D01*
X619413Y526003D01*
G01X621705Y529686D02*
X621663Y529978D01*
X621538Y530311D01*
X621330Y530519D01*
X621038Y530603D01*
X620747Y530519D01*
X620497Y530269D01*
X620372Y529894D01*
Y529478D01*
X620288Y529228D01*
X620080Y529019D01*
X619788Y528936D01*
X619497Y529061D01*
X619288Y529353D01*
X619205Y529686D01*
X619288Y530019D01*
X619497Y530311D01*
X619788Y530436D01*
X620080Y530353D01*
X620288Y530144D01*
X620372Y529894D01*
Y529478D01*
X620497Y529103D01*
X620747Y528853D01*
X621038Y528769D01*
X621330Y528853D01*
X621538Y529061D01*
X621663Y529394D01*
X621705Y529686D01*
G01X613100Y514900D02*
X617100D01*
Y522300D01*
G01X649967Y539000D02*
Y541500D01*
X651008D01*
X651342Y541375D01*
X651550Y541208D01*
X651633Y540875D01*
X651550Y540542D01*
X651300Y540333D01*
X651008Y540208D01*
X649967D01*
G01X651008D02*
X651633Y539000D01*
G01X653900D02*
Y541500D01*
X653400Y541000D01*
G01Y539000D02*
X654400D01*
G01X657000Y541500D02*
X656667Y541417D01*
X656417Y541208D01*
X656250Y540958D01*
X656125Y540625D01*
X656083Y540250D01*
X656125Y539875D01*
X656250Y539542D01*
X656417Y539292D01*
X656667Y539083D01*
X657000Y539000D01*
X657333Y539083D01*
X657583Y539292D01*
X657750Y539542D01*
X657875Y539875D01*
X657917Y540250D01*
X657875Y540625D01*
X657750Y540958D01*
X657583Y541208D01*
X657333Y541417D01*
X657000Y541500D01*
G01X659183Y539375D02*
X659433Y539167D01*
X659725Y539042D01*
X660100Y539000D01*
X660475Y539083D01*
X660767Y539250D01*
X660975Y539542D01*
X661017Y539875D01*
X660933Y540208D01*
X660725Y540417D01*
X660433Y540583D01*
X660142Y540625D01*
X659850Y540583D01*
X659475Y540417D01*
X659600Y541500D01*
X660725D01*
G01X662408Y541083D02*
X662658Y541333D01*
X662950Y541458D01*
X663283Y541500D01*
X663700Y541417D01*
X663992Y541208D01*
X664075Y540958D01*
X664033Y540708D01*
X663867Y540500D01*
X663033Y540083D01*
X662658Y539792D01*
X662408Y539375D01*
X662325Y539000D01*
X664075D01*
G01X611558Y544745D02*
Y540745D01*
X618958D01*
G01X622467Y550000D02*
Y552500D01*
X623508D01*
X623842Y552375D01*
X624050Y552208D01*
X624133Y551875D01*
X624050Y551542D01*
X623800Y551333D01*
X623508Y551208D01*
X622467D01*
G01X623508D02*
X624133Y550000D01*
G01X626400D02*
Y552500D01*
X625900Y552000D01*
G01Y550000D02*
X626900D01*
G01X629500Y552500D02*
X629167Y552417D01*
X628917Y552208D01*
X628750Y551958D01*
X628625Y551625D01*
X628583Y551250D01*
X628625Y550875D01*
X628750Y550542D01*
X628917Y550292D01*
X629167Y550083D01*
X629500Y550000D01*
X629833Y550083D01*
X630083Y550292D01*
X630250Y550542D01*
X630375Y550875D01*
X630417Y551250D01*
X630375Y551625D01*
X630250Y551958D01*
X630083Y552208D01*
X629833Y552417D01*
X629500Y552500D01*
G01X631683Y550500D02*
X631933Y550208D01*
X632267Y550042D01*
X632642Y550000D01*
X632975Y550042D01*
X633308Y550250D01*
X633517Y550500D01*
X633558Y550750D01*
X633475Y551042D01*
X633183Y551250D01*
X632892Y551333D01*
X632517D01*
G01X632892D02*
X633142Y551458D01*
X633350Y551667D01*
X633433Y551917D01*
X633350Y552167D01*
X633142Y552375D01*
X632767Y552500D01*
X632392Y552458D01*
X632017Y552292D01*
G01X634992Y550292D02*
X635283Y550083D01*
X635617Y550000D01*
X635950Y550083D01*
X636242Y550333D01*
X636450Y550708D01*
X636533Y551083D01*
Y551542D01*
X636450Y551917D01*
X636242Y552250D01*
X635992Y552417D01*
X635700Y552500D01*
X635367Y552417D01*
X635117Y552250D01*
X634950Y552000D01*
X634867Y551667D01*
X634950Y551375D01*
X635158Y551083D01*
X635408Y550917D01*
X635700Y550875D01*
X636033Y550958D01*
X636283Y551167D01*
X636533Y551542D01*
G01X639208Y550267D02*
X639083Y550017D01*
X639000Y549725D01*
Y549392D01*
X639125Y549017D01*
X639333Y548725D01*
X639583Y548517D01*
X640000Y548350D01*
X640375Y548308D01*
X640750Y548392D01*
X641000Y548517D01*
X641250Y548767D01*
X641417Y549058D01*
X641500Y549350D01*
Y549642D01*
X641417Y549933D01*
X641292Y550183D01*
X641125Y550392D01*
G01Y551533D02*
X641333Y551783D01*
X641458Y552075D01*
X641500Y552450D01*
X641417Y552825D01*
X641250Y553117D01*
X640958Y553325D01*
X640625Y553367D01*
X640292Y553283D01*
X640083Y553075D01*
X639917Y552783D01*
X639875Y552492D01*
X639917Y552200D01*
X640083Y551825D01*
X639000Y551950D01*
Y553075D01*
G01X641125Y554633D02*
X641333Y554883D01*
X641458Y555175D01*
X641500Y555550D01*
X641417Y555925D01*
X641250Y556217D01*
X640958Y556425D01*
X640625Y556467D01*
X640292Y556383D01*
X640083Y556175D01*
X639917Y555883D01*
X639875Y555592D01*
X639917Y555300D01*
X640083Y554925D01*
X639000Y555050D01*
Y556175D01*
G01X641000Y557733D02*
X641292Y557983D01*
X641458Y558317D01*
X641500Y558692D01*
X641458Y559025D01*
X641250Y559358D01*
X641000Y559567D01*
X640750Y559608D01*
X640458Y559525D01*
X640250Y559233D01*
X640167Y558942D01*
Y558567D01*
G01Y558942D02*
X640042Y559192D01*
X639833Y559400D01*
X639583Y559483D01*
X639333Y559400D01*
X639125Y559192D01*
X639000Y558817D01*
X639042Y558442D01*
X639208Y558067D01*
G01X624546Y548123D02*
X624296Y548248D01*
X624004Y548331D01*
X623671D01*
X623296Y548206D01*
X623004Y547998D01*
X622796Y547748D01*
X622629Y547331D01*
X622587Y546956D01*
X622671Y546581D01*
X622796Y546331D01*
X623046Y546081D01*
X623337Y545914D01*
X623629Y545831D01*
X623921D01*
X624212Y545914D01*
X624462Y546039D01*
X624671Y546206D01*
G01X625812D02*
X626062Y545998D01*
X626354Y545873D01*
X626729Y545831D01*
X627104Y545914D01*
X627396Y546081D01*
X627604Y546373D01*
X627646Y546706D01*
X627562Y547039D01*
X627354Y547248D01*
X627062Y547414D01*
X626771Y547456D01*
X626479Y547414D01*
X626104Y547248D01*
X626229Y548331D01*
X627354D01*
G01X630329Y545831D02*
Y548331D01*
X628787Y546539D01*
X630871D01*
G01X632012Y546331D02*
X632262Y546039D01*
X632596Y545873D01*
X632971Y545831D01*
X633304Y545873D01*
X633637Y546081D01*
X633846Y546331D01*
X633887Y546581D01*
X633804Y546873D01*
X633512Y547081D01*
X633221Y547164D01*
X632846D01*
G01X633221D02*
X633471Y547289D01*
X633679Y547498D01*
X633762Y547748D01*
X633679Y547998D01*
X633471Y548206D01*
X633096Y548331D01*
X632721Y548289D01*
X632346Y548123D01*
G01X629708Y534767D02*
X629583Y534517D01*
X629500Y534225D01*
Y533892D01*
X629625Y533517D01*
X629833Y533225D01*
X630083Y533017D01*
X630500Y532850D01*
X630875Y532808D01*
X631250Y532892D01*
X631500Y533017D01*
X631750Y533267D01*
X631917Y533558D01*
X632000Y533850D01*
Y534142D01*
X631917Y534433D01*
X631792Y534683D01*
X631625Y534892D01*
G01Y536033D02*
X631833Y536283D01*
X631958Y536575D01*
X632000Y536950D01*
X631917Y537325D01*
X631750Y537617D01*
X631458Y537825D01*
X631125Y537867D01*
X630792Y537783D01*
X630583Y537575D01*
X630417Y537283D01*
X630375Y536992D01*
X630417Y536700D01*
X630583Y536325D01*
X629500Y536450D01*
Y537575D01*
G01X630958Y539258D02*
X630667Y539550D01*
X630500Y539800D01*
X630417Y540133D01*
X630500Y540425D01*
X630667Y540633D01*
X630917Y540800D01*
X631208Y540842D01*
X631458Y540800D01*
X631708Y540633D01*
X631917Y540383D01*
X632000Y540092D01*
X631917Y539758D01*
X631667Y539467D01*
X631292Y539300D01*
X630875Y539258D01*
X630333Y539342D01*
X630042Y539467D01*
X629750Y539675D01*
X629542Y539967D01*
X629500Y540258D01*
X629583Y540550D01*
X629792Y540758D01*
G01X631708Y542442D02*
X631917Y542733D01*
X632000Y543067D01*
X631917Y543400D01*
X631667Y543692D01*
X631292Y543900D01*
X630917Y543983D01*
X630458D01*
X630083Y543900D01*
X629750Y543692D01*
X629583Y543442D01*
X629500Y543150D01*
X629583Y542817D01*
X629750Y542567D01*
X630000Y542400D01*
X630333Y542317D01*
X630625Y542400D01*
X630917Y542608D01*
X631083Y542858D01*
X631125Y543150D01*
X631042Y543483D01*
X630833Y543733D01*
X630458Y543983D01*
G01X607767Y531792D02*
X607517Y531917D01*
X607225Y532000D01*
X606892D01*
X606517Y531875D01*
X606225Y531667D01*
X606017Y531417D01*
X605850Y531000D01*
X605808Y530625D01*
X605892Y530250D01*
X606017Y530000D01*
X606267Y529750D01*
X606558Y529583D01*
X606850Y529500D01*
X607142D01*
X607433Y529583D01*
X607683Y529708D01*
X607892Y529875D01*
G01X609033D02*
X609283Y529667D01*
X609575Y529542D01*
X609950Y529500D01*
X610325Y529583D01*
X610617Y529750D01*
X610825Y530042D01*
X610867Y530375D01*
X610783Y530708D01*
X610575Y530917D01*
X610283Y531083D01*
X609992Y531125D01*
X609700Y531083D01*
X609325Y530917D01*
X609450Y532000D01*
X610575D01*
G01X613550Y529500D02*
Y532000D01*
X612008Y530208D01*
X614092D01*
G01X616150Y529500D02*
Y532000D01*
X615650Y531500D01*
G01Y529500D02*
X616650D01*
G01X626467Y566000D02*
Y568500D01*
X627508D01*
X627842Y568375D01*
X628050Y568208D01*
X628133Y567875D01*
X628050Y567542D01*
X627800Y567333D01*
X627508Y567208D01*
X626467D01*
G01X627508D02*
X628133Y566000D01*
G01X630400D02*
Y568500D01*
X629900Y568000D01*
G01Y566000D02*
X630900D01*
G01X633500Y568500D02*
X633167Y568417D01*
X632917Y568208D01*
X632750Y567958D01*
X632625Y567625D01*
X632583Y567250D01*
X632625Y566875D01*
X632750Y566542D01*
X632917Y566292D01*
X633167Y566083D01*
X633500Y566000D01*
X633833Y566083D01*
X634083Y566292D01*
X634250Y566542D01*
X634375Y566875D01*
X634417Y567250D01*
X634375Y567625D01*
X634250Y567958D01*
X634083Y568208D01*
X633833Y568417D01*
X633500Y568500D01*
G01X635808Y567042D02*
X636100Y567333D01*
X636350Y567500D01*
X636683Y567583D01*
X636975Y567500D01*
X637183Y567333D01*
X637350Y567083D01*
X637392Y566792D01*
X637350Y566542D01*
X637183Y566292D01*
X636933Y566083D01*
X636642Y566000D01*
X636308Y566083D01*
X636017Y566333D01*
X635850Y566708D01*
X635808Y567125D01*
X635892Y567667D01*
X636017Y567958D01*
X636225Y568250D01*
X636517Y568458D01*
X636808Y568500D01*
X637100Y568417D01*
X637308Y568208D01*
G01X638783Y566500D02*
X639033Y566208D01*
X639367Y566042D01*
X639742Y566000D01*
X640075Y566042D01*
X640408Y566250D01*
X640617Y566500D01*
X640658Y566750D01*
X640575Y567042D01*
X640283Y567250D01*
X639992Y567333D01*
X639617D01*
G01X639992D02*
X640242Y567458D01*
X640450Y567667D01*
X640533Y567917D01*
X640450Y568167D01*
X640242Y568375D01*
X639867Y568500D01*
X639492Y568458D01*
X639117Y568292D01*
G01X621510Y560574D02*
Y564574D01*
X614110D01*
G01X621510Y553174D02*
Y557174D01*
X614110D01*
G01X624410Y566241D02*
X621910D01*
Y567282D01*
X622035Y567616D01*
X622202Y567824D01*
X622535Y567907D01*
X622868Y567824D01*
X623077Y567574D01*
X623202Y567282D01*
Y566241D01*
G01Y567282D02*
X624410Y567907D01*
G01Y570174D02*
X621910D01*
X622410Y569674D01*
G01X624410D02*
Y570674D01*
G01X621910Y573274D02*
X621993Y572941D01*
X622202Y572691D01*
X622452Y572524D01*
X622785Y572399D01*
X623160Y572357D01*
X623535Y572399D01*
X623868Y572524D01*
X624118Y572691D01*
X624327Y572941D01*
X624410Y573274D01*
X624327Y573607D01*
X624118Y573857D01*
X623868Y574024D01*
X623535Y574149D01*
X623160Y574191D01*
X622785Y574149D01*
X622452Y574024D01*
X622202Y573857D01*
X621993Y573607D01*
X621910Y573274D01*
G01X623368Y575582D02*
X623077Y575874D01*
X622910Y576124D01*
X622827Y576457D01*
X622910Y576749D01*
X623077Y576957D01*
X623327Y577124D01*
X623618Y577166D01*
X623868Y577124D01*
X624118Y576957D01*
X624327Y576707D01*
X624410Y576416D01*
X624327Y576082D01*
X624077Y575791D01*
X623702Y575624D01*
X623285Y575582D01*
X622743Y575666D01*
X622452Y575791D01*
X622160Y575999D01*
X621952Y576291D01*
X621910Y576582D01*
X621993Y576874D01*
X622202Y577082D01*
G01X624035Y578557D02*
X624243Y578807D01*
X624368Y579099D01*
X624410Y579474D01*
X624327Y579849D01*
X624160Y580141D01*
X623868Y580349D01*
X623535Y580391D01*
X623202Y580307D01*
X622993Y580099D01*
X622827Y579807D01*
X622785Y579516D01*
X622827Y579224D01*
X622993Y578849D01*
X621910Y578974D01*
Y580099D01*
G01X609910Y560574D02*
X613910D01*
Y567974D01*
G01X633500Y576467D02*
X631000D01*
Y577508D01*
X631125Y577842D01*
X631292Y578050D01*
X631625Y578133D01*
X631958Y578050D01*
X632167Y577800D01*
X632292Y577508D01*
Y576467D01*
G01Y577508D02*
X633500Y578133D01*
G01Y580400D02*
X631000D01*
X631500Y579900D01*
G01X633500D02*
Y580900D01*
G01X631000Y583500D02*
X631083Y583167D01*
X631292Y582917D01*
X631542Y582750D01*
X631875Y582625D01*
X632250Y582583D01*
X632625Y582625D01*
X632958Y582750D01*
X633208Y582917D01*
X633417Y583167D01*
X633500Y583500D01*
X633417Y583833D01*
X633208Y584083D01*
X632958Y584250D01*
X632625Y584375D01*
X632250Y584417D01*
X631875Y584375D01*
X631542Y584250D01*
X631292Y584083D01*
X631083Y583833D01*
X631000Y583500D01*
G01X632458Y585808D02*
X632167Y586100D01*
X632000Y586350D01*
X631917Y586683D01*
X632000Y586975D01*
X632167Y587183D01*
X632417Y587350D01*
X632708Y587392D01*
X632958Y587350D01*
X633208Y587183D01*
X633417Y586933D01*
X633500Y586642D01*
X633417Y586308D01*
X633167Y586017D01*
X632792Y585850D01*
X632375Y585808D01*
X631833Y585892D01*
X631542Y586017D01*
X631250Y586225D01*
X631042Y586517D01*
X631000Y586808D01*
X631083Y587100D01*
X631292Y587308D01*
G01X633500Y589700D02*
X633458Y589992D01*
X633333Y590325D01*
X633125Y590533D01*
X632833Y590617D01*
X632542Y590533D01*
X632292Y590283D01*
X632167Y589908D01*
Y589492D01*
X632083Y589242D01*
X631875Y589033D01*
X631583Y588950D01*
X631292Y589075D01*
X631083Y589367D01*
X631000Y589700D01*
X631083Y590033D01*
X631292Y590325D01*
X631583Y590450D01*
X631875Y590367D01*
X632083Y590158D01*
X632167Y589908D01*
Y589492D01*
X632292Y589117D01*
X632542Y588867D01*
X632833Y588783D01*
X633125Y588867D01*
X633333Y589075D01*
X633458Y589408D01*
X633500Y589700D01*
G01X635213Y583955D02*
X639213D01*
Y591355D01*
G01X645565Y580967D02*
X650765D01*
G01X645565Y573967D02*
X653365D01*
G01X645565Y580967D02*
Y573967D01*
G01X658965Y580967D02*
X650265D01*
G01X652565Y573967D02*
X658965D01*
G01X644392Y607086D02*
X674392D01*
Y584286D01*
X644392D01*
Y607086D01*
G01X617668Y569041D02*
X617543Y568791D01*
X617460Y568499D01*
Y568166D01*
X617585Y567791D01*
X617793Y567499D01*
X618043Y567291D01*
X618460Y567124D01*
X618835Y567082D01*
X619210Y567166D01*
X619460Y567291D01*
X619710Y567541D01*
X619877Y567832D01*
X619960Y568124D01*
Y568416D01*
X619877Y568707D01*
X619752Y568957D01*
X619585Y569166D01*
G01Y570307D02*
X619793Y570557D01*
X619918Y570849D01*
X619960Y571224D01*
X619877Y571599D01*
X619710Y571891D01*
X619418Y572099D01*
X619085Y572141D01*
X618752Y572057D01*
X618543Y571849D01*
X618377Y571557D01*
X618335Y571266D01*
X618377Y570974D01*
X618543Y570599D01*
X617460Y570724D01*
Y571849D01*
G01X619585Y573407D02*
X619793Y573657D01*
X619918Y573949D01*
X619960Y574324D01*
X619877Y574699D01*
X619710Y574991D01*
X619418Y575199D01*
X619085Y575241D01*
X618752Y575157D01*
X618543Y574949D01*
X618377Y574657D01*
X618335Y574366D01*
X618377Y574074D01*
X618543Y573699D01*
X617460Y573824D01*
Y574949D01*
G01X617877Y576632D02*
X617627Y576882D01*
X617502Y577174D01*
X617460Y577507D01*
X617543Y577924D01*
X617752Y578216D01*
X618002Y578299D01*
X618252Y578257D01*
X618460Y578091D01*
X618877Y577257D01*
X619168Y576882D01*
X619585Y576632D01*
X619960Y576549D01*
Y578299D01*
G01X644350Y610000D02*
X644017Y610042D01*
X643725Y610208D01*
X643475Y610458D01*
X643308Y610750D01*
X643225Y611083D01*
Y611417D01*
X643308Y611750D01*
X643475Y612042D01*
X643725Y612292D01*
X644017Y612458D01*
X644350Y612500D01*
X644683Y612458D01*
X644975Y612292D01*
X645225Y612042D01*
X645392Y611750D01*
X645475Y611417D01*
Y611083D01*
X645392Y610750D01*
X645225Y610458D01*
X644975Y610208D01*
X644683Y610042D01*
X644350Y610000D01*
G01X644683Y610667D02*
X645183Y610000D01*
G01X646658Y612083D02*
X646908Y612333D01*
X647200Y612458D01*
X647533Y612500D01*
X647950Y612417D01*
X648242Y612208D01*
X648325Y611958D01*
X648283Y611708D01*
X648117Y611500D01*
X647283Y611083D01*
X646908Y610792D01*
X646658Y610375D01*
X646575Y610000D01*
X648325D01*
G01X649758Y612083D02*
X650008Y612333D01*
X650300Y612458D01*
X650633Y612500D01*
X651050Y612417D01*
X651342Y612208D01*
X651425Y611958D01*
X651383Y611708D01*
X651217Y611500D01*
X650383Y611083D01*
X650008Y610792D01*
X649758Y610375D01*
X649675Y610000D01*
X651425D01*
G01X653650Y612500D02*
X653317Y612417D01*
X653067Y612208D01*
X652900Y611958D01*
X652775Y611625D01*
X652733Y611250D01*
X652775Y610875D01*
X652900Y610542D01*
X653067Y610292D01*
X653317Y610083D01*
X653650Y610000D01*
X653983Y610083D01*
X654233Y610292D01*
X654400Y610542D01*
X654525Y610875D01*
X654567Y611250D01*
X654525Y611625D01*
X654400Y611958D01*
X654233Y612208D01*
X653983Y612417D01*
X653650Y612500D01*
G01X624626Y610440D02*
X624376Y610565D01*
X624084Y610648D01*
X623751D01*
X623376Y610523D01*
X623084Y610315D01*
X622876Y610065D01*
X622709Y609648D01*
X622667Y609273D01*
X622751Y608898D01*
X622876Y608648D01*
X623126Y608398D01*
X623417Y608231D01*
X623709Y608148D01*
X624001D01*
X624292Y608231D01*
X624542Y608356D01*
X624751Y608523D01*
G01X626017Y610231D02*
X626267Y610481D01*
X626559Y610606D01*
X626892Y610648D01*
X627309Y610565D01*
X627601Y610356D01*
X627684Y610106D01*
X627642Y609856D01*
X627476Y609648D01*
X626642Y609231D01*
X626267Y608940D01*
X626017Y608523D01*
X625934Y608148D01*
X627684D01*
G01X630409D02*
Y610648D01*
X628867Y608856D01*
X630951D01*
G01X632926Y608148D02*
X633009Y608690D01*
X633134Y609148D01*
X633301Y609565D01*
X633509Y610023D01*
X633842Y610648D01*
X632176D01*
G01X624467Y614292D02*
X624217Y614417D01*
X623925Y614500D01*
X623592D01*
X623217Y614375D01*
X622925Y614167D01*
X622717Y613917D01*
X622550Y613500D01*
X622508Y613125D01*
X622592Y612750D01*
X622717Y612500D01*
X622967Y612250D01*
X623258Y612083D01*
X623550Y612000D01*
X623842D01*
X624133Y612083D01*
X624383Y612208D01*
X624592Y612375D01*
G01X625858Y614083D02*
X626108Y614333D01*
X626400Y614458D01*
X626733Y614500D01*
X627150Y614417D01*
X627442Y614208D01*
X627525Y613958D01*
X627483Y613708D01*
X627317Y613500D01*
X626483Y613083D01*
X626108Y612792D01*
X625858Y612375D01*
X625775Y612000D01*
X627525D01*
G01X630250D02*
Y614500D01*
X628708Y612708D01*
X630792D01*
G01X632058Y613042D02*
X632350Y613333D01*
X632600Y613500D01*
X632933Y613583D01*
X633225Y613500D01*
X633433Y613333D01*
X633600Y613083D01*
X633642Y612792D01*
X633600Y612542D01*
X633433Y612292D01*
X633183Y612083D01*
X632892Y612000D01*
X632558Y612083D01*
X632267Y612333D01*
X632100Y612708D01*
X632058Y613125D01*
X632142Y613667D01*
X632267Y613958D01*
X632475Y614250D01*
X632767Y614458D01*
X633058Y614500D01*
X633350Y614417D01*
X633558Y614208D01*
G01X625902Y687954D02*
Y690454D01*
X626943D01*
X627277Y690329D01*
X627485Y690162D01*
X627568Y689829D01*
X627485Y689496D01*
X627235Y689287D01*
X626943Y689162D01*
X625902D01*
G01X626943D02*
X627568Y687954D01*
G01X630335D02*
Y690454D01*
X628793Y688662D01*
X630877D01*
G01X632227Y688246D02*
X632518Y688037D01*
X632852Y687954D01*
X633185Y688037D01*
X633477Y688287D01*
X633685Y688662D01*
X633768Y689037D01*
Y689496D01*
X633685Y689871D01*
X633477Y690204D01*
X633227Y690371D01*
X632935Y690454D01*
X632602Y690371D01*
X632352Y690204D01*
X632185Y689954D01*
X632102Y689621D01*
X632185Y689329D01*
X632393Y689037D01*
X632643Y688871D01*
X632935Y688829D01*
X633268Y688912D01*
X633518Y689121D01*
X633768Y689496D01*
G01X636035Y687954D02*
X636327Y687996D01*
X636660Y688121D01*
X636868Y688329D01*
X636952Y688621D01*
X636868Y688912D01*
X636618Y689162D01*
X636243Y689287D01*
X635827D01*
X635577Y689371D01*
X635368Y689579D01*
X635285Y689871D01*
X635410Y690162D01*
X635702Y690371D01*
X636035Y690454D01*
X636368Y690371D01*
X636660Y690162D01*
X636785Y689871D01*
X636702Y689579D01*
X636493Y689371D01*
X636243Y689287D01*
X635827D01*
X635452Y689162D01*
X635202Y688912D01*
X635118Y688621D01*
X635202Y688329D01*
X635410Y688121D01*
X635743Y687996D01*
X636035Y687954D01*
G01X641487Y695517D02*
Y699517D01*
X634087D01*
G01X627652Y686146D02*
X627402Y686271D01*
X627110Y686354D01*
X626777D01*
X626402Y686229D01*
X626110Y686021D01*
X625902Y685771D01*
X625735Y685354D01*
X625693Y684979D01*
X625777Y684604D01*
X625902Y684354D01*
X626152Y684104D01*
X626443Y683937D01*
X626735Y683854D01*
X627027D01*
X627318Y683937D01*
X627568Y684062D01*
X627777Y684229D01*
G01X629043Y685937D02*
X629293Y686187D01*
X629585Y686312D01*
X629918Y686354D01*
X630335Y686271D01*
X630627Y686062D01*
X630710Y685812D01*
X630668Y685562D01*
X630502Y685354D01*
X629668Y684937D01*
X629293Y684646D01*
X629043Y684229D01*
X628960Y683854D01*
X630710D01*
G01X632018Y684229D02*
X632268Y684021D01*
X632560Y683896D01*
X632935Y683854D01*
X633310Y683937D01*
X633602Y684104D01*
X633810Y684396D01*
X633852Y684729D01*
X633768Y685062D01*
X633560Y685271D01*
X633268Y685437D01*
X632977Y685479D01*
X632685Y685437D01*
X632310Y685271D01*
X632435Y686354D01*
X633560D01*
G01X635118Y684354D02*
X635368Y684062D01*
X635702Y683896D01*
X636077Y683854D01*
X636410Y683896D01*
X636743Y684104D01*
X636952Y684354D01*
X636993Y684604D01*
X636910Y684896D01*
X636618Y685104D01*
X636327Y685187D01*
X635952D01*
G01X636327D02*
X636577Y685312D01*
X636785Y685521D01*
X636868Y685771D01*
X636785Y686021D01*
X636577Y686229D01*
X636202Y686354D01*
X635827Y686312D01*
X635452Y686146D01*
G01X633700Y732017D02*
X631200D01*
Y733058D01*
X631325Y733392D01*
X631492Y733600D01*
X631825Y733683D01*
X632158Y733600D01*
X632367Y733350D01*
X632492Y733058D01*
Y732017D01*
G01Y733058D02*
X633700Y733683D01*
G01Y736450D02*
X631200D01*
X632992Y734908D01*
Y736992D01*
G01X633700Y738967D02*
X633158Y739050D01*
X632700Y739175D01*
X632283Y739342D01*
X631825Y739550D01*
X631200Y739883D01*
Y738217D01*
G01X633200Y741233D02*
X633492Y741483D01*
X633658Y741817D01*
X633700Y742192D01*
X633658Y742525D01*
X633450Y742858D01*
X633200Y743067D01*
X632950Y743108D01*
X632658Y743025D01*
X632450Y742733D01*
X632367Y742442D01*
Y742067D01*
G01Y742442D02*
X632242Y742692D01*
X632033Y742900D01*
X631783Y742983D01*
X631533Y742900D01*
X631325Y742692D01*
X631200Y742317D01*
X631242Y741942D01*
X631408Y741567D01*
G01X639326Y741766D02*
X635326D01*
Y734366D01*
G01X628117Y713100D02*
Y715600D01*
X629158D01*
X629492Y715475D01*
X629700Y715308D01*
X629783Y714975D01*
X629700Y714642D01*
X629450Y714433D01*
X629158Y714308D01*
X628117D01*
G01X629158D02*
X629783Y713100D01*
G01X632550D02*
Y715600D01*
X631008Y713808D01*
X633092D01*
G01X635067Y713100D02*
X635150Y713642D01*
X635275Y714100D01*
X635442Y714517D01*
X635650Y714975D01*
X635983Y715600D01*
X634317D01*
G01X637458Y715183D02*
X637708Y715433D01*
X638000Y715558D01*
X638333Y715600D01*
X638750Y715517D01*
X639042Y715308D01*
X639125Y715058D01*
X639083Y714808D01*
X638917Y714600D01*
X638083Y714183D01*
X637708Y713892D01*
X637458Y713475D01*
X637375Y713100D01*
X639125D01*
G01X645257Y716197D02*
Y712197D01*
X652657D01*
G01X640280Y735683D02*
Y721683D01*
G01X653280Y735683D02*
X640280D01*
G01Y721683D02*
X653280D01*
G01X640284Y750603D02*
Y736603D01*
G01D02*
X653284D01*
G01X629500Y717850D02*
X632000D01*
G01X629500Y716892D02*
Y718808D01*
G01X632000Y720117D02*
X629500D01*
Y721117D01*
X629625Y721450D01*
X629917Y721700D01*
X630250Y721783D01*
X630583Y721700D01*
X630833Y721492D01*
X630958Y721117D01*
Y720117D01*
G01X632000Y724050D02*
X631958Y724342D01*
X631833Y724675D01*
X631625Y724883D01*
X631333Y724967D01*
X631042Y724883D01*
X630792Y724633D01*
X630667Y724258D01*
Y723842D01*
X630583Y723592D01*
X630375Y723383D01*
X630083Y723300D01*
X629792Y723425D01*
X629583Y723717D01*
X629500Y724050D01*
X629583Y724383D01*
X629792Y724675D01*
X630083Y724800D01*
X630375Y724717D01*
X630583Y724508D01*
X630667Y724258D01*
Y723842D01*
X630792Y723467D01*
X631042Y723217D01*
X631333Y723133D01*
X631625Y723217D01*
X631833Y723425D01*
X631958Y723758D01*
X632000Y724050D01*
G01X629917Y726358D02*
X629667Y726608D01*
X629542Y726900D01*
X629500Y727233D01*
X629583Y727650D01*
X629792Y727942D01*
X630042Y728025D01*
X630292Y727983D01*
X630500Y727817D01*
X630917Y726983D01*
X631208Y726608D01*
X631625Y726358D01*
X632000Y726275D01*
Y728025D01*
G01X641217Y702300D02*
Y704800D01*
X642258D01*
X642592Y704675D01*
X642800Y704508D01*
X642883Y704175D01*
X642800Y703842D01*
X642550Y703633D01*
X642258Y703508D01*
X641217D01*
G01X642258D02*
X642883Y702300D01*
G01X644233Y702675D02*
X644483Y702467D01*
X644775Y702342D01*
X645150Y702300D01*
X645525Y702383D01*
X645817Y702550D01*
X646025Y702842D01*
X646067Y703175D01*
X645983Y703508D01*
X645775Y703717D01*
X645483Y703883D01*
X645192Y703925D01*
X644900Y703883D01*
X644525Y703717D01*
X644650Y704800D01*
X645775D01*
G01X648250D02*
X647917Y704717D01*
X647667Y704508D01*
X647500Y704258D01*
X647375Y703925D01*
X647333Y703550D01*
X647375Y703175D01*
X647500Y702842D01*
X647667Y702592D01*
X647917Y702383D01*
X648250Y702300D01*
X648583Y702383D01*
X648833Y702592D01*
X649000Y702842D01*
X649125Y703175D01*
X649167Y703550D01*
X649125Y703925D01*
X649000Y704258D01*
X648833Y704508D01*
X648583Y704717D01*
X648250Y704800D01*
G01X650558Y704383D02*
X650808Y704633D01*
X651100Y704758D01*
X651433Y704800D01*
X651850Y704717D01*
X652142Y704508D01*
X652225Y704258D01*
X652183Y704008D01*
X652017Y703800D01*
X651183Y703383D01*
X650808Y703092D01*
X650558Y702675D01*
X650475Y702300D01*
X652225D01*
G01X653284Y750603D02*
X640284D01*
G01X628610Y1069423D02*
X628360Y1069548D01*
X628068Y1069631D01*
X627735D01*
X627360Y1069506D01*
X627068Y1069298D01*
X626860Y1069048D01*
X626693Y1068631D01*
X626651Y1068256D01*
X626735Y1067881D01*
X626860Y1067631D01*
X627110Y1067381D01*
X627401Y1067214D01*
X627693Y1067131D01*
X627985D01*
X628276Y1067214D01*
X628526Y1067339D01*
X628735Y1067506D01*
G01X630085Y1067423D02*
X630376Y1067214D01*
X630710Y1067131D01*
X631043Y1067214D01*
X631335Y1067464D01*
X631543Y1067839D01*
X631626Y1068214D01*
Y1068673D01*
X631543Y1069048D01*
X631335Y1069381D01*
X631085Y1069548D01*
X630793Y1069631D01*
X630460Y1069548D01*
X630210Y1069381D01*
X630043Y1069131D01*
X629960Y1068798D01*
X630043Y1068506D01*
X630251Y1068214D01*
X630501Y1068048D01*
X630793Y1068006D01*
X631126Y1068089D01*
X631376Y1068298D01*
X631626Y1068673D01*
G01X633893Y1067131D02*
Y1069631D01*
X633393Y1069131D01*
G01Y1067131D02*
X634393D01*
G01X628451Y1073519D02*
X628201Y1073644D01*
X627909Y1073727D01*
X627576D01*
X627201Y1073602D01*
X626909Y1073394D01*
X626701Y1073144D01*
X626534Y1072727D01*
X626492Y1072352D01*
X626576Y1071977D01*
X626701Y1071727D01*
X626951Y1071477D01*
X627242Y1071310D01*
X627534Y1071227D01*
X627826D01*
X628117Y1071310D01*
X628367Y1071435D01*
X628576Y1071602D01*
G01X629926Y1071519D02*
X630217Y1071310D01*
X630551Y1071227D01*
X630884Y1071310D01*
X631176Y1071560D01*
X631384Y1071935D01*
X631467Y1072310D01*
Y1072769D01*
X631384Y1073144D01*
X631176Y1073477D01*
X630926Y1073644D01*
X630634Y1073727D01*
X630301Y1073644D01*
X630051Y1073477D01*
X629884Y1073227D01*
X629801Y1072894D01*
X629884Y1072602D01*
X630092Y1072310D01*
X630342Y1072144D01*
X630634Y1072102D01*
X630967Y1072185D01*
X631217Y1072394D01*
X631467Y1072769D01*
G01X633734Y1073727D02*
X633401Y1073644D01*
X633151Y1073435D01*
X632984Y1073185D01*
X632859Y1072852D01*
X632817Y1072477D01*
X632859Y1072102D01*
X632984Y1071769D01*
X633151Y1071519D01*
X633401Y1071310D01*
X633734Y1071227D01*
X634067Y1071310D01*
X634317Y1071519D01*
X634484Y1071769D01*
X634609Y1072102D01*
X634651Y1072477D01*
X634609Y1072852D01*
X634484Y1073185D01*
X634317Y1073435D01*
X634067Y1073644D01*
X633734Y1073727D01*
G01X622046Y1149257D02*
Y1151757D01*
X623087D01*
X623421Y1151632D01*
X623629Y1151465D01*
X623712Y1151132D01*
X623629Y1150799D01*
X623379Y1150590D01*
X623087Y1150465D01*
X622046D01*
G01X623087D02*
X623712Y1149257D01*
G01X625187Y1151340D02*
X625437Y1151590D01*
X625729Y1151715D01*
X626062Y1151757D01*
X626479Y1151674D01*
X626771Y1151465D01*
X626854Y1151215D01*
X626812Y1150965D01*
X626646Y1150757D01*
X625812Y1150340D01*
X625437Y1150049D01*
X625187Y1149632D01*
X625104Y1149257D01*
X626854D01*
G01X628287Y1151340D02*
X628537Y1151590D01*
X628829Y1151715D01*
X629162Y1151757D01*
X629579Y1151674D01*
X629871Y1151465D01*
X629954Y1151215D01*
X629912Y1150965D01*
X629746Y1150757D01*
X628912Y1150340D01*
X628537Y1150049D01*
X628287Y1149632D01*
X628204Y1149257D01*
X629954D01*
G01X632679D02*
Y1151757D01*
X631137Y1149965D01*
X633221D01*
G01X641487Y1148273D02*
Y1152273D01*
X634087D01*
G01X645317Y1155600D02*
Y1158100D01*
X646358D01*
X646692Y1157975D01*
X646900Y1157808D01*
X646983Y1157475D01*
X646900Y1157142D01*
X646650Y1156933D01*
X646358Y1156808D01*
X645317D01*
G01X646358D02*
X646983Y1155600D01*
G01X648333Y1155975D02*
X648583Y1155767D01*
X648875Y1155642D01*
X649250Y1155600D01*
X649625Y1155683D01*
X649917Y1155850D01*
X650125Y1156142D01*
X650167Y1156475D01*
X650083Y1156808D01*
X649875Y1157017D01*
X649583Y1157183D01*
X649292Y1157225D01*
X649000Y1157183D01*
X648625Y1157017D01*
X648750Y1158100D01*
X649875D01*
G01X652267Y1155600D02*
X652350Y1156142D01*
X652475Y1156600D01*
X652642Y1157017D01*
X652850Y1157475D01*
X653183Y1158100D01*
X651517D01*
G01X654533Y1156100D02*
X654783Y1155808D01*
X655117Y1155642D01*
X655492Y1155600D01*
X655825Y1155642D01*
X656158Y1155850D01*
X656367Y1156100D01*
X656408Y1156350D01*
X656325Y1156642D01*
X656033Y1156850D01*
X655742Y1156933D01*
X655367D01*
G01X655742D02*
X655992Y1157058D01*
X656200Y1157267D01*
X656283Y1157517D01*
X656200Y1157767D01*
X655992Y1157975D01*
X655617Y1158100D01*
X655242Y1158058D01*
X654867Y1157892D01*
G01X645766Y1162810D02*
Y1158810D01*
X653166D01*
G01X640364Y1183159D02*
Y1169159D01*
G01D02*
X653364D01*
G01X630500Y1171850D02*
X633000D01*
G01X630500Y1170892D02*
Y1172808D01*
G01X633000Y1174117D02*
X630500D01*
Y1175117D01*
X630625Y1175450D01*
X630917Y1175700D01*
X631250Y1175783D01*
X631583Y1175700D01*
X631833Y1175492D01*
X631958Y1175117D01*
Y1174117D01*
G01X630917Y1177258D02*
X630667Y1177508D01*
X630542Y1177800D01*
X630500Y1178133D01*
X630583Y1178550D01*
X630792Y1178842D01*
X631042Y1178925D01*
X631292Y1178883D01*
X631500Y1178717D01*
X631917Y1177883D01*
X632208Y1177508D01*
X632625Y1177258D01*
X633000Y1177175D01*
Y1178925D01*
G01X630917Y1180358D02*
X630667Y1180608D01*
X630542Y1180900D01*
X630500Y1181233D01*
X630583Y1181650D01*
X630792Y1181942D01*
X631042Y1182025D01*
X631292Y1181983D01*
X631500Y1181817D01*
X631917Y1180983D01*
X632208Y1180608D01*
X632625Y1180358D01*
X633000Y1180275D01*
Y1182025D01*
G01X622417Y1160467D02*
Y1162967D01*
X623458D01*
X623792Y1162842D01*
X624000Y1162675D01*
X624083Y1162342D01*
X624000Y1162009D01*
X623750Y1161800D01*
X623458Y1161675D01*
X622417D01*
G01X623458D02*
X624083Y1160467D01*
G01X625558Y1162550D02*
X625808Y1162800D01*
X626100Y1162925D01*
X626433Y1162967D01*
X626850Y1162884D01*
X627142Y1162675D01*
X627225Y1162425D01*
X627183Y1162175D01*
X627017Y1161967D01*
X626183Y1161550D01*
X625808Y1161259D01*
X625558Y1160842D01*
X625475Y1160467D01*
X627225D01*
G01X628658Y1162550D02*
X628908Y1162800D01*
X629200Y1162925D01*
X629533Y1162967D01*
X629950Y1162884D01*
X630242Y1162675D01*
X630325Y1162425D01*
X630283Y1162175D01*
X630117Y1161967D01*
X629283Y1161550D01*
X628908Y1161259D01*
X628658Y1160842D01*
X628575Y1160467D01*
X630325D01*
G01X631758Y1161509D02*
X632050Y1161800D01*
X632300Y1161967D01*
X632633Y1162050D01*
X632925Y1161967D01*
X633133Y1161800D01*
X633300Y1161550D01*
X633342Y1161259D01*
X633300Y1161009D01*
X633133Y1160759D01*
X632883Y1160550D01*
X632592Y1160467D01*
X632258Y1160550D01*
X631967Y1160800D01*
X631800Y1161175D01*
X631758Y1161592D01*
X631842Y1162134D01*
X631967Y1162425D01*
X632175Y1162717D01*
X632467Y1162925D01*
X632758Y1162967D01*
X633050Y1162884D01*
X633258Y1162675D01*
G01X626064Y1146942D02*
X625814Y1147067D01*
X625522Y1147150D01*
X625189D01*
X624814Y1147025D01*
X624522Y1146817D01*
X624314Y1146567D01*
X624147Y1146150D01*
X624105Y1145775D01*
X624189Y1145400D01*
X624314Y1145150D01*
X624564Y1144900D01*
X624855Y1144733D01*
X625147Y1144650D01*
X625439D01*
X625730Y1144733D01*
X625980Y1144858D01*
X626189Y1145025D01*
G01X627539Y1144942D02*
X627830Y1144733D01*
X628164Y1144650D01*
X628497Y1144733D01*
X628789Y1144983D01*
X628997Y1145358D01*
X629080Y1145733D01*
Y1146192D01*
X628997Y1146567D01*
X628789Y1146900D01*
X628539Y1147067D01*
X628247Y1147150D01*
X627914Y1147067D01*
X627664Y1146900D01*
X627497Y1146650D01*
X627414Y1146317D01*
X627497Y1146025D01*
X627705Y1145733D01*
X627955Y1145567D01*
X628247Y1145525D01*
X628580Y1145608D01*
X628830Y1145817D01*
X629080Y1146192D01*
G01X631347Y1144650D02*
X631639Y1144692D01*
X631972Y1144817D01*
X632180Y1145025D01*
X632264Y1145317D01*
X632180Y1145608D01*
X631930Y1145858D01*
X631555Y1145983D01*
X631139D01*
X630889Y1146067D01*
X630680Y1146275D01*
X630597Y1146567D01*
X630722Y1146858D01*
X631014Y1147067D01*
X631347Y1147150D01*
X631680Y1147067D01*
X631972Y1146858D01*
X632097Y1146567D01*
X632014Y1146275D01*
X631805Y1146067D01*
X631555Y1145983D01*
X631139D01*
X630764Y1145858D01*
X630514Y1145608D01*
X630430Y1145317D01*
X630514Y1145025D01*
X630722Y1144817D01*
X631055Y1144692D01*
X631347Y1144650D01*
G01X645176Y1188007D02*
Y1184007D01*
X652576D01*
G01X653364Y1183159D02*
X640364D01*
G01X645350Y1205000D02*
X645017Y1205042D01*
X644725Y1205208D01*
X644475Y1205458D01*
X644308Y1205750D01*
X644225Y1206083D01*
Y1206417D01*
X644308Y1206750D01*
X644475Y1207042D01*
X644725Y1207292D01*
X645017Y1207458D01*
X645350Y1207500D01*
X645683Y1207458D01*
X645975Y1207292D01*
X646225Y1207042D01*
X646392Y1206750D01*
X646475Y1206417D01*
Y1206083D01*
X646392Y1205750D01*
X646225Y1205458D01*
X645975Y1205208D01*
X645683Y1205042D01*
X645350Y1205000D01*
G01X645683Y1205667D02*
X646183Y1205000D01*
G01X647658Y1207083D02*
X647908Y1207333D01*
X648200Y1207458D01*
X648533Y1207500D01*
X648950Y1207417D01*
X649242Y1207208D01*
X649325Y1206958D01*
X649283Y1206708D01*
X649117Y1206500D01*
X648283Y1206083D01*
X647908Y1205792D01*
X647658Y1205375D01*
X647575Y1205000D01*
X649325D01*
G01X650633Y1205375D02*
X650883Y1205167D01*
X651175Y1205042D01*
X651550Y1205000D01*
X651925Y1205083D01*
X652217Y1205250D01*
X652425Y1205542D01*
X652467Y1205875D01*
X652383Y1206208D01*
X652175Y1206417D01*
X651883Y1206583D01*
X651592Y1206625D01*
X651300Y1206583D01*
X650925Y1206417D01*
X651050Y1207500D01*
X652175D01*
G01X653858Y1206042D02*
X654150Y1206333D01*
X654400Y1206500D01*
X654733Y1206583D01*
X655025Y1206500D01*
X655233Y1206333D01*
X655400Y1206083D01*
X655442Y1205792D01*
X655400Y1205542D01*
X655233Y1205292D01*
X654983Y1205083D01*
X654692Y1205000D01*
X654358Y1205083D01*
X654067Y1205333D01*
X653900Y1205708D01*
X653858Y1206125D01*
X653942Y1206667D01*
X654067Y1206958D01*
X654275Y1207250D01*
X654567Y1207458D01*
X654858Y1207500D01*
X655150Y1207417D01*
X655358Y1207208D01*
G01X640269Y1203390D02*
Y1189390D01*
G01X653269Y1203390D02*
X640269D01*
G01Y1189390D02*
X653269D01*
G01X632834Y1204517D02*
X630334D01*
Y1205558D01*
X630459Y1205892D01*
X630626Y1206100D01*
X630959Y1206183D01*
X631292Y1206100D01*
X631501Y1205850D01*
X631626Y1205558D01*
Y1204517D01*
G01Y1205558D02*
X632834Y1206183D01*
G01X630751Y1207658D02*
X630501Y1207908D01*
X630376Y1208200D01*
X630334Y1208533D01*
X630417Y1208950D01*
X630626Y1209242D01*
X630876Y1209325D01*
X631126Y1209283D01*
X631334Y1209117D01*
X631751Y1208283D01*
X632042Y1207908D01*
X632459Y1207658D01*
X632834Y1207575D01*
Y1209325D01*
G01X632459Y1210633D02*
X632667Y1210883D01*
X632792Y1211175D01*
X632834Y1211550D01*
X632751Y1211925D01*
X632584Y1212217D01*
X632292Y1212425D01*
X631959Y1212467D01*
X631626Y1212383D01*
X631417Y1212175D01*
X631251Y1211883D01*
X631209Y1211592D01*
X631251Y1211300D01*
X631417Y1210925D01*
X630334Y1211050D01*
Y1212175D01*
G01X632834Y1214567D02*
X632292Y1214650D01*
X631834Y1214775D01*
X631417Y1214942D01*
X630959Y1215150D01*
X630334Y1215483D01*
Y1213817D01*
G01X636834Y1204517D02*
X634334D01*
Y1205558D01*
X634459Y1205892D01*
X634626Y1206100D01*
X634959Y1206183D01*
X635292Y1206100D01*
X635501Y1205850D01*
X635626Y1205558D01*
Y1204517D01*
G01Y1205558D02*
X636834Y1206183D01*
G01X634751Y1207658D02*
X634501Y1207908D01*
X634376Y1208200D01*
X634334Y1208533D01*
X634417Y1208950D01*
X634626Y1209242D01*
X634876Y1209325D01*
X635126Y1209283D01*
X635334Y1209117D01*
X635751Y1208283D01*
X636042Y1207908D01*
X636459Y1207658D01*
X636834Y1207575D01*
Y1209325D01*
G01X636459Y1210633D02*
X636667Y1210883D01*
X636792Y1211175D01*
X636834Y1211550D01*
X636751Y1211925D01*
X636584Y1212217D01*
X636292Y1212425D01*
X635959Y1212467D01*
X635626Y1212383D01*
X635417Y1212175D01*
X635251Y1211883D01*
X635209Y1211592D01*
X635251Y1211300D01*
X635417Y1210925D01*
X634334Y1211050D01*
Y1212175D01*
G01X636459Y1213733D02*
X636667Y1213983D01*
X636792Y1214275D01*
X636834Y1214650D01*
X636751Y1215025D01*
X636584Y1215317D01*
X636292Y1215525D01*
X635959Y1215567D01*
X635626Y1215483D01*
X635417Y1215275D01*
X635251Y1214983D01*
X635209Y1214692D01*
X635251Y1214400D01*
X635417Y1214025D01*
X634334Y1214150D01*
Y1215275D01*
G01X700074Y105747D02*
Y108247D01*
X701115D01*
X701449Y108122D01*
X701657Y107955D01*
X701740Y107622D01*
X701657Y107289D01*
X701407Y107080D01*
X701115Y106955D01*
X700074D01*
G01X701115D02*
X701740Y105747D01*
G01X703090Y106247D02*
X703340Y105955D01*
X703674Y105789D01*
X704049Y105747D01*
X704382Y105789D01*
X704715Y105997D01*
X704924Y106247D01*
X704965Y106497D01*
X704882Y106789D01*
X704590Y106997D01*
X704299Y107080D01*
X703924D01*
G01X704299D02*
X704549Y107205D01*
X704757Y107414D01*
X704840Y107664D01*
X704757Y107914D01*
X704549Y108122D01*
X704174Y108247D01*
X703799Y108205D01*
X703424Y108039D01*
G01X706399Y106039D02*
X706690Y105830D01*
X707024Y105747D01*
X707357Y105830D01*
X707649Y106080D01*
X707857Y106455D01*
X707940Y106830D01*
Y107289D01*
X707857Y107664D01*
X707649Y107997D01*
X707399Y108164D01*
X707107Y108247D01*
X706774Y108164D01*
X706524Y107997D01*
X706357Y107747D01*
X706274Y107414D01*
X706357Y107122D01*
X706565Y106830D01*
X706815Y106664D01*
X707107Y106622D01*
X707440Y106705D01*
X707690Y106914D01*
X707940Y107289D01*
G01X709415Y107830D02*
X709665Y108080D01*
X709957Y108205D01*
X710290Y108247D01*
X710707Y108164D01*
X710999Y107955D01*
X711082Y107705D01*
X711040Y107455D01*
X710874Y107247D01*
X710040Y106830D01*
X709665Y106539D01*
X709415Y106122D01*
X709332Y105747D01*
X711082D01*
G01X688857Y109247D02*
Y105247D01*
X696257D01*
G01X658256Y104016D02*
X655756D01*
Y105057D01*
X655881Y105391D01*
X656048Y105599D01*
X656381Y105682D01*
X656714Y105599D01*
X656923Y105349D01*
X657048Y105057D01*
Y104016D01*
G01Y105057D02*
X658256Y105682D01*
G01X657756Y107032D02*
X658048Y107282D01*
X658214Y107616D01*
X658256Y107991D01*
X658214Y108324D01*
X658006Y108657D01*
X657756Y108866D01*
X657506Y108907D01*
X657214Y108824D01*
X657006Y108532D01*
X656923Y108241D01*
Y107866D01*
G01Y108241D02*
X656798Y108491D01*
X656589Y108699D01*
X656339Y108782D01*
X656089Y108699D01*
X655881Y108491D01*
X655756Y108116D01*
X655798Y107741D01*
X655964Y107366D01*
G01X658256Y111049D02*
X658214Y111341D01*
X658089Y111674D01*
X657881Y111882D01*
X657589Y111966D01*
X657298Y111882D01*
X657048Y111632D01*
X656923Y111257D01*
Y110841D01*
X656839Y110591D01*
X656631Y110382D01*
X656339Y110299D01*
X656048Y110424D01*
X655839Y110716D01*
X655756Y111049D01*
X655839Y111382D01*
X656048Y111674D01*
X656339Y111799D01*
X656631Y111716D01*
X656839Y111507D01*
X656923Y111257D01*
Y110841D01*
X657048Y110466D01*
X657298Y110216D01*
X657589Y110132D01*
X657881Y110216D01*
X658089Y110424D01*
X658214Y110757D01*
X658256Y111049D01*
G01X657964Y113441D02*
X658173Y113732D01*
X658256Y114066D01*
X658173Y114399D01*
X657923Y114691D01*
X657548Y114899D01*
X657173Y114982D01*
X656714D01*
X656339Y114899D01*
X656006Y114691D01*
X655839Y114441D01*
X655756Y114149D01*
X655839Y113816D01*
X656006Y113566D01*
X656256Y113399D01*
X656589Y113316D01*
X656881Y113399D01*
X657173Y113607D01*
X657339Y113857D01*
X657381Y114149D01*
X657298Y114482D01*
X657089Y114732D01*
X656714Y114982D01*
G01X668142Y111919D02*
X664142D01*
Y104519D01*
G01X675035Y102310D02*
Y100518D01*
X675202Y100143D01*
X675535Y99893D01*
X675952Y99810D01*
X676369Y99893D01*
X676702Y100143D01*
X676869Y100518D01*
Y102310D01*
G01X678135Y100310D02*
X678385Y100018D01*
X678719Y99852D01*
X679094Y99810D01*
X679427Y99852D01*
X679760Y100060D01*
X679969Y100310D01*
X680010Y100560D01*
X679927Y100852D01*
X679635Y101060D01*
X679344Y101143D01*
X678969D01*
G01X679344D02*
X679594Y101268D01*
X679802Y101477D01*
X679885Y101727D01*
X679802Y101977D01*
X679594Y102185D01*
X679219Y102310D01*
X678844Y102268D01*
X678469Y102102D01*
G01X682152Y102310D02*
X681819Y102227D01*
X681569Y102018D01*
X681402Y101768D01*
X681277Y101435D01*
X681235Y101060D01*
X681277Y100685D01*
X681402Y100352D01*
X681569Y100102D01*
X681819Y99893D01*
X682152Y99810D01*
X682485Y99893D01*
X682735Y100102D01*
X682902Y100352D01*
X683027Y100685D01*
X683069Y101060D01*
X683027Y101435D01*
X682902Y101768D01*
X682735Y102018D01*
X682485Y102227D01*
X682152Y102310D01*
G01X685902Y105210D02*
X672502D01*
G01X685902Y115210D02*
Y105210D01*
G01X672502Y115210D02*
X685902D01*
G01X672502Y105210D02*
Y115210D01*
G01X703134Y113530D02*
X702884Y113655D01*
X702592Y113738D01*
X702259D01*
X701884Y113613D01*
X701592Y113405D01*
X701384Y113155D01*
X701217Y112738D01*
X701175Y112363D01*
X701259Y111988D01*
X701384Y111738D01*
X701634Y111488D01*
X701925Y111321D01*
X702217Y111238D01*
X702509D01*
X702800Y111321D01*
X703050Y111446D01*
X703259Y111613D01*
G01X705317Y111238D02*
X705609Y111280D01*
X705942Y111405D01*
X706150Y111613D01*
X706234Y111905D01*
X706150Y112196D01*
X705900Y112446D01*
X705525Y112571D01*
X705109D01*
X704859Y112655D01*
X704650Y112863D01*
X704567Y113155D01*
X704692Y113446D01*
X704984Y113655D01*
X705317Y113738D01*
X705650Y113655D01*
X705942Y113446D01*
X706067Y113155D01*
X705984Y112863D01*
X705775Y112655D01*
X705525Y112571D01*
X705109D01*
X704734Y112446D01*
X704484Y112196D01*
X704400Y111905D01*
X704484Y111613D01*
X704692Y111405D01*
X705025Y111280D01*
X705317Y111238D01*
G01X708417D02*
Y113738D01*
X707917Y113238D01*
G01Y111238D02*
X708917D01*
G01X693900Y163017D02*
X691400D01*
Y164058D01*
X691525Y164392D01*
X691692Y164600D01*
X692025Y164683D01*
X692358Y164600D01*
X692567Y164350D01*
X692692Y164058D01*
Y163017D01*
G01Y164058D02*
X693900Y164683D01*
G01Y166950D02*
X693858Y167242D01*
X693733Y167575D01*
X693525Y167783D01*
X693233Y167867D01*
X692942Y167783D01*
X692692Y167533D01*
X692567Y167158D01*
Y166742D01*
X692483Y166492D01*
X692275Y166283D01*
X691983Y166200D01*
X691692Y166325D01*
X691483Y166617D01*
X691400Y166950D01*
X691483Y167283D01*
X691692Y167575D01*
X691983Y167700D01*
X692275Y167617D01*
X692483Y167408D01*
X692567Y167158D01*
Y166742D01*
X692692Y166367D01*
X692942Y166117D01*
X693233Y166033D01*
X693525Y166117D01*
X693733Y166325D01*
X693858Y166658D01*
X693900Y166950D01*
G01Y170050D02*
X691400D01*
X691900Y169550D01*
G01X693900D02*
Y170550D01*
G01Y173650D02*
X691400D01*
X693192Y172108D01*
Y174192D01*
G01X687500Y162983D02*
X685000D01*
Y163817D01*
X685125Y164150D01*
X685292Y164400D01*
X685542Y164608D01*
X685833Y164775D01*
X686250Y164817D01*
X686667Y164775D01*
X686958Y164608D01*
X687208Y164400D01*
X687375Y164150D01*
X687500Y163817D01*
Y162983D01*
G01X685417Y166208D02*
X685167Y166458D01*
X685042Y166750D01*
X685000Y167083D01*
X685083Y167500D01*
X685292Y167792D01*
X685542Y167875D01*
X685792Y167833D01*
X686000Y167667D01*
X686417Y166833D01*
X686708Y166458D01*
X687125Y166208D01*
X687500Y166125D01*
Y167875D01*
G01X687208Y169392D02*
X687417Y169683D01*
X687500Y170017D01*
X687417Y170350D01*
X687167Y170642D01*
X686792Y170850D01*
X686417Y170933D01*
X685958D01*
X685583Y170850D01*
X685250Y170642D01*
X685083Y170392D01*
X685000Y170100D01*
X685083Y169767D01*
X685250Y169517D01*
X685500Y169350D01*
X685833Y169267D01*
X686125Y169350D01*
X686417Y169558D01*
X686583Y169808D01*
X686625Y170100D01*
X686542Y170433D01*
X686333Y170683D01*
X685958Y170933D01*
G01X695900Y183361D02*
X691900D01*
Y175961D01*
G01X671317Y201161D02*
Y203661D01*
X672358D01*
X672692Y203536D01*
X672900Y203369D01*
X672983Y203036D01*
X672900Y202703D01*
X672650Y202494D01*
X672358Y202369D01*
X671317D01*
G01X672358D02*
X672983Y201161D01*
G01X675250D02*
X675542Y201203D01*
X675875Y201328D01*
X676083Y201536D01*
X676167Y201828D01*
X676083Y202119D01*
X675833Y202369D01*
X675458Y202494D01*
X675042D01*
X674792Y202578D01*
X674583Y202786D01*
X674500Y203078D01*
X674625Y203369D01*
X674917Y203578D01*
X675250Y203661D01*
X675583Y203578D01*
X675875Y203369D01*
X676000Y203078D01*
X675917Y202786D01*
X675708Y202578D01*
X675458Y202494D01*
X675042D01*
X674667Y202369D01*
X674417Y202119D01*
X674333Y201828D01*
X674417Y201536D01*
X674625Y201328D01*
X674958Y201203D01*
X675250Y201161D01*
G01X678350Y203661D02*
X678017Y203578D01*
X677767Y203369D01*
X677600Y203119D01*
X677475Y202786D01*
X677433Y202411D01*
X677475Y202036D01*
X677600Y201703D01*
X677767Y201453D01*
X678017Y201244D01*
X678350Y201161D01*
X678683Y201244D01*
X678933Y201453D01*
X679100Y201703D01*
X679225Y202036D01*
X679267Y202411D01*
X679225Y202786D01*
X679100Y203119D01*
X678933Y203369D01*
X678683Y203578D01*
X678350Y203661D01*
G01X681950Y201161D02*
Y203661D01*
X680408Y201869D01*
X682492D01*
G01X683600Y207161D02*
Y203161D01*
X691000D01*
G01X676000Y183017D02*
X673500D01*
Y184058D01*
X673625Y184392D01*
X673792Y184600D01*
X674125Y184683D01*
X674458Y184600D01*
X674667Y184350D01*
X674792Y184058D01*
Y183017D01*
G01Y184058D02*
X676000Y184683D01*
G01Y186950D02*
X675958Y187242D01*
X675833Y187575D01*
X675625Y187783D01*
X675333Y187867D01*
X675042Y187783D01*
X674792Y187533D01*
X674667Y187158D01*
Y186742D01*
X674583Y186492D01*
X674375Y186283D01*
X674083Y186200D01*
X673792Y186325D01*
X673583Y186617D01*
X673500Y186950D01*
X673583Y187283D01*
X673792Y187575D01*
X674083Y187700D01*
X674375Y187617D01*
X674583Y187408D01*
X674667Y187158D01*
Y186742D01*
X674792Y186367D01*
X675042Y186117D01*
X675333Y186033D01*
X675625Y186117D01*
X675833Y186325D01*
X675958Y186658D01*
X676000Y186950D01*
G01Y190050D02*
X673500D01*
X674000Y189550D01*
G01X676000D02*
Y190550D01*
G01X675500Y192233D02*
X675792Y192483D01*
X675958Y192817D01*
X676000Y193192D01*
X675958Y193525D01*
X675750Y193858D01*
X675500Y194067D01*
X675250Y194108D01*
X674958Y194025D01*
X674750Y193733D01*
X674667Y193442D01*
Y193067D01*
G01Y193442D02*
X674542Y193692D01*
X674333Y193900D01*
X674083Y193983D01*
X673833Y193900D01*
X673625Y193692D01*
X673500Y193317D01*
X673542Y192942D01*
X673708Y192567D01*
G01X679000Y181961D02*
X683000D01*
Y189361D01*
G01X672317Y173900D02*
Y176400D01*
X673358D01*
X673692Y176275D01*
X673900Y176108D01*
X673983Y175775D01*
X673900Y175442D01*
X673650Y175233D01*
X673358Y175108D01*
X672317D01*
G01X673358D02*
X673983Y173900D01*
G01X676250D02*
X676542Y173942D01*
X676875Y174067D01*
X677083Y174275D01*
X677167Y174567D01*
X677083Y174858D01*
X676833Y175108D01*
X676458Y175233D01*
X676042D01*
X675792Y175317D01*
X675583Y175525D01*
X675500Y175817D01*
X675625Y176108D01*
X675917Y176317D01*
X676250Y176400D01*
X676583Y176317D01*
X676875Y176108D01*
X677000Y175817D01*
X676917Y175525D01*
X676708Y175317D01*
X676458Y175233D01*
X676042D01*
X675667Y175108D01*
X675417Y174858D01*
X675333Y174567D01*
X675417Y174275D01*
X675625Y174067D01*
X675958Y173942D01*
X676250Y173900D01*
G01X679350D02*
Y176400D01*
X678850Y175900D01*
G01Y173900D02*
X679850D01*
G01X682450D02*
Y176400D01*
X681950Y175900D01*
G01Y173900D02*
X682950D01*
G01X675600Y181561D02*
Y177561D01*
X683000D01*
G01X663017Y210061D02*
Y212561D01*
X664058D01*
X664392Y212436D01*
X664600Y212269D01*
X664683Y211936D01*
X664600Y211603D01*
X664350Y211394D01*
X664058Y211269D01*
X663017D01*
G01X664058D02*
X664683Y210061D01*
G01X666950D02*
X667242Y210103D01*
X667575Y210228D01*
X667783Y210436D01*
X667867Y210728D01*
X667783Y211019D01*
X667533Y211269D01*
X667158Y211394D01*
X666742D01*
X666492Y211478D01*
X666283Y211686D01*
X666200Y211978D01*
X666325Y212269D01*
X666617Y212478D01*
X666950Y212561D01*
X667283Y212478D01*
X667575Y212269D01*
X667700Y211978D01*
X667617Y211686D01*
X667408Y211478D01*
X667158Y211394D01*
X666742D01*
X666367Y211269D01*
X666117Y211019D01*
X666033Y210728D01*
X666117Y210436D01*
X666325Y210228D01*
X666658Y210103D01*
X666950Y210061D01*
G01X670050D02*
Y212561D01*
X669550Y212061D01*
G01Y210061D02*
X670550D01*
G01X672358Y212144D02*
X672608Y212394D01*
X672900Y212519D01*
X673233Y212561D01*
X673650Y212478D01*
X673942Y212269D01*
X674025Y212019D01*
X673983Y211769D01*
X673817Y211561D01*
X672983Y211144D01*
X672608Y210853D01*
X672358Y210436D01*
X672275Y210061D01*
X674025D01*
G01X683200Y208561D02*
Y212561D01*
X675800D01*
G01X696850Y172500D02*
X696517Y172542D01*
X696225Y172708D01*
X695975Y172958D01*
X695808Y173250D01*
X695725Y173583D01*
Y173917D01*
X695808Y174250D01*
X695975Y174542D01*
X696225Y174792D01*
X696517Y174958D01*
X696850Y175000D01*
X697183Y174958D01*
X697475Y174792D01*
X697725Y174542D01*
X697892Y174250D01*
X697975Y173917D01*
Y173583D01*
X697892Y173250D01*
X697725Y172958D01*
X697475Y172708D01*
X697183Y172542D01*
X696850Y172500D01*
G01X697183Y173167D02*
X697683Y172500D01*
G01X699950D02*
Y175000D01*
X699450Y174500D01*
G01Y172500D02*
X700450D01*
G01X702967D02*
X703050Y173042D01*
X703175Y173500D01*
X703342Y173917D01*
X703550Y174375D01*
X703883Y175000D01*
X702217D01*
G01X705233Y172875D02*
X705483Y172667D01*
X705775Y172542D01*
X706150Y172500D01*
X706525Y172583D01*
X706817Y172750D01*
X707025Y173042D01*
X707067Y173375D01*
X706983Y173708D01*
X706775Y173917D01*
X706483Y174083D01*
X706192Y174125D01*
X705900Y174083D01*
X705525Y173917D01*
X705650Y175000D01*
X706775D01*
G01X707200Y197861D02*
X695800D01*
G01Y184461D02*
X707200D01*
G01X695800Y197861D02*
Y184461D01*
G01X691000Y192161D02*
Y176061D01*
G01X684000Y192161D02*
X691000D01*
G01X684000Y176061D02*
Y192161D01*
G01X691000Y176061D02*
X684000D01*
G01X713300Y223261D02*
X694100D01*
Y212061D01*
X713300D01*
Y223261D01*
X712900D01*
G01X673067Y207553D02*
X672817Y207678D01*
X672525Y207761D01*
X672192D01*
X671817Y207636D01*
X671525Y207428D01*
X671317Y207178D01*
X671150Y206761D01*
X671108Y206386D01*
X671192Y206011D01*
X671317Y205761D01*
X671567Y205511D01*
X671858Y205344D01*
X672150Y205261D01*
X672442D01*
X672733Y205344D01*
X672983Y205469D01*
X673192Y205636D01*
G01X675750Y205261D02*
Y207761D01*
X674208Y205969D01*
X676292D01*
G01X677558Y207344D02*
X677808Y207594D01*
X678100Y207719D01*
X678433Y207761D01*
X678850Y207678D01*
X679142Y207469D01*
X679225Y207219D01*
X679183Y206969D01*
X679017Y206761D01*
X678183Y206344D01*
X677808Y206053D01*
X677558Y205636D01*
X677475Y205261D01*
X679225D01*
G01X680533Y205636D02*
X680783Y205428D01*
X681075Y205303D01*
X681450Y205261D01*
X681825Y205344D01*
X682117Y205511D01*
X682325Y205803D01*
X682367Y206136D01*
X682283Y206469D01*
X682075Y206678D01*
X681783Y206844D01*
X681492Y206886D01*
X681200Y206844D01*
X680825Y206678D01*
X680950Y207761D01*
X682075D01*
G01X686700Y250661D02*
Y258661D01*
X704300D01*
Y250661D01*
X686700D01*
G01X676267Y262792D02*
X676017Y262917D01*
X675725Y263000D01*
X675392D01*
X675017Y262875D01*
X674725Y262667D01*
X674517Y262417D01*
X674350Y262000D01*
X674308Y261625D01*
X674392Y261250D01*
X674517Y261000D01*
X674767Y260750D01*
X675058Y260583D01*
X675350Y260500D01*
X675642D01*
X675933Y260583D01*
X676183Y260708D01*
X676392Y260875D01*
G01X678950Y260500D02*
Y263000D01*
X677408Y261208D01*
X679492D01*
G01X680758Y262583D02*
X681008Y262833D01*
X681300Y262958D01*
X681633Y263000D01*
X682050Y262917D01*
X682342Y262708D01*
X682425Y262458D01*
X682383Y262208D01*
X682217Y262000D01*
X681383Y261583D01*
X681008Y261292D01*
X680758Y260875D01*
X680675Y260500D01*
X682425D01*
G01X683858Y262583D02*
X684108Y262833D01*
X684400Y262958D01*
X684733Y263000D01*
X685150Y262917D01*
X685442Y262708D01*
X685525Y262458D01*
X685483Y262208D01*
X685317Y262000D01*
X684483Y261583D01*
X684108Y261292D01*
X683858Y260875D01*
X683775Y260500D01*
X685525D01*
G01X691200Y244161D02*
X696700D01*
G01X691200Y236161D02*
Y244161D01*
G01X696700Y236161D02*
X691200D01*
G01X666500Y223350D02*
X666458Y223017D01*
X666292Y222725D01*
X666042Y222475D01*
X665750Y222308D01*
X665417Y222225D01*
X665083D01*
X664750Y222308D01*
X664458Y222475D01*
X664208Y222725D01*
X664042Y223017D01*
X664000Y223350D01*
X664042Y223683D01*
X664208Y223975D01*
X664458Y224225D01*
X664750Y224392D01*
X665083Y224475D01*
X665417D01*
X665750Y224392D01*
X666042Y224225D01*
X666292Y223975D01*
X666458Y223683D01*
X666500Y223350D01*
G01X665833Y223683D02*
X666500Y224183D01*
G01Y226450D02*
X664000D01*
X664500Y225950D01*
G01X666500D02*
Y226950D01*
G01Y229467D02*
X665958Y229550D01*
X665500Y229675D01*
X665083Y229842D01*
X664625Y230050D01*
X664000Y230383D01*
Y228717D01*
G01X665458Y231858D02*
X665167Y232150D01*
X665000Y232400D01*
X664917Y232733D01*
X665000Y233025D01*
X665167Y233233D01*
X665417Y233400D01*
X665708Y233442D01*
X665958Y233400D01*
X666208Y233233D01*
X666417Y232983D01*
X666500Y232692D01*
X666417Y232358D01*
X666167Y232067D01*
X665792Y231900D01*
X665375Y231858D01*
X664833Y231942D01*
X664542Y232067D01*
X664250Y232275D01*
X664042Y232567D01*
X664000Y232858D01*
X664083Y233150D01*
X664292Y233358D01*
G01X668800Y237661D02*
X670900Y235861D01*
X668800Y233661D01*
G01X668700Y230061D02*
X687900D01*
Y241261D01*
X668700D01*
Y230061D01*
X669100D01*
G01X664767Y216453D02*
X664517Y216578D01*
X664225Y216661D01*
X663892D01*
X663517Y216536D01*
X663225Y216328D01*
X663017Y216078D01*
X662850Y215661D01*
X662808Y215286D01*
X662892Y214911D01*
X663017Y214661D01*
X663267Y214411D01*
X663558Y214244D01*
X663850Y214161D01*
X664142D01*
X664433Y214244D01*
X664683Y214369D01*
X664892Y214536D01*
G01X667450Y214161D02*
Y216661D01*
X665908Y214869D01*
X667992D01*
G01X669258Y216244D02*
X669508Y216494D01*
X669800Y216619D01*
X670133Y216661D01*
X670550Y216578D01*
X670842Y216369D01*
X670925Y216119D01*
X670883Y215869D01*
X670717Y215661D01*
X669883Y215244D01*
X669508Y214953D01*
X669258Y214536D01*
X669175Y214161D01*
X670925D01*
G01X672358Y215203D02*
X672650Y215494D01*
X672900Y215661D01*
X673233Y215744D01*
X673525Y215661D01*
X673733Y215494D01*
X673900Y215244D01*
X673942Y214953D01*
X673900Y214703D01*
X673733Y214453D01*
X673483Y214244D01*
X673192Y214161D01*
X672858Y214244D01*
X672567Y214494D01*
X672400Y214869D01*
X672358Y215286D01*
X672442Y215828D01*
X672567Y216119D01*
X672775Y216411D01*
X673067Y216619D01*
X673358Y216661D01*
X673650Y216578D01*
X673858Y216369D01*
G01X692017Y271000D02*
Y273500D01*
X693058D01*
X693392Y273375D01*
X693600Y273208D01*
X693683Y272875D01*
X693600Y272542D01*
X693350Y272333D01*
X693058Y272208D01*
X692017D01*
G01X693058D02*
X693683Y271000D01*
G01X695867D02*
X695950Y271542D01*
X696075Y272000D01*
X696242Y272417D01*
X696450Y272875D01*
X696783Y273500D01*
X695117D01*
G01X698342Y271292D02*
X698633Y271083D01*
X698967Y271000D01*
X699300Y271083D01*
X699592Y271333D01*
X699800Y271708D01*
X699883Y272083D01*
Y272542D01*
X699800Y272917D01*
X699592Y273250D01*
X699342Y273417D01*
X699050Y273500D01*
X698717Y273417D01*
X698467Y273250D01*
X698300Y273000D01*
X698217Y272667D01*
X698300Y272375D01*
X698508Y272083D01*
X698758Y271917D01*
X699050Y271875D01*
X699383Y271958D01*
X699633Y272167D01*
X699883Y272542D01*
G01X702150Y271000D02*
X702442Y271042D01*
X702775Y271167D01*
X702983Y271375D01*
X703067Y271667D01*
X702983Y271958D01*
X702733Y272208D01*
X702358Y272333D01*
X701942D01*
X701692Y272417D01*
X701483Y272625D01*
X701400Y272917D01*
X701525Y273208D01*
X701817Y273417D01*
X702150Y273500D01*
X702483Y273417D01*
X702775Y273208D01*
X702900Y272917D01*
X702817Y272625D01*
X702608Y272417D01*
X702358Y272333D01*
X701942D01*
X701567Y272208D01*
X701317Y271958D01*
X701233Y271667D01*
X701317Y271375D01*
X701525Y271167D01*
X701858Y271042D01*
X702150Y271000D01*
G01X693767Y265292D02*
X693517Y265417D01*
X693225Y265500D01*
X692892D01*
X692517Y265375D01*
X692225Y265167D01*
X692017Y264917D01*
X691850Y264500D01*
X691808Y264125D01*
X691892Y263750D01*
X692017Y263500D01*
X692267Y263250D01*
X692558Y263083D01*
X692850Y263000D01*
X693142D01*
X693433Y263083D01*
X693683Y263208D01*
X693892Y263375D01*
G01X696450Y263000D02*
Y265500D01*
X694908Y263708D01*
X696992D01*
G01X699050Y263000D02*
Y265500D01*
X698550Y265000D01*
G01Y263000D02*
X699550D01*
G01X702150D02*
X702442Y263042D01*
X702775Y263167D01*
X702983Y263375D01*
X703067Y263667D01*
X702983Y263958D01*
X702733Y264208D01*
X702358Y264333D01*
X701942D01*
X701692Y264417D01*
X701483Y264625D01*
X701400Y264917D01*
X701525Y265208D01*
X701817Y265417D01*
X702150Y265500D01*
X702483Y265417D01*
X702775Y265208D01*
X702900Y264917D01*
X702817Y264625D01*
X702608Y264417D01*
X702358Y264333D01*
X701942D01*
X701567Y264208D01*
X701317Y263958D01*
X701233Y263667D01*
X701317Y263375D01*
X701525Y263167D01*
X701858Y263042D01*
X702150Y263000D01*
G01X693767Y269292D02*
X693517Y269417D01*
X693225Y269500D01*
X692892D01*
X692517Y269375D01*
X692225Y269167D01*
X692017Y268917D01*
X691850Y268500D01*
X691808Y268125D01*
X691892Y267750D01*
X692017Y267500D01*
X692267Y267250D01*
X692558Y267083D01*
X692850Y267000D01*
X693142D01*
X693433Y267083D01*
X693683Y267208D01*
X693892Y267375D01*
G01X696450Y267000D02*
Y269500D01*
X694908Y267708D01*
X696992D01*
G01X699050Y267000D02*
Y269500D01*
X698550Y269000D01*
G01Y267000D02*
X699550D01*
G01X702067D02*
X702150Y267542D01*
X702275Y268000D01*
X702442Y268417D01*
X702650Y268875D01*
X702983Y269500D01*
X701317D01*
G01X682458Y390000D02*
Y392500D01*
X684042D01*
G01X683458Y391292D02*
X682458D01*
G01X685517Y392500D02*
Y390000D01*
X687183D01*
G01X690283D02*
X688617D01*
Y392500D01*
X690283D01*
G01X689617Y391292D02*
X688617D01*
G01X691633Y390000D02*
Y392500D01*
X692467D01*
X692800Y392375D01*
X693050Y392208D01*
X693258Y391958D01*
X693425Y391667D01*
X693467Y391250D01*
X693425Y390833D01*
X693258Y390542D01*
X693050Y390292D01*
X692800Y390125D01*
X692467Y390000D01*
X691633D01*
G01X695650D02*
Y392500D01*
X695150Y392000D01*
G01Y390000D02*
X696150D01*
G01X698750D02*
X699042Y390042D01*
X699375Y390167D01*
X699583Y390375D01*
X699667Y390667D01*
X699583Y390958D01*
X699333Y391208D01*
X698958Y391333D01*
X698542D01*
X698292Y391417D01*
X698083Y391625D01*
X698000Y391917D01*
X698125Y392208D01*
X698417Y392417D01*
X698750Y392500D01*
X699083Y392417D01*
X699375Y392208D01*
X699500Y391917D01*
X699417Y391625D01*
X699208Y391417D01*
X698958Y391333D01*
X698542D01*
X698167Y391208D01*
X697917Y390958D01*
X697833Y390667D01*
X697917Y390375D01*
X698125Y390167D01*
X698458Y390042D01*
X698750Y390000D01*
G01X686742Y366054D02*
Y377254D01*
X695542D01*
Y366054D01*
X686742D01*
G01X664043Y506654D02*
X661543D01*
Y507695D01*
X661668Y508029D01*
X661835Y508237D01*
X662168Y508320D01*
X662501Y508237D01*
X662710Y507987D01*
X662835Y507695D01*
Y506654D01*
G01Y507695D02*
X664043Y508320D01*
G01X663543Y509670D02*
X663835Y509920D01*
X664001Y510254D01*
X664043Y510629D01*
X664001Y510962D01*
X663793Y511295D01*
X663543Y511504D01*
X663293Y511545D01*
X663001Y511462D01*
X662793Y511170D01*
X662710Y510879D01*
Y510504D01*
G01Y510879D02*
X662585Y511129D01*
X662376Y511337D01*
X662126Y511420D01*
X661876Y511337D01*
X661668Y511129D01*
X661543Y510754D01*
X661585Y510379D01*
X661751Y510004D01*
G01X664043Y513687D02*
X661543D01*
X662043Y513187D01*
G01X664043D02*
Y514187D01*
G01X661960Y515995D02*
X661710Y516245D01*
X661585Y516537D01*
X661543Y516870D01*
X661626Y517287D01*
X661835Y517579D01*
X662085Y517662D01*
X662335Y517620D01*
X662543Y517454D01*
X662960Y516620D01*
X663251Y516245D01*
X663668Y515995D01*
X664043Y515912D01*
Y517662D01*
G01X659043Y506654D02*
X656543D01*
Y507695D01*
X656668Y508029D01*
X656835Y508237D01*
X657168Y508320D01*
X657501Y508237D01*
X657710Y507987D01*
X657835Y507695D01*
Y506654D01*
G01Y507695D02*
X659043Y508320D01*
G01X658543Y509670D02*
X658835Y509920D01*
X659001Y510254D01*
X659043Y510629D01*
X659001Y510962D01*
X658793Y511295D01*
X658543Y511504D01*
X658293Y511545D01*
X658001Y511462D01*
X657793Y511170D01*
X657710Y510879D01*
Y510504D01*
G01Y510879D02*
X657585Y511129D01*
X657376Y511337D01*
X657126Y511420D01*
X656876Y511337D01*
X656668Y511129D01*
X656543Y510754D01*
X656585Y510379D01*
X656751Y510004D01*
G01X659043Y513687D02*
X656543D01*
X657043Y513187D01*
G01X659043D02*
Y514187D01*
G01Y516787D02*
X656543D01*
X657043Y516287D01*
G01X659043D02*
Y517287D01*
G01X666208Y534767D02*
X666083Y534517D01*
X666000Y534225D01*
Y533892D01*
X666125Y533517D01*
X666333Y533225D01*
X666583Y533017D01*
X667000Y532850D01*
X667375Y532808D01*
X667750Y532892D01*
X668000Y533017D01*
X668250Y533267D01*
X668417Y533558D01*
X668500Y533850D01*
Y534142D01*
X668417Y534433D01*
X668292Y534683D01*
X668125Y534892D01*
G01Y536033D02*
X668333Y536283D01*
X668458Y536575D01*
X668500Y536950D01*
X668417Y537325D01*
X668250Y537617D01*
X667958Y537825D01*
X667625Y537867D01*
X667292Y537783D01*
X667083Y537575D01*
X666917Y537283D01*
X666875Y536992D01*
X666917Y536700D01*
X667083Y536325D01*
X666000Y536450D01*
Y537575D01*
G01X668500Y540550D02*
X666000D01*
X667792Y539008D01*
Y541092D01*
G01X668125Y542233D02*
X668333Y542483D01*
X668458Y542775D01*
X668500Y543150D01*
X668417Y543525D01*
X668250Y543817D01*
X667958Y544025D01*
X667625Y544067D01*
X667292Y543983D01*
X667083Y543775D01*
X666917Y543483D01*
X666875Y543192D01*
X666917Y542900D01*
X667083Y542525D01*
X666000Y542650D01*
Y543775D01*
G01X660467Y576000D02*
Y578500D01*
X661508D01*
X661842Y578375D01*
X662050Y578208D01*
X662133Y577875D01*
X662050Y577542D01*
X661800Y577333D01*
X661508Y577208D01*
X660467D01*
G01X661508D02*
X662133Y576000D01*
G01X664400D02*
Y578500D01*
X663900Y578000D01*
G01Y576000D02*
X664900D01*
G01X667500Y578500D02*
X667167Y578417D01*
X666917Y578208D01*
X666750Y577958D01*
X666625Y577625D01*
X666583Y577250D01*
X666625Y576875D01*
X666750Y576542D01*
X666917Y576292D01*
X667167Y576083D01*
X667500Y576000D01*
X667833Y576083D01*
X668083Y576292D01*
X668250Y576542D01*
X668375Y576875D01*
X668417Y577250D01*
X668375Y577625D01*
X668250Y577958D01*
X668083Y578208D01*
X667833Y578417D01*
X667500Y578500D01*
G01X669808Y577042D02*
X670100Y577333D01*
X670350Y577500D01*
X670683Y577583D01*
X670975Y577500D01*
X671183Y577333D01*
X671350Y577083D01*
X671392Y576792D01*
X671350Y576542D01*
X671183Y576292D01*
X670933Y576083D01*
X670642Y576000D01*
X670308Y576083D01*
X670017Y576333D01*
X669850Y576708D01*
X669808Y577125D01*
X669892Y577667D01*
X670017Y577958D01*
X670225Y578250D01*
X670517Y578458D01*
X670808Y578500D01*
X671100Y578417D01*
X671308Y578208D01*
G01X673617Y576000D02*
X673700Y576542D01*
X673825Y577000D01*
X673992Y577417D01*
X674200Y577875D01*
X674533Y578500D01*
X672867D01*
G01X658965Y573967D02*
Y580967D01*
G01X680467Y574500D02*
Y577000D01*
X681508D01*
X681842Y576875D01*
X682050Y576708D01*
X682133Y576375D01*
X682050Y576042D01*
X681800Y575833D01*
X681508Y575708D01*
X680467D01*
G01X681508D02*
X682133Y574500D01*
G01X684400D02*
Y577000D01*
X683900Y576500D01*
G01Y574500D02*
X684900D01*
G01X687500Y577000D02*
X687167Y576917D01*
X686917Y576708D01*
X686750Y576458D01*
X686625Y576125D01*
X686583Y575750D01*
X686625Y575375D01*
X686750Y575042D01*
X686917Y574792D01*
X687167Y574583D01*
X687500Y574500D01*
X687833Y574583D01*
X688083Y574792D01*
X688250Y575042D01*
X688375Y575375D01*
X688417Y575750D01*
X688375Y576125D01*
X688250Y576458D01*
X688083Y576708D01*
X687833Y576917D01*
X687500Y577000D01*
G01X689808Y575542D02*
X690100Y575833D01*
X690350Y576000D01*
X690683Y576083D01*
X690975Y576000D01*
X691183Y575833D01*
X691350Y575583D01*
X691392Y575292D01*
X691350Y575042D01*
X691183Y574792D01*
X690933Y574583D01*
X690642Y574500D01*
X690308Y574583D01*
X690017Y574833D01*
X689850Y575208D01*
X689808Y575625D01*
X689892Y576167D01*
X690017Y576458D01*
X690225Y576750D01*
X690517Y576958D01*
X690808Y577000D01*
X691100Y576917D01*
X691308Y576708D01*
G01X692908Y576583D02*
X693158Y576833D01*
X693450Y576958D01*
X693783Y577000D01*
X694200Y576917D01*
X694492Y576708D01*
X694575Y576458D01*
X694533Y576208D01*
X694367Y576000D01*
X693533Y575583D01*
X693158Y575292D01*
X692908Y574875D01*
X692825Y574500D01*
X694575D01*
G01X680044Y599326D02*
X693044D01*
Y583826D01*
X680044D01*
Y599326D01*
G01X699708Y581267D02*
X699583Y581017D01*
X699500Y580725D01*
Y580392D01*
X699625Y580017D01*
X699833Y579725D01*
X700083Y579517D01*
X700500Y579350D01*
X700875Y579308D01*
X701250Y579392D01*
X701500Y579517D01*
X701750Y579767D01*
X701917Y580058D01*
X702000Y580350D01*
Y580642D01*
X701917Y580933D01*
X701792Y581183D01*
X701625Y581392D01*
G01Y582533D02*
X701833Y582783D01*
X701958Y583075D01*
X702000Y583450D01*
X701917Y583825D01*
X701750Y584117D01*
X701458Y584325D01*
X701125Y584367D01*
X700792Y584283D01*
X700583Y584075D01*
X700417Y583783D01*
X700375Y583492D01*
X700417Y583200D01*
X700583Y582825D01*
X699500Y582950D01*
Y584075D01*
G01X701625Y585633D02*
X701833Y585883D01*
X701958Y586175D01*
X702000Y586550D01*
X701917Y586925D01*
X701750Y587217D01*
X701458Y587425D01*
X701125Y587467D01*
X700792Y587383D01*
X700583Y587175D01*
X700417Y586883D01*
X700375Y586592D01*
X700417Y586300D01*
X700583Y585925D01*
X699500Y586050D01*
Y587175D01*
G01X702000Y589650D02*
X699500D01*
X700000Y589150D01*
G01X702000D02*
Y590150D01*
G01X670758Y623869D02*
Y626369D01*
X671799D01*
X672133Y626244D01*
X672341Y626077D01*
X672424Y625744D01*
X672341Y625411D01*
X672091Y625202D01*
X671799Y625077D01*
X670758D01*
G01X671799D02*
X672424Y623869D01*
G01X673774Y624244D02*
X674024Y624036D01*
X674316Y623911D01*
X674691Y623869D01*
X675066Y623952D01*
X675358Y624119D01*
X675566Y624411D01*
X675608Y624744D01*
X675524Y625077D01*
X675316Y625286D01*
X675024Y625452D01*
X674733Y625494D01*
X674441Y625452D01*
X674066Y625286D01*
X674191Y626369D01*
X675316D01*
G01X676874Y624369D02*
X677124Y624077D01*
X677458Y623911D01*
X677833Y623869D01*
X678166Y623911D01*
X678499Y624119D01*
X678708Y624369D01*
X678749Y624619D01*
X678666Y624911D01*
X678374Y625119D01*
X678083Y625202D01*
X677708D01*
G01X678083D02*
X678333Y625327D01*
X678541Y625536D01*
X678624Y625786D01*
X678541Y626036D01*
X678333Y626244D01*
X677958Y626369D01*
X677583Y626327D01*
X677208Y626161D01*
G01X679974Y624244D02*
X680224Y624036D01*
X680516Y623911D01*
X680891Y623869D01*
X681266Y623952D01*
X681558Y624119D01*
X681766Y624411D01*
X681808Y624744D01*
X681724Y625077D01*
X681516Y625286D01*
X681224Y625452D01*
X680933Y625494D01*
X680641Y625452D01*
X680266Y625286D01*
X680391Y626369D01*
X681516D01*
G01X680050Y633917D02*
Y629917D01*
X687450D01*
G01X682500Y637517D02*
X680000D01*
Y638558D01*
X680125Y638892D01*
X680292Y639100D01*
X680625Y639183D01*
X680958Y639100D01*
X681167Y638850D01*
X681292Y638558D01*
Y637517D01*
G01Y638558D02*
X682500Y639183D01*
G01X682125Y640533D02*
X682333Y640783D01*
X682458Y641075D01*
X682500Y641450D01*
X682417Y641825D01*
X682250Y642117D01*
X681958Y642325D01*
X681625Y642367D01*
X681292Y642283D01*
X681083Y642075D01*
X680917Y641783D01*
X680875Y641492D01*
X680917Y641200D01*
X681083Y640825D01*
X680000Y640950D01*
Y642075D01*
G01X682000Y643633D02*
X682292Y643883D01*
X682458Y644217D01*
X682500Y644592D01*
X682458Y644925D01*
X682250Y645258D01*
X682000Y645467D01*
X681750Y645508D01*
X681458Y645425D01*
X681250Y645133D01*
X681167Y644842D01*
Y644467D01*
G01Y644842D02*
X681042Y645092D01*
X680833Y645300D01*
X680583Y645383D01*
X680333Y645300D01*
X680125Y645092D01*
X680000Y644717D01*
X680042Y644342D01*
X680208Y643967D01*
G01X682500Y647567D02*
X681958Y647650D01*
X681500Y647775D01*
X681083Y647942D01*
X680625Y648150D01*
X680000Y648483D01*
Y646817D01*
G01X683500Y634717D02*
X687500D01*
Y642117D01*
G01X690187Y620697D02*
Y623197D01*
X691228D01*
X691562Y623072D01*
X691770Y622905D01*
X691853Y622572D01*
X691770Y622239D01*
X691520Y622030D01*
X691228Y621905D01*
X690187D01*
G01X691228D02*
X691853Y620697D01*
G01X693203Y621072D02*
X693453Y620864D01*
X693745Y620739D01*
X694120Y620697D01*
X694495Y620780D01*
X694787Y620947D01*
X694995Y621239D01*
X695037Y621572D01*
X694953Y621905D01*
X694745Y622114D01*
X694453Y622280D01*
X694162Y622322D01*
X693870Y622280D01*
X693495Y622114D01*
X693620Y623197D01*
X694745D01*
G01X696303Y621197D02*
X696553Y620905D01*
X696887Y620739D01*
X697262Y620697D01*
X697595Y620739D01*
X697928Y620947D01*
X698137Y621197D01*
X698178Y621447D01*
X698095Y621739D01*
X697803Y621947D01*
X697512Y622030D01*
X697137D01*
G01X697512D02*
X697762Y622155D01*
X697970Y622364D01*
X698053Y622614D01*
X697970Y622864D01*
X697762Y623072D01*
X697387Y623197D01*
X697012Y623155D01*
X696637Y622989D01*
G01X700320Y620697D02*
X700612Y620739D01*
X700945Y620864D01*
X701153Y621072D01*
X701237Y621364D01*
X701153Y621655D01*
X700903Y621905D01*
X700528Y622030D01*
X700112D01*
X699862Y622114D01*
X699653Y622322D01*
X699570Y622614D01*
X699695Y622905D01*
X699987Y623114D01*
X700320Y623197D01*
X700653Y623114D01*
X700945Y622905D01*
X701070Y622614D01*
X700987Y622322D01*
X700778Y622114D01*
X700528Y622030D01*
X700112D01*
X699737Y621905D01*
X699487Y621655D01*
X699403Y621364D01*
X699487Y621072D01*
X699695Y620864D01*
X700028Y620739D01*
X700320Y620697D01*
G01X695953Y632996D02*
Y628996D01*
X703353D01*
G01X691020Y624397D02*
X690687Y624439D01*
X690395Y624605D01*
X690145Y624855D01*
X689978Y625147D01*
X689895Y625480D01*
Y625814D01*
X689978Y626147D01*
X690145Y626439D01*
X690395Y626689D01*
X690687Y626855D01*
X691020Y626897D01*
X691353Y626855D01*
X691645Y626689D01*
X691895Y626439D01*
X692062Y626147D01*
X692145Y625814D01*
Y625480D01*
X692062Y625147D01*
X691895Y624855D01*
X691645Y624605D01*
X691353Y624439D01*
X691020Y624397D01*
G01X691353Y625064D02*
X691853Y624397D01*
G01X694120D02*
Y626897D01*
X693620Y626397D01*
G01Y624397D02*
X694620D01*
G01X697220Y626897D02*
X696887Y626814D01*
X696637Y626605D01*
X696470Y626355D01*
X696345Y626022D01*
X696303Y625647D01*
X696345Y625272D01*
X696470Y624939D01*
X696637Y624689D01*
X696887Y624480D01*
X697220Y624397D01*
X697553Y624480D01*
X697803Y624689D01*
X697970Y624939D01*
X698095Y625272D01*
X698137Y625647D01*
X698095Y626022D01*
X697970Y626355D01*
X697803Y626605D01*
X697553Y626814D01*
X697220Y626897D01*
G01X699403Y624897D02*
X699653Y624605D01*
X699987Y624439D01*
X700362Y624397D01*
X700695Y624439D01*
X701028Y624647D01*
X701237Y624897D01*
X701278Y625147D01*
X701195Y625439D01*
X700903Y625647D01*
X700612Y625730D01*
X700237D01*
G01X700612D02*
X700862Y625855D01*
X701070Y626064D01*
X701153Y626314D01*
X701070Y626564D01*
X700862Y626772D01*
X700487Y626897D01*
X700112Y626855D01*
X699737Y626689D01*
G01X696000Y638717D02*
X707400D01*
G01X696000Y652117D02*
Y638717D01*
G01X687100Y618483D02*
X684600D01*
Y619317D01*
X684725Y619650D01*
X684892Y619900D01*
X685142Y620108D01*
X685433Y620275D01*
X685850Y620317D01*
X686267Y620275D01*
X686558Y620108D01*
X686808Y619900D01*
X686975Y619650D01*
X687100Y619317D01*
Y618483D01*
G01Y622500D02*
X684600D01*
X685100Y622000D01*
G01X687100D02*
Y623000D01*
G01Y625517D02*
X686558Y625600D01*
X686100Y625725D01*
X685683Y625892D01*
X685225Y626100D01*
X684600Y626433D01*
Y624767D01*
G01X695100Y644917D02*
Y628817D01*
G01X688100Y644917D02*
X695100D01*
G01X688100Y628817D02*
Y644917D01*
G01X695100Y628817D02*
X688100D01*
G01X657449Y666597D02*
Y669097D01*
X658490D01*
X658824Y668972D01*
X659032Y668805D01*
X659115Y668472D01*
X659032Y668139D01*
X658782Y667930D01*
X658490Y667805D01*
X657449D01*
G01X658490D02*
X659115Y666597D01*
G01X660465Y666972D02*
X660715Y666764D01*
X661007Y666639D01*
X661382Y666597D01*
X661757Y666680D01*
X662049Y666847D01*
X662257Y667139D01*
X662299Y667472D01*
X662215Y667805D01*
X662007Y668014D01*
X661715Y668180D01*
X661424Y668222D01*
X661132Y668180D01*
X660757Y668014D01*
X660882Y669097D01*
X662007D01*
G01X663690Y668680D02*
X663940Y668930D01*
X664232Y669055D01*
X664565Y669097D01*
X664982Y669014D01*
X665274Y668805D01*
X665357Y668555D01*
X665315Y668305D01*
X665149Y668097D01*
X664315Y667680D01*
X663940Y667389D01*
X663690Y666972D01*
X663607Y666597D01*
X665357D01*
G01X667582D02*
X667874Y666639D01*
X668207Y666764D01*
X668415Y666972D01*
X668499Y667264D01*
X668415Y667555D01*
X668165Y667805D01*
X667790Y667930D01*
X667374D01*
X667124Y668014D01*
X666915Y668222D01*
X666832Y668514D01*
X666957Y668805D01*
X667249Y669014D01*
X667582Y669097D01*
X667915Y669014D01*
X668207Y668805D01*
X668332Y668514D01*
X668249Y668222D01*
X668040Y668014D01*
X667790Y667930D01*
X667374D01*
X666999Y667805D01*
X666749Y667555D01*
X666665Y667264D01*
X666749Y666972D01*
X666957Y666764D01*
X667290Y666639D01*
X667582Y666597D01*
G01X683600Y659917D02*
Y655917D01*
X691000D01*
G01X654304Y674864D02*
Y677364D01*
X655345D01*
X655679Y677239D01*
X655887Y677072D01*
X655970Y676739D01*
X655887Y676406D01*
X655637Y676197D01*
X655345Y676072D01*
X654304D01*
G01X655345D02*
X655970Y674864D01*
G01X657320Y675239D02*
X657570Y675031D01*
X657862Y674906D01*
X658237Y674864D01*
X658612Y674947D01*
X658904Y675114D01*
X659112Y675406D01*
X659154Y675739D01*
X659070Y676072D01*
X658862Y676281D01*
X658570Y676447D01*
X658279Y676489D01*
X657987Y676447D01*
X657612Y676281D01*
X657737Y677364D01*
X658862D01*
G01X660420Y675364D02*
X660670Y675072D01*
X661004Y674906D01*
X661379Y674864D01*
X661712Y674906D01*
X662045Y675114D01*
X662254Y675364D01*
X662295Y675614D01*
X662212Y675906D01*
X661920Y676114D01*
X661629Y676197D01*
X661254D01*
G01X661629D02*
X661879Y676322D01*
X662087Y676531D01*
X662170Y676781D01*
X662087Y677031D01*
X661879Y677239D01*
X661504Y677364D01*
X661129Y677322D01*
X660754Y677156D01*
G01X663645Y675906D02*
X663937Y676197D01*
X664187Y676364D01*
X664520Y676447D01*
X664812Y676364D01*
X665020Y676197D01*
X665187Y675947D01*
X665229Y675656D01*
X665187Y675406D01*
X665020Y675156D01*
X664770Y674947D01*
X664479Y674864D01*
X664145Y674947D01*
X663854Y675197D01*
X663687Y675572D01*
X663645Y675989D01*
X663729Y676531D01*
X663854Y676822D01*
X664062Y677114D01*
X664354Y677322D01*
X664645Y677364D01*
X664937Y677281D01*
X665145Y677072D01*
G01X683700Y663817D02*
Y667817D01*
X676300D01*
G01X707400Y652117D02*
X696000D01*
G01X691200Y688917D02*
Y696917D01*
G01X696700Y688917D02*
X691200D01*
G01X664560Y685147D02*
X664518Y684814D01*
X664352Y684522D01*
X664102Y684272D01*
X663810Y684105D01*
X663477Y684022D01*
X663143D01*
X662810Y684105D01*
X662518Y684272D01*
X662268Y684522D01*
X662102Y684814D01*
X662060Y685147D01*
X662102Y685480D01*
X662268Y685772D01*
X662518Y686022D01*
X662810Y686189D01*
X663143Y686272D01*
X663477D01*
X663810Y686189D01*
X664102Y686022D01*
X664352Y685772D01*
X664518Y685480D01*
X664560Y685147D01*
G01X663893Y685480D02*
X664560Y685980D01*
G01Y688247D02*
X662060D01*
X662560Y687747D01*
G01X664560D02*
Y688747D01*
G01X662060Y691347D02*
X662143Y691014D01*
X662352Y690764D01*
X662602Y690597D01*
X662935Y690472D01*
X663310Y690430D01*
X663685Y690472D01*
X664018Y690597D01*
X664268Y690764D01*
X664477Y691014D01*
X664560Y691347D01*
X664477Y691680D01*
X664268Y691930D01*
X664018Y692097D01*
X663685Y692222D01*
X663310Y692264D01*
X662935Y692222D01*
X662602Y692097D01*
X662352Y691930D01*
X662143Y691680D01*
X662060Y691347D01*
G01X664560Y694947D02*
X662060D01*
X663852Y693405D01*
Y695489D01*
G01X668800Y690417D02*
X670900Y688617D01*
X668800Y686417D01*
G01X668700Y682817D02*
X687900D01*
Y694017D01*
X668700D01*
Y682817D01*
X669100D01*
G01X713300Y676017D02*
X694100D01*
Y664817D01*
X713300D01*
Y676017D01*
X712900D01*
G01X656054Y681256D02*
X655804Y681381D01*
X655512Y681464D01*
X655179D01*
X654804Y681339D01*
X654512Y681131D01*
X654304Y680881D01*
X654137Y680464D01*
X654095Y680089D01*
X654179Y679714D01*
X654304Y679464D01*
X654554Y679214D01*
X654845Y679047D01*
X655137Y678964D01*
X655429D01*
X655720Y679047D01*
X655970Y679172D01*
X656179Y679339D01*
G01X657445Y681047D02*
X657695Y681297D01*
X657987Y681422D01*
X658320Y681464D01*
X658737Y681381D01*
X659029Y681172D01*
X659112Y680922D01*
X659070Y680672D01*
X658904Y680464D01*
X658070Y680047D01*
X657695Y679756D01*
X657445Y679339D01*
X657362Y678964D01*
X659112D01*
G01X661254D02*
X661337Y679506D01*
X661462Y679964D01*
X661629Y680381D01*
X661837Y680839D01*
X662170Y681464D01*
X660504D01*
G01X664437D02*
X664104Y681381D01*
X663854Y681172D01*
X663687Y680922D01*
X663562Y680589D01*
X663520Y680214D01*
X663562Y679839D01*
X663687Y679506D01*
X663854Y679256D01*
X664104Y679047D01*
X664437Y678964D01*
X664770Y679047D01*
X665020Y679256D01*
X665187Y679506D01*
X665312Y679839D01*
X665354Y680214D01*
X665312Y680589D01*
X665187Y680922D01*
X665020Y681172D01*
X664770Y681381D01*
X664437Y681464D01*
G01X659199Y672989D02*
X658949Y673114D01*
X658657Y673197D01*
X658324D01*
X657949Y673072D01*
X657657Y672864D01*
X657449Y672614D01*
X657282Y672197D01*
X657240Y671822D01*
X657324Y671447D01*
X657449Y671197D01*
X657699Y670947D01*
X657990Y670780D01*
X658282Y670697D01*
X658574D01*
X658865Y670780D01*
X659115Y670905D01*
X659324Y671072D01*
G01X660590Y672780D02*
X660840Y673030D01*
X661132Y673155D01*
X661465Y673197D01*
X661882Y673114D01*
X662174Y672905D01*
X662257Y672655D01*
X662215Y672405D01*
X662049Y672197D01*
X661215Y671780D01*
X660840Y671489D01*
X660590Y671072D01*
X660507Y670697D01*
X662257D01*
G01X663690Y671739D02*
X663982Y672030D01*
X664232Y672197D01*
X664565Y672280D01*
X664857Y672197D01*
X665065Y672030D01*
X665232Y671780D01*
X665274Y671489D01*
X665232Y671239D01*
X665065Y670989D01*
X664815Y670780D01*
X664524Y670697D01*
X664190Y670780D01*
X663899Y671030D01*
X663732Y671405D01*
X663690Y671822D01*
X663774Y672364D01*
X663899Y672655D01*
X664107Y672947D01*
X664399Y673155D01*
X664690Y673197D01*
X664982Y673114D01*
X665190Y672905D01*
G01X666874Y670989D02*
X667165Y670780D01*
X667499Y670697D01*
X667832Y670780D01*
X668124Y671030D01*
X668332Y671405D01*
X668415Y671780D01*
Y672239D01*
X668332Y672614D01*
X668124Y672947D01*
X667874Y673114D01*
X667582Y673197D01*
X667249Y673114D01*
X666999Y672947D01*
X666832Y672697D01*
X666749Y672364D01*
X666832Y672072D01*
X667040Y671780D01*
X667290Y671614D01*
X667582Y671572D01*
X667915Y671655D01*
X668165Y671864D01*
X668415Y672239D01*
G01X693517Y725000D02*
Y727500D01*
X694558D01*
X694892Y727375D01*
X695100Y727208D01*
X695183Y726875D01*
X695100Y726542D01*
X694850Y726333D01*
X694558Y726208D01*
X693517D01*
G01X694558D02*
X695183Y725000D01*
G01X696533Y725375D02*
X696783Y725167D01*
X697075Y725042D01*
X697450Y725000D01*
X697825Y725083D01*
X698117Y725250D01*
X698325Y725542D01*
X698367Y725875D01*
X698283Y726208D01*
X698075Y726417D01*
X697783Y726583D01*
X697492Y726625D01*
X697200Y726583D01*
X696825Y726417D01*
X696950Y727500D01*
X698075D01*
G01X699758Y727083D02*
X700008Y727333D01*
X700300Y727458D01*
X700633Y727500D01*
X701050Y727417D01*
X701342Y727208D01*
X701425Y726958D01*
X701383Y726708D01*
X701217Y726500D01*
X700383Y726083D01*
X700008Y725792D01*
X699758Y725375D01*
X699675Y725000D01*
X701425D01*
G01X702858Y727083D02*
X703108Y727333D01*
X703400Y727458D01*
X703733Y727500D01*
X704150Y727417D01*
X704442Y727208D01*
X704525Y726958D01*
X704483Y726708D01*
X704317Y726500D01*
X703483Y726083D01*
X703108Y725792D01*
X702858Y725375D01*
X702775Y725000D01*
X704525D01*
G01X686700Y703417D02*
Y711417D01*
X704300D01*
Y703417D01*
X686700D01*
G01X657780Y723533D02*
X657738Y723200D01*
X657572Y722908D01*
X657322Y722658D01*
X657030Y722491D01*
X656697Y722408D01*
X656363D01*
X656030Y722491D01*
X655738Y722658D01*
X655488Y722908D01*
X655322Y723200D01*
X655280Y723533D01*
X655322Y723866D01*
X655488Y724158D01*
X655738Y724408D01*
X656030Y724575D01*
X656363Y724658D01*
X656697D01*
X657030Y724575D01*
X657322Y724408D01*
X657572Y724158D01*
X657738Y723866D01*
X657780Y723533D01*
G01X657113Y723866D02*
X657780Y724366D01*
G01X655697Y725841D02*
X655447Y726091D01*
X655322Y726383D01*
X655280Y726716D01*
X655363Y727133D01*
X655572Y727425D01*
X655822Y727508D01*
X656072Y727466D01*
X656280Y727300D01*
X656697Y726466D01*
X656988Y726091D01*
X657405Y725841D01*
X657780Y725758D01*
Y727508D01*
G01X656738Y728941D02*
X656447Y729233D01*
X656280Y729483D01*
X656197Y729816D01*
X656280Y730108D01*
X656447Y730316D01*
X656697Y730483D01*
X656988Y730525D01*
X657238Y730483D01*
X657488Y730316D01*
X657697Y730066D01*
X657780Y729775D01*
X657697Y729441D01*
X657447Y729150D01*
X657072Y728983D01*
X656655Y728941D01*
X656113Y729025D01*
X655822Y729150D01*
X655530Y729358D01*
X655322Y729650D01*
X655280Y729941D01*
X655363Y730233D01*
X655572Y730441D01*
G01X657780Y732833D02*
X657738Y733125D01*
X657613Y733458D01*
X657405Y733666D01*
X657113Y733750D01*
X656822Y733666D01*
X656572Y733416D01*
X656447Y733041D01*
Y732625D01*
X656363Y732375D01*
X656155Y732166D01*
X655863Y732083D01*
X655572Y732208D01*
X655363Y732500D01*
X655280Y732833D01*
X655363Y733166D01*
X655572Y733458D01*
X655863Y733583D01*
X656155Y733500D01*
X656363Y733291D01*
X656447Y733041D01*
Y732625D01*
X656572Y732250D01*
X656822Y732000D01*
X657113Y731916D01*
X657405Y732000D01*
X657613Y732208D01*
X657738Y732541D01*
X657780Y732833D01*
G01X653280Y721683D02*
Y735683D01*
G01X657784Y738453D02*
X657742Y738120D01*
X657576Y737828D01*
X657326Y737578D01*
X657034Y737411D01*
X656701Y737328D01*
X656367D01*
X656034Y737411D01*
X655742Y737578D01*
X655492Y737828D01*
X655326Y738120D01*
X655284Y738453D01*
X655326Y738786D01*
X655492Y739078D01*
X655742Y739328D01*
X656034Y739495D01*
X656367Y739578D01*
X656701D01*
X657034Y739495D01*
X657326Y739328D01*
X657576Y739078D01*
X657742Y738786D01*
X657784Y738453D01*
G01X657117Y738786D02*
X657784Y739286D01*
G01X655701Y740761D02*
X655451Y741011D01*
X655326Y741303D01*
X655284Y741636D01*
X655367Y742053D01*
X655576Y742345D01*
X655826Y742428D01*
X656076Y742386D01*
X656284Y742220D01*
X656701Y741386D01*
X656992Y741011D01*
X657409Y740761D01*
X657784Y740678D01*
Y742428D01*
G01X657284Y743736D02*
X657576Y743986D01*
X657742Y744320D01*
X657784Y744695D01*
X657742Y745028D01*
X657534Y745361D01*
X657284Y745570D01*
X657034Y745611D01*
X656742Y745528D01*
X656534Y745236D01*
X656451Y744945D01*
Y744570D01*
G01Y744945D02*
X656326Y745195D01*
X656117Y745403D01*
X655867Y745486D01*
X655617Y745403D01*
X655409Y745195D01*
X655284Y744820D01*
X655326Y744445D01*
X655492Y744070D01*
G01X655701Y746961D02*
X655451Y747211D01*
X655326Y747503D01*
X655284Y747836D01*
X655367Y748253D01*
X655576Y748545D01*
X655826Y748628D01*
X656076Y748586D01*
X656284Y748420D01*
X656701Y747586D01*
X656992Y747211D01*
X657409Y746961D01*
X657784Y746878D01*
Y748628D01*
G01X653284Y736603D02*
Y750603D01*
G01X676767Y716792D02*
X676517Y716917D01*
X676225Y717000D01*
X675892D01*
X675517Y716875D01*
X675225Y716667D01*
X675017Y716417D01*
X674850Y716000D01*
X674808Y715625D01*
X674892Y715250D01*
X675017Y715000D01*
X675267Y714750D01*
X675558Y714583D01*
X675850Y714500D01*
X676142D01*
X676433Y714583D01*
X676683Y714708D01*
X676892Y714875D01*
G01X678158Y716583D02*
X678408Y716833D01*
X678700Y716958D01*
X679033Y717000D01*
X679450Y716917D01*
X679742Y716708D01*
X679825Y716458D01*
X679783Y716208D01*
X679617Y716000D01*
X678783Y715583D01*
X678408Y715292D01*
X678158Y714875D01*
X678075Y714500D01*
X679825D01*
G01X681258Y715542D02*
X681550Y715833D01*
X681800Y716000D01*
X682133Y716083D01*
X682425Y716000D01*
X682633Y715833D01*
X682800Y715583D01*
X682842Y715292D01*
X682800Y715042D01*
X682633Y714792D01*
X682383Y714583D01*
X682092Y714500D01*
X681758Y714583D01*
X681467Y714833D01*
X681300Y715208D01*
X681258Y715625D01*
X681342Y716167D01*
X681467Y716458D01*
X681675Y716750D01*
X681967Y716958D01*
X682258Y717000D01*
X682550Y716917D01*
X682758Y716708D01*
G01X684233Y714875D02*
X684483Y714667D01*
X684775Y714542D01*
X685150Y714500D01*
X685525Y714583D01*
X685817Y714750D01*
X686025Y715042D01*
X686067Y715375D01*
X685983Y715708D01*
X685775Y715917D01*
X685483Y716083D01*
X685192Y716125D01*
X684900Y716083D01*
X684525Y715917D01*
X684650Y717000D01*
X685775D01*
G01X694767Y718709D02*
X694517Y718834D01*
X694225Y718917D01*
X693892D01*
X693517Y718792D01*
X693225Y718584D01*
X693017Y718334D01*
X692850Y717917D01*
X692808Y717542D01*
X692892Y717167D01*
X693017Y716917D01*
X693267Y716667D01*
X693558Y716500D01*
X693850Y716417D01*
X694142D01*
X694433Y716500D01*
X694683Y716625D01*
X694892Y716792D01*
G01X696158Y718500D02*
X696408Y718750D01*
X696700Y718875D01*
X697033Y718917D01*
X697450Y718834D01*
X697742Y718625D01*
X697825Y718375D01*
X697783Y718125D01*
X697617Y717917D01*
X696783Y717500D01*
X696408Y717209D01*
X696158Y716792D01*
X696075Y716417D01*
X697825D01*
G01X699258Y717459D02*
X699550Y717750D01*
X699800Y717917D01*
X700133Y718000D01*
X700425Y717917D01*
X700633Y717750D01*
X700800Y717500D01*
X700842Y717209D01*
X700800Y716959D01*
X700633Y716709D01*
X700383Y716500D01*
X700092Y716417D01*
X699758Y716500D01*
X699467Y716750D01*
X699300Y717125D01*
X699258Y717542D01*
X699342Y718084D01*
X699467Y718375D01*
X699675Y718667D01*
X699967Y718875D01*
X700258Y718917D01*
X700550Y718834D01*
X700758Y718625D01*
G01X702358Y718500D02*
X702608Y718750D01*
X702900Y718875D01*
X703233Y718917D01*
X703650Y718834D01*
X703942Y718625D01*
X704025Y718375D01*
X703983Y718125D01*
X703817Y717917D01*
X702983Y717500D01*
X702608Y717209D01*
X702358Y716792D01*
X702275Y716417D01*
X704025D01*
G01X691200Y696917D02*
X696700D01*
G01X694767Y723292D02*
X694517Y723417D01*
X694225Y723500D01*
X693892D01*
X693517Y723375D01*
X693225Y723167D01*
X693017Y722917D01*
X692850Y722500D01*
X692808Y722125D01*
X692892Y721750D01*
X693017Y721500D01*
X693267Y721250D01*
X693558Y721083D01*
X693850Y721000D01*
X694142D01*
X694433Y721083D01*
X694683Y721208D01*
X694892Y721375D01*
G01X696158Y723083D02*
X696408Y723333D01*
X696700Y723458D01*
X697033Y723500D01*
X697450Y723417D01*
X697742Y723208D01*
X697825Y722958D01*
X697783Y722708D01*
X697617Y722500D01*
X696783Y722083D01*
X696408Y721792D01*
X696158Y721375D01*
X696075Y721000D01*
X697825D01*
G01X699258Y722042D02*
X699550Y722333D01*
X699800Y722500D01*
X700133Y722583D01*
X700425Y722500D01*
X700633Y722333D01*
X700800Y722083D01*
X700842Y721792D01*
X700800Y721542D01*
X700633Y721292D01*
X700383Y721083D01*
X700092Y721000D01*
X699758Y721083D01*
X699467Y721333D01*
X699300Y721708D01*
X699258Y722125D01*
X699342Y722667D01*
X699467Y722958D01*
X699675Y723250D01*
X699967Y723458D01*
X700258Y723500D01*
X700550Y723417D01*
X700758Y723208D01*
G01X703150Y721000D02*
Y723500D01*
X702650Y723000D01*
G01Y721000D02*
X703650D01*
G01X701753Y818544D02*
X699253D01*
Y820128D01*
G01X700461Y819544D02*
Y818544D01*
G01X699253Y821603D02*
X701753D01*
Y823269D01*
G01Y826369D02*
Y824703D01*
X699253D01*
Y826369D01*
G01X700461Y825703D02*
Y824703D01*
G01X701753Y827719D02*
X699253D01*
Y828553D01*
X699378Y828886D01*
X699545Y829136D01*
X699795Y829344D01*
X700086Y829511D01*
X700503Y829553D01*
X700920Y829511D01*
X701211Y829344D01*
X701461Y829136D01*
X701628Y828886D01*
X701753Y828553D01*
Y827719D01*
G01X700711Y830944D02*
X700420Y831236D01*
X700253Y831486D01*
X700170Y831819D01*
X700253Y832111D01*
X700420Y832319D01*
X700670Y832486D01*
X700961Y832528D01*
X701211Y832486D01*
X701461Y832319D01*
X701670Y832069D01*
X701753Y831778D01*
X701670Y831444D01*
X701420Y831153D01*
X701045Y830986D01*
X700628Y830944D01*
X700086Y831028D01*
X699795Y831153D01*
X699503Y831361D01*
X699295Y831653D01*
X699253Y831944D01*
X699336Y832236D01*
X699545Y832444D01*
G01X686742Y818809D02*
Y830009D01*
X695542D01*
Y818809D01*
X686742D01*
G01X701670Y947941D02*
X699170D01*
Y948982D01*
X699295Y949316D01*
X699462Y949524D01*
X699795Y949607D01*
X700128Y949524D01*
X700337Y949274D01*
X700462Y948982D01*
Y947941D01*
G01Y948982D02*
X701670Y949607D01*
G01X699587Y951082D02*
X699337Y951332D01*
X699212Y951624D01*
X699170Y951957D01*
X699253Y952374D01*
X699462Y952666D01*
X699712Y952749D01*
X699962Y952707D01*
X700170Y952541D01*
X700587Y951707D01*
X700878Y951332D01*
X701295Y951082D01*
X701670Y950999D01*
Y952749D01*
G01X699587Y954182D02*
X699337Y954432D01*
X699212Y954724D01*
X699170Y955057D01*
X699253Y955474D01*
X699462Y955766D01*
X699712Y955849D01*
X699962Y955807D01*
X700170Y955641D01*
X700587Y954807D01*
X700878Y954432D01*
X701295Y954182D01*
X701670Y954099D01*
Y955849D01*
G01Y957991D02*
X701128Y958074D01*
X700670Y958199D01*
X700253Y958366D01*
X699795Y958574D01*
X699170Y958907D01*
Y957241D01*
G01X682307Y946758D02*
X679807D01*
Y947799D01*
X679932Y948133D01*
X680099Y948341D01*
X680432Y948424D01*
X680765Y948341D01*
X680974Y948091D01*
X681099Y947799D01*
Y946758D01*
G01Y947799D02*
X682307Y948424D01*
G01X680224Y949899D02*
X679974Y950149D01*
X679849Y950441D01*
X679807Y950774D01*
X679890Y951191D01*
X680099Y951483D01*
X680349Y951566D01*
X680599Y951524D01*
X680807Y951358D01*
X681224Y950524D01*
X681515Y950149D01*
X681932Y949899D01*
X682307Y949816D01*
Y951566D01*
G01X680224Y952999D02*
X679974Y953249D01*
X679849Y953541D01*
X679807Y953874D01*
X679890Y954291D01*
X680099Y954583D01*
X680349Y954666D01*
X680599Y954624D01*
X680807Y954458D01*
X681224Y953624D01*
X681515Y953249D01*
X681932Y952999D01*
X682307Y952916D01*
Y954666D01*
G01X681807Y955974D02*
X682099Y956224D01*
X682265Y956558D01*
X682307Y956933D01*
X682265Y957266D01*
X682057Y957599D01*
X681807Y957808D01*
X681557Y957849D01*
X681265Y957766D01*
X681057Y957474D01*
X680974Y957183D01*
Y956808D01*
G01Y957183D02*
X680849Y957433D01*
X680640Y957641D01*
X680390Y957724D01*
X680140Y957641D01*
X679932Y957433D01*
X679807Y957058D01*
X679849Y956683D01*
X680015Y956308D01*
G01X694900Y1069017D02*
X692400D01*
Y1070058D01*
X692525Y1070392D01*
X692692Y1070600D01*
X693025Y1070683D01*
X693358Y1070600D01*
X693567Y1070350D01*
X693692Y1070058D01*
Y1069017D01*
G01Y1070058D02*
X694900Y1070683D01*
G01X692817Y1072158D02*
X692567Y1072408D01*
X692442Y1072700D01*
X692400Y1073033D01*
X692483Y1073450D01*
X692692Y1073742D01*
X692942Y1073825D01*
X693192Y1073783D01*
X693400Y1073617D01*
X693817Y1072783D01*
X694108Y1072408D01*
X694525Y1072158D01*
X694900Y1072075D01*
Y1073825D01*
G01X693858Y1075258D02*
X693567Y1075550D01*
X693400Y1075800D01*
X693317Y1076133D01*
X693400Y1076425D01*
X693567Y1076633D01*
X693817Y1076800D01*
X694108Y1076842D01*
X694358Y1076800D01*
X694608Y1076633D01*
X694817Y1076383D01*
X694900Y1076092D01*
X694817Y1075758D01*
X694567Y1075467D01*
X694192Y1075300D01*
X693775Y1075258D01*
X693233Y1075342D01*
X692942Y1075467D01*
X692650Y1075675D01*
X692442Y1075967D01*
X692400Y1076258D01*
X692483Y1076550D01*
X692692Y1076758D01*
G01X692817Y1078358D02*
X692567Y1078608D01*
X692442Y1078900D01*
X692400Y1079233D01*
X692483Y1079650D01*
X692692Y1079942D01*
X692942Y1080025D01*
X693192Y1079983D01*
X693400Y1079817D01*
X693817Y1078983D01*
X694108Y1078608D01*
X694525Y1078358D01*
X694900Y1078275D01*
Y1080025D01*
G01X695900Y1088873D02*
X691900D01*
Y1081473D01*
G01X698400Y1078500D02*
X698067Y1078542D01*
X697775Y1078708D01*
X697525Y1078958D01*
X697358Y1079250D01*
X697275Y1079583D01*
Y1079917D01*
X697358Y1080250D01*
X697525Y1080542D01*
X697775Y1080792D01*
X698067Y1080958D01*
X698400Y1081000D01*
X698733Y1080958D01*
X699025Y1080792D01*
X699275Y1080542D01*
X699442Y1080250D01*
X699525Y1079917D01*
Y1079583D01*
X699442Y1079250D01*
X699275Y1078958D01*
X699025Y1078708D01*
X698733Y1078542D01*
X698400Y1078500D01*
G01X698733Y1079167D02*
X699233Y1078500D01*
G01X700583Y1079000D02*
X700833Y1078708D01*
X701167Y1078542D01*
X701542Y1078500D01*
X701875Y1078542D01*
X702208Y1078750D01*
X702417Y1079000D01*
X702458Y1079250D01*
X702375Y1079542D01*
X702083Y1079750D01*
X701792Y1079833D01*
X701417D01*
G01X701792D02*
X702042Y1079958D01*
X702250Y1080167D01*
X702333Y1080417D01*
X702250Y1080667D01*
X702042Y1080875D01*
X701667Y1081000D01*
X701292Y1080958D01*
X700917Y1080792D01*
G01X704600Y1078500D02*
Y1081000D01*
X704100Y1080500D01*
G01Y1078500D02*
X705100D01*
G01X690000Y1075033D02*
X687500D01*
Y1075867D01*
X687625Y1076200D01*
X687792Y1076450D01*
X688042Y1076658D01*
X688333Y1076825D01*
X688750Y1076867D01*
X689167Y1076825D01*
X689458Y1076658D01*
X689708Y1076450D01*
X689875Y1076200D01*
X690000Y1075867D01*
Y1075033D01*
G01X689625Y1078133D02*
X689833Y1078383D01*
X689958Y1078675D01*
X690000Y1079050D01*
X689917Y1079425D01*
X689750Y1079717D01*
X689458Y1079925D01*
X689125Y1079967D01*
X688792Y1079883D01*
X688583Y1079675D01*
X688417Y1079383D01*
X688375Y1079092D01*
X688417Y1078800D01*
X688583Y1078425D01*
X687500Y1078550D01*
Y1079675D01*
G01X691000Y1097673D02*
Y1081573D01*
G01X684000D02*
Y1097673D01*
G01X691000Y1081573D02*
X684000D01*
G01X666017Y1098773D02*
Y1101273D01*
X667058D01*
X667392Y1101148D01*
X667600Y1100981D01*
X667683Y1100648D01*
X667600Y1100315D01*
X667350Y1100106D01*
X667058Y1099981D01*
X666017D01*
G01X667058D02*
X667683Y1098773D01*
G01X669158Y1100856D02*
X669408Y1101106D01*
X669700Y1101231D01*
X670033Y1101273D01*
X670450Y1101190D01*
X670742Y1100981D01*
X670825Y1100731D01*
X670783Y1100481D01*
X670617Y1100273D01*
X669783Y1099856D01*
X669408Y1099565D01*
X669158Y1099148D01*
X669075Y1098773D01*
X670825D01*
G01X672133Y1099148D02*
X672383Y1098940D01*
X672675Y1098815D01*
X673050Y1098773D01*
X673425Y1098856D01*
X673717Y1099023D01*
X673925Y1099315D01*
X673967Y1099648D01*
X673883Y1099981D01*
X673675Y1100190D01*
X673383Y1100356D01*
X673092Y1100398D01*
X672800Y1100356D01*
X672425Y1100190D01*
X672550Y1101273D01*
X673675D01*
G01X675358Y1100856D02*
X675608Y1101106D01*
X675900Y1101231D01*
X676233Y1101273D01*
X676650Y1101190D01*
X676942Y1100981D01*
X677025Y1100731D01*
X676983Y1100481D01*
X676817Y1100273D01*
X675983Y1099856D01*
X675608Y1099565D01*
X675358Y1099148D01*
X675275Y1098773D01*
X677025D01*
G01X683300Y1108273D02*
Y1104273D01*
X690700D01*
G01X669417Y1087427D02*
Y1089927D01*
X670458D01*
X670792Y1089802D01*
X671000Y1089635D01*
X671083Y1089302D01*
X671000Y1088969D01*
X670750Y1088760D01*
X670458Y1088635D01*
X669417D01*
G01X670458D02*
X671083Y1087427D01*
G01X672558Y1089510D02*
X672808Y1089760D01*
X673100Y1089885D01*
X673433Y1089927D01*
X673850Y1089844D01*
X674142Y1089635D01*
X674225Y1089385D01*
X674183Y1089135D01*
X674017Y1088927D01*
X673183Y1088510D01*
X672808Y1088219D01*
X672558Y1087802D01*
X672475Y1087427D01*
X674225D01*
G01X675533Y1087802D02*
X675783Y1087594D01*
X676075Y1087469D01*
X676450Y1087427D01*
X676825Y1087510D01*
X677117Y1087677D01*
X677325Y1087969D01*
X677367Y1088302D01*
X677283Y1088635D01*
X677075Y1088844D01*
X676783Y1089010D01*
X676492Y1089052D01*
X676200Y1089010D01*
X675825Y1088844D01*
X675950Y1089927D01*
X677075D01*
G01X678842Y1087719D02*
X679133Y1087510D01*
X679467Y1087427D01*
X679800Y1087510D01*
X680092Y1087760D01*
X680300Y1088135D01*
X680383Y1088510D01*
Y1088969D01*
X680300Y1089344D01*
X680092Y1089677D01*
X679842Y1089844D01*
X679550Y1089927D01*
X679217Y1089844D01*
X678967Y1089677D01*
X678800Y1089427D01*
X678717Y1089094D01*
X678800Y1088802D01*
X679008Y1088510D01*
X679258Y1088344D01*
X679550Y1088302D01*
X679883Y1088385D01*
X680133Y1088594D01*
X680383Y1088969D01*
G01X675200Y1095100D02*
Y1091100D01*
X682600D01*
G01X656317Y1122473D02*
Y1124973D01*
X657358D01*
X657692Y1124848D01*
X657900Y1124681D01*
X657983Y1124348D01*
X657900Y1124015D01*
X657650Y1123806D01*
X657358Y1123681D01*
X656317D01*
G01X657358D02*
X657983Y1122473D01*
G01X659458Y1124556D02*
X659708Y1124806D01*
X660000Y1124931D01*
X660333Y1124973D01*
X660750Y1124890D01*
X661042Y1124681D01*
X661125Y1124431D01*
X661083Y1124181D01*
X660917Y1123973D01*
X660083Y1123556D01*
X659708Y1123265D01*
X659458Y1122848D01*
X659375Y1122473D01*
X661125D01*
G01X662558Y1123515D02*
X662850Y1123806D01*
X663100Y1123973D01*
X663433Y1124056D01*
X663725Y1123973D01*
X663933Y1123806D01*
X664100Y1123556D01*
X664142Y1123265D01*
X664100Y1123015D01*
X663933Y1122765D01*
X663683Y1122556D01*
X663392Y1122473D01*
X663058Y1122556D01*
X662767Y1122806D01*
X662600Y1123181D01*
X662558Y1123598D01*
X662642Y1124140D01*
X662767Y1124431D01*
X662975Y1124723D01*
X663267Y1124931D01*
X663558Y1124973D01*
X663850Y1124890D01*
X664058Y1124681D01*
G01X666450Y1124973D02*
X666117Y1124890D01*
X665867Y1124681D01*
X665700Y1124431D01*
X665575Y1124098D01*
X665533Y1123723D01*
X665575Y1123348D01*
X665700Y1123015D01*
X665867Y1122765D01*
X666117Y1122556D01*
X666450Y1122473D01*
X666783Y1122556D01*
X667033Y1122765D01*
X667200Y1123015D01*
X667325Y1123348D01*
X667367Y1123723D01*
X667325Y1124098D01*
X667200Y1124431D01*
X667033Y1124681D01*
X666783Y1124890D01*
X666450Y1124973D01*
G01X689000Y1117973D02*
Y1121973D01*
X681600D01*
G01X663834Y1091517D02*
X661334D01*
Y1092558D01*
X661459Y1092892D01*
X661626Y1093100D01*
X661959Y1093183D01*
X662292Y1093100D01*
X662501Y1092850D01*
X662626Y1092558D01*
Y1091517D01*
G01Y1092558D02*
X663834Y1093183D01*
G01X661751Y1094658D02*
X661501Y1094908D01*
X661376Y1095200D01*
X661334Y1095533D01*
X661417Y1095950D01*
X661626Y1096242D01*
X661876Y1096325D01*
X662126Y1096283D01*
X662334Y1096117D01*
X662751Y1095283D01*
X663042Y1094908D01*
X663459Y1094658D01*
X663834Y1094575D01*
Y1096325D01*
G01X662792Y1097758D02*
X662501Y1098050D01*
X662334Y1098300D01*
X662251Y1098633D01*
X662334Y1098925D01*
X662501Y1099133D01*
X662751Y1099300D01*
X663042Y1099342D01*
X663292Y1099300D01*
X663542Y1099133D01*
X663751Y1098883D01*
X663834Y1098592D01*
X663751Y1098258D01*
X663501Y1097967D01*
X663126Y1097800D01*
X662709Y1097758D01*
X662167Y1097842D01*
X661876Y1097967D01*
X661584Y1098175D01*
X661376Y1098467D01*
X661334Y1098758D01*
X661417Y1099050D01*
X661626Y1099258D01*
G01X663834Y1101650D02*
X661334D01*
X661834Y1101150D01*
G01X663834D02*
Y1102150D01*
G01X678400Y1095600D02*
X682400D01*
Y1103000D01*
G01X707200Y1103373D02*
X695800D01*
G01Y1089973D02*
X707200D01*
G01X695800Y1103373D02*
Y1089973D01*
G01X684000Y1097673D02*
X691000D01*
G01X713300Y1128773D02*
X694100D01*
Y1117573D01*
X713300D01*
Y1128773D01*
X712900D01*
G01X658067Y1128865D02*
X657817Y1128990D01*
X657525Y1129073D01*
X657192D01*
X656817Y1128948D01*
X656525Y1128740D01*
X656317Y1128490D01*
X656150Y1128073D01*
X656108Y1127698D01*
X656192Y1127323D01*
X656317Y1127073D01*
X656567Y1126823D01*
X656858Y1126656D01*
X657150Y1126573D01*
X657442D01*
X657733Y1126656D01*
X657983Y1126781D01*
X658192Y1126948D01*
G01X660250Y1126573D02*
Y1129073D01*
X659750Y1128573D01*
G01Y1126573D02*
X660750D01*
G01X663350D02*
Y1129073D01*
X662850Y1128573D01*
G01Y1126573D02*
X663850D01*
G01X666950D02*
Y1129073D01*
X665408Y1127281D01*
X667492D01*
G01X667767Y1105165D02*
X667517Y1105290D01*
X667225Y1105373D01*
X666892D01*
X666517Y1105248D01*
X666225Y1105040D01*
X666017Y1104790D01*
X665850Y1104373D01*
X665808Y1103998D01*
X665892Y1103623D01*
X666017Y1103373D01*
X666267Y1103123D01*
X666558Y1102956D01*
X666850Y1102873D01*
X667142D01*
X667433Y1102956D01*
X667683Y1103081D01*
X667892Y1103248D01*
G01X669950Y1102873D02*
Y1105373D01*
X669450Y1104873D01*
G01Y1102873D02*
X670450D01*
G01X673050D02*
Y1105373D01*
X672550Y1104873D01*
G01Y1102873D02*
X673550D01*
G01X675233Y1103373D02*
X675483Y1103081D01*
X675817Y1102915D01*
X676192Y1102873D01*
X676525Y1102915D01*
X676858Y1103123D01*
X677067Y1103373D01*
X677108Y1103623D01*
X677025Y1103915D01*
X676733Y1104123D01*
X676442Y1104206D01*
X676067D01*
G01X676442D02*
X676692Y1104331D01*
X676900Y1104540D01*
X676983Y1104790D01*
X676900Y1105040D01*
X676692Y1105248D01*
X676317Y1105373D01*
X675942Y1105331D01*
X675567Y1105165D01*
G01X692517Y1176000D02*
Y1178500D01*
X693558D01*
X693892Y1178375D01*
X694100Y1178208D01*
X694183Y1177875D01*
X694100Y1177542D01*
X693850Y1177333D01*
X693558Y1177208D01*
X692517D01*
G01X693558D02*
X694183Y1176000D01*
G01X695658Y1178083D02*
X695908Y1178333D01*
X696200Y1178458D01*
X696533Y1178500D01*
X696950Y1178417D01*
X697242Y1178208D01*
X697325Y1177958D01*
X697283Y1177708D01*
X697117Y1177500D01*
X696283Y1177083D01*
X695908Y1176792D01*
X695658Y1176375D01*
X695575Y1176000D01*
X697325D01*
G01X700050D02*
Y1178500D01*
X698508Y1176708D01*
X700592D01*
G01X702650Y1176000D02*
X702942Y1176042D01*
X703275Y1176167D01*
X703483Y1176375D01*
X703567Y1176667D01*
X703483Y1176958D01*
X703233Y1177208D01*
X702858Y1177333D01*
X702442D01*
X702192Y1177417D01*
X701983Y1177625D01*
X701900Y1177917D01*
X702025Y1178208D01*
X702317Y1178417D01*
X702650Y1178500D01*
X702983Y1178417D01*
X703275Y1178208D01*
X703400Y1177917D01*
X703317Y1177625D01*
X703108Y1177417D01*
X702858Y1177333D01*
X702442D01*
X702067Y1177208D01*
X701817Y1176958D01*
X701733Y1176667D01*
X701817Y1176375D01*
X702025Y1176167D01*
X702358Y1176042D01*
X702650Y1176000D01*
G01X686700Y1156173D02*
Y1164173D01*
X704300D01*
Y1156173D01*
X686700D01*
G01X657500Y1171850D02*
X657458Y1171517D01*
X657292Y1171225D01*
X657042Y1170975D01*
X656750Y1170808D01*
X656417Y1170725D01*
X656083D01*
X655750Y1170808D01*
X655458Y1170975D01*
X655208Y1171225D01*
X655042Y1171517D01*
X655000Y1171850D01*
X655042Y1172183D01*
X655208Y1172475D01*
X655458Y1172725D01*
X655750Y1172892D01*
X656083Y1172975D01*
X656417D01*
X656750Y1172892D01*
X657042Y1172725D01*
X657292Y1172475D01*
X657458Y1172183D01*
X657500Y1171850D01*
G01X656833Y1172183D02*
X657500Y1172683D01*
G01X655417Y1174158D02*
X655167Y1174408D01*
X655042Y1174700D01*
X655000Y1175033D01*
X655083Y1175450D01*
X655292Y1175742D01*
X655542Y1175825D01*
X655792Y1175783D01*
X656000Y1175617D01*
X656417Y1174783D01*
X656708Y1174408D01*
X657125Y1174158D01*
X657500Y1174075D01*
Y1175825D01*
G01X657208Y1177342D02*
X657417Y1177633D01*
X657500Y1177967D01*
X657417Y1178300D01*
X657167Y1178592D01*
X656792Y1178800D01*
X656417Y1178883D01*
X655958D01*
X655583Y1178800D01*
X655250Y1178592D01*
X655083Y1178342D01*
X655000Y1178050D01*
X655083Y1177717D01*
X655250Y1177467D01*
X655500Y1177300D01*
X655833Y1177217D01*
X656125Y1177300D01*
X656417Y1177508D01*
X656583Y1177758D01*
X656625Y1178050D01*
X656542Y1178383D01*
X656333Y1178633D01*
X655958Y1178883D01*
G01X655417Y1180358D02*
X655167Y1180608D01*
X655042Y1180900D01*
X655000Y1181233D01*
X655083Y1181650D01*
X655292Y1181942D01*
X655542Y1182025D01*
X655792Y1181983D01*
X656000Y1181817D01*
X656417Y1180983D01*
X656708Y1180608D01*
X657125Y1180358D01*
X657500Y1180275D01*
Y1182025D01*
G01X653364Y1169159D02*
Y1183159D01*
G01X676767Y1171465D02*
X676517Y1171590D01*
X676225Y1171673D01*
X675892D01*
X675517Y1171548D01*
X675225Y1171340D01*
X675017Y1171090D01*
X674850Y1170673D01*
X674808Y1170298D01*
X674892Y1169923D01*
X675017Y1169673D01*
X675267Y1169423D01*
X675558Y1169256D01*
X675850Y1169173D01*
X676142D01*
X676433Y1169256D01*
X676683Y1169381D01*
X676892Y1169548D01*
G01X678950Y1169173D02*
Y1171673D01*
X678450Y1171173D01*
G01Y1169173D02*
X679450D01*
G01X682050D02*
Y1171673D01*
X681550Y1171173D01*
G01Y1169173D02*
X682550D01*
G01X685150Y1171673D02*
X684817Y1171590D01*
X684567Y1171381D01*
X684400Y1171131D01*
X684275Y1170798D01*
X684233Y1170423D01*
X684275Y1170048D01*
X684400Y1169715D01*
X684567Y1169465D01*
X684817Y1169256D01*
X685150Y1169173D01*
X685483Y1169256D01*
X685733Y1169465D01*
X685900Y1169715D01*
X686025Y1170048D01*
X686067Y1170423D01*
X686025Y1170798D01*
X685900Y1171131D01*
X685733Y1171381D01*
X685483Y1171590D01*
X685150Y1171673D01*
G01X693767Y1170465D02*
X693517Y1170590D01*
X693225Y1170673D01*
X692892D01*
X692517Y1170548D01*
X692225Y1170340D01*
X692017Y1170090D01*
X691850Y1169673D01*
X691808Y1169298D01*
X691892Y1168923D01*
X692017Y1168673D01*
X692267Y1168423D01*
X692558Y1168256D01*
X692850Y1168173D01*
X693142D01*
X693433Y1168256D01*
X693683Y1168381D01*
X693892Y1168548D01*
G01X695950Y1168173D02*
Y1170673D01*
X695450Y1170173D01*
G01Y1168173D02*
X696450D01*
G01X699050Y1170673D02*
X698717Y1170590D01*
X698467Y1170381D01*
X698300Y1170131D01*
X698175Y1169798D01*
X698133Y1169423D01*
X698175Y1169048D01*
X698300Y1168715D01*
X698467Y1168465D01*
X698717Y1168256D01*
X699050Y1168173D01*
X699383Y1168256D01*
X699633Y1168465D01*
X699800Y1168715D01*
X699925Y1169048D01*
X699967Y1169423D01*
X699925Y1169798D01*
X699800Y1170131D01*
X699633Y1170381D01*
X699383Y1170590D01*
X699050Y1170673D01*
G01X701358Y1169215D02*
X701650Y1169506D01*
X701900Y1169673D01*
X702233Y1169756D01*
X702525Y1169673D01*
X702733Y1169506D01*
X702900Y1169256D01*
X702942Y1168965D01*
X702900Y1168715D01*
X702733Y1168465D01*
X702483Y1168256D01*
X702192Y1168173D01*
X701858Y1168256D01*
X701567Y1168506D01*
X701400Y1168881D01*
X701358Y1169298D01*
X701442Y1169840D01*
X701567Y1170131D01*
X701775Y1170423D01*
X702067Y1170631D01*
X702358Y1170673D01*
X702650Y1170590D01*
X702858Y1170381D01*
G01X691200Y1149673D02*
X696700D01*
G01X691200Y1141673D02*
Y1149673D01*
G01X696700Y1141673D02*
X691200D01*
G01X667000Y1137900D02*
X666958Y1137567D01*
X666792Y1137275D01*
X666542Y1137025D01*
X666250Y1136858D01*
X665917Y1136775D01*
X665583D01*
X665250Y1136858D01*
X664958Y1137025D01*
X664708Y1137275D01*
X664542Y1137567D01*
X664500Y1137900D01*
X664542Y1138233D01*
X664708Y1138525D01*
X664958Y1138775D01*
X665250Y1138942D01*
X665583Y1139025D01*
X665917D01*
X666250Y1138942D01*
X666542Y1138775D01*
X666792Y1138525D01*
X666958Y1138233D01*
X667000Y1137900D01*
G01X666333Y1138233D02*
X667000Y1138733D01*
G01X666500Y1140083D02*
X666792Y1140333D01*
X666958Y1140667D01*
X667000Y1141042D01*
X666958Y1141375D01*
X666750Y1141708D01*
X666500Y1141917D01*
X666250Y1141958D01*
X665958Y1141875D01*
X665750Y1141583D01*
X665667Y1141292D01*
Y1140917D01*
G01Y1141292D02*
X665542Y1141542D01*
X665333Y1141750D01*
X665083Y1141833D01*
X664833Y1141750D01*
X664625Y1141542D01*
X664500Y1141167D01*
X664542Y1140792D01*
X664708Y1140417D01*
G01X664917Y1143308D02*
X664667Y1143558D01*
X664542Y1143850D01*
X664500Y1144183D01*
X664583Y1144600D01*
X664792Y1144892D01*
X665042Y1144975D01*
X665292Y1144933D01*
X665500Y1144767D01*
X665917Y1143933D01*
X666208Y1143558D01*
X666625Y1143308D01*
X667000Y1143225D01*
Y1144975D01*
G01X668800Y1143173D02*
X670900Y1141373D01*
X668800Y1139173D01*
G01X668700Y1135573D02*
X687900D01*
Y1146773D01*
X668700D01*
Y1135573D01*
X669100D01*
G01X693767Y1174292D02*
X693517Y1174417D01*
X693225Y1174500D01*
X692892D01*
X692517Y1174375D01*
X692225Y1174167D01*
X692017Y1173917D01*
X691850Y1173500D01*
X691808Y1173125D01*
X691892Y1172750D01*
X692017Y1172500D01*
X692267Y1172250D01*
X692558Y1172083D01*
X692850Y1172000D01*
X693142D01*
X693433Y1172083D01*
X693683Y1172208D01*
X693892Y1172375D01*
G01X695950Y1172000D02*
Y1174500D01*
X695450Y1174000D01*
G01Y1172000D02*
X696450D01*
G01X699050Y1174500D02*
X698717Y1174417D01*
X698467Y1174208D01*
X698300Y1173958D01*
X698175Y1173625D01*
X698133Y1173250D01*
X698175Y1172875D01*
X698300Y1172542D01*
X698467Y1172292D01*
X698717Y1172083D01*
X699050Y1172000D01*
X699383Y1172083D01*
X699633Y1172292D01*
X699800Y1172542D01*
X699925Y1172875D01*
X699967Y1173250D01*
X699925Y1173625D01*
X699800Y1173958D01*
X699633Y1174208D01*
X699383Y1174417D01*
X699050Y1174500D01*
G01X701233Y1172375D02*
X701483Y1172167D01*
X701775Y1172042D01*
X702150Y1172000D01*
X702525Y1172083D01*
X702817Y1172250D01*
X703025Y1172542D01*
X703067Y1172875D01*
X702983Y1173208D01*
X702775Y1173417D01*
X702483Y1173583D01*
X702192Y1173625D01*
X701900Y1173583D01*
X701525Y1173417D01*
X701650Y1174500D01*
X702775D01*
G01X654017Y1185000D02*
Y1187500D01*
X655058D01*
X655392Y1187375D01*
X655600Y1187208D01*
X655683Y1186875D01*
X655600Y1186542D01*
X655350Y1186333D01*
X655058Y1186208D01*
X654017D01*
G01X655058D02*
X655683Y1185000D01*
G01X657033Y1185375D02*
X657283Y1185167D01*
X657575Y1185042D01*
X657950Y1185000D01*
X658325Y1185083D01*
X658617Y1185250D01*
X658825Y1185542D01*
X658867Y1185875D01*
X658783Y1186208D01*
X658575Y1186417D01*
X658283Y1186583D01*
X657992Y1186625D01*
X657700Y1186583D01*
X657325Y1186417D01*
X657450Y1187500D01*
X658575D01*
G01X660967Y1185000D02*
X661050Y1185542D01*
X661175Y1186000D01*
X661342Y1186417D01*
X661550Y1186875D01*
X661883Y1187500D01*
X660217D01*
G01X663358Y1187083D02*
X663608Y1187333D01*
X663900Y1187458D01*
X664233Y1187500D01*
X664650Y1187417D01*
X664942Y1187208D01*
X665025Y1186958D01*
X664983Y1186708D01*
X664817Y1186500D01*
X663983Y1186083D01*
X663608Y1185792D01*
X663358Y1185375D01*
X663275Y1185000D01*
X665025D01*
G01X653269Y1189390D02*
Y1203390D01*
G01X702544Y1270811D02*
X700044D01*
Y1271852D01*
X700169Y1272186D01*
X700336Y1272394D01*
X700669Y1272477D01*
X701002Y1272394D01*
X701211Y1272144D01*
X701336Y1271852D01*
Y1270811D01*
G01Y1271852D02*
X702544Y1272477D01*
G01X700044Y1273911D02*
X702544D01*
Y1275577D01*
G01Y1278677D02*
Y1277011D01*
X700044D01*
Y1278677D01*
G01X701252Y1278011D02*
Y1277011D01*
G01X702544Y1280027D02*
X700044D01*
Y1280861D01*
X700169Y1281194D01*
X700336Y1281444D01*
X700586Y1281652D01*
X700877Y1281819D01*
X701294Y1281861D01*
X701711Y1281819D01*
X702002Y1281652D01*
X702252Y1281444D01*
X702419Y1281194D01*
X702544Y1280861D01*
Y1280027D01*
G01X702044Y1283127D02*
X702336Y1283377D01*
X702502Y1283711D01*
X702544Y1284086D01*
X702502Y1284419D01*
X702294Y1284752D01*
X702044Y1284961D01*
X701794Y1285002D01*
X701502Y1284919D01*
X701294Y1284627D01*
X701211Y1284336D01*
Y1283961D01*
G01Y1284336D02*
X701086Y1284586D01*
X700877Y1284794D01*
X700627Y1284877D01*
X700377Y1284794D01*
X700169Y1284586D01*
X700044Y1284211D01*
X700086Y1283836D01*
X700252Y1283461D01*
G01X700044Y1287144D02*
X700127Y1286811D01*
X700336Y1286561D01*
X700586Y1286394D01*
X700919Y1286269D01*
X701294Y1286227D01*
X701669Y1286269D01*
X702002Y1286394D01*
X702252Y1286561D01*
X702461Y1286811D01*
X702544Y1287144D01*
X702461Y1287477D01*
X702252Y1287727D01*
X702002Y1287894D01*
X701669Y1288019D01*
X701294Y1288061D01*
X700919Y1288019D01*
X700586Y1287894D01*
X700336Y1287727D01*
X700127Y1287477D01*
X700044Y1287144D01*
G01X686742Y1271565D02*
Y1282765D01*
X695542D01*
Y1271565D01*
X686742D01*
G01X715187Y221492D02*
X720237D01*
Y320192D01*
X744887D01*
Y135792D01*
X720237D01*
Y194492D01*
X715187D01*
Y221492D01*
G01X707617Y159961D02*
Y162461D01*
X708658D01*
X708992Y162336D01*
X709200Y162169D01*
X709283Y161836D01*
X709200Y161503D01*
X708950Y161294D01*
X708658Y161169D01*
X707617D01*
G01X708658D02*
X709283Y159961D01*
G01X711550D02*
X711842Y160003D01*
X712175Y160128D01*
X712383Y160336D01*
X712467Y160628D01*
X712383Y160919D01*
X712133Y161169D01*
X711758Y161294D01*
X711342D01*
X711092Y161378D01*
X710883Y161586D01*
X710800Y161878D01*
X710925Y162169D01*
X711217Y162378D01*
X711550Y162461D01*
X711883Y162378D01*
X712175Y162169D01*
X712300Y161878D01*
X712217Y161586D01*
X712008Y161378D01*
X711758Y161294D01*
X711342D01*
X710967Y161169D01*
X710717Y160919D01*
X710633Y160628D01*
X710717Y160336D01*
X710925Y160128D01*
X711258Y160003D01*
X711550Y159961D01*
G01X714650Y162461D02*
X714317Y162378D01*
X714067Y162169D01*
X713900Y161919D01*
X713775Y161586D01*
X713733Y161211D01*
X713775Y160836D01*
X713900Y160503D01*
X714067Y160253D01*
X714317Y160044D01*
X714650Y159961D01*
X714983Y160044D01*
X715233Y160253D01*
X715400Y160503D01*
X715525Y160836D01*
X715567Y161211D01*
X715525Y161586D01*
X715400Y161919D01*
X715233Y162169D01*
X714983Y162378D01*
X714650Y162461D01*
G01X717750Y159961D02*
X718042Y160003D01*
X718375Y160128D01*
X718583Y160336D01*
X718667Y160628D01*
X718583Y160919D01*
X718333Y161169D01*
X717958Y161294D01*
X717542D01*
X717292Y161378D01*
X717083Y161586D01*
X717000Y161878D01*
X717125Y162169D01*
X717417Y162378D01*
X717750Y162461D01*
X718083Y162378D01*
X718375Y162169D01*
X718500Y161878D01*
X718417Y161586D01*
X718208Y161378D01*
X717958Y161294D01*
X717542D01*
X717167Y161169D01*
X716917Y160919D01*
X716833Y160628D01*
X716917Y160336D01*
X717125Y160128D01*
X717458Y160003D01*
X717750Y159961D01*
G01X707617Y164500D02*
Y167000D01*
X708658D01*
X708992Y166875D01*
X709200Y166708D01*
X709283Y166375D01*
X709200Y166042D01*
X708950Y165833D01*
X708658Y165708D01*
X707617D01*
G01X708658D02*
X709283Y164500D01*
G01X711550D02*
X711842Y164542D01*
X712175Y164667D01*
X712383Y164875D01*
X712467Y165167D01*
X712383Y165458D01*
X712133Y165708D01*
X711758Y165833D01*
X711342D01*
X711092Y165917D01*
X710883Y166125D01*
X710800Y166417D01*
X710925Y166708D01*
X711217Y166917D01*
X711550Y167000D01*
X711883Y166917D01*
X712175Y166708D01*
X712300Y166417D01*
X712217Y166125D01*
X712008Y165917D01*
X711758Y165833D01*
X711342D01*
X710967Y165708D01*
X710717Y165458D01*
X710633Y165167D01*
X710717Y164875D01*
X710925Y164667D01*
X711258Y164542D01*
X711550Y164500D01*
G01X714650Y167000D02*
X714317Y166917D01*
X714067Y166708D01*
X713900Y166458D01*
X713775Y166125D01*
X713733Y165750D01*
X713775Y165375D01*
X713900Y165042D01*
X714067Y164792D01*
X714317Y164583D01*
X714650Y164500D01*
X714983Y164583D01*
X715233Y164792D01*
X715400Y165042D01*
X715525Y165375D01*
X715567Y165750D01*
X715525Y166125D01*
X715400Y166458D01*
X715233Y166708D01*
X714983Y166917D01*
X714650Y167000D01*
G01X716833Y164875D02*
X717083Y164667D01*
X717375Y164542D01*
X717750Y164500D01*
X718125Y164583D01*
X718417Y164750D01*
X718625Y165042D01*
X718667Y165375D01*
X718583Y165708D01*
X718375Y165917D01*
X718083Y166083D01*
X717792Y166125D01*
X717500Y166083D01*
X717125Y165917D01*
X717250Y167000D01*
X718375D01*
G01X715300Y174461D02*
Y178461D01*
X707900D01*
G01X715300Y179161D02*
Y183161D01*
X707900D01*
G01X707617Y168500D02*
Y171000D01*
X708658D01*
X708992Y170875D01*
X709200Y170708D01*
X709283Y170375D01*
X709200Y170042D01*
X708950Y169833D01*
X708658Y169708D01*
X707617D01*
G01X708658D02*
X709283Y168500D01*
G01X711550D02*
X711842Y168542D01*
X712175Y168667D01*
X712383Y168875D01*
X712467Y169167D01*
X712383Y169458D01*
X712133Y169708D01*
X711758Y169833D01*
X711342D01*
X711092Y169917D01*
X710883Y170125D01*
X710800Y170417D01*
X710925Y170708D01*
X711217Y170917D01*
X711550Y171000D01*
X711883Y170917D01*
X712175Y170708D01*
X712300Y170417D01*
X712217Y170125D01*
X712008Y169917D01*
X711758Y169833D01*
X711342D01*
X710967Y169708D01*
X710717Y169458D01*
X710633Y169167D01*
X710717Y168875D01*
X710925Y168667D01*
X711258Y168542D01*
X711550Y168500D01*
G01X714650D02*
Y171000D01*
X714150Y170500D01*
G01Y168500D02*
X715150D01*
G01X717750Y171000D02*
X717417Y170917D01*
X717167Y170708D01*
X717000Y170458D01*
X716875Y170125D01*
X716833Y169750D01*
X716875Y169375D01*
X717000Y169042D01*
X717167Y168792D01*
X717417Y168583D01*
X717750Y168500D01*
X718083Y168583D01*
X718333Y168792D01*
X718500Y169042D01*
X718625Y169375D01*
X718667Y169750D01*
X718625Y170125D01*
X718500Y170458D01*
X718333Y170708D01*
X718083Y170917D01*
X717750Y171000D01*
G01X707900Y193161D02*
Y189161D01*
X715300D01*
G01X754900Y203500D02*
Y207500D01*
X747500D01*
G01X707200Y184461D02*
Y197861D01*
G01X715500Y256517D02*
X713000D01*
Y257558D01*
X713125Y257892D01*
X713292Y258100D01*
X713625Y258183D01*
X713958Y258100D01*
X714167Y257850D01*
X714292Y257558D01*
Y256517D01*
G01Y257558D02*
X715500Y258183D01*
G01Y260367D02*
X714958Y260450D01*
X714500Y260575D01*
X714083Y260742D01*
X713625Y260950D01*
X713000Y261283D01*
Y259617D01*
G01X715208Y262842D02*
X715417Y263133D01*
X715500Y263467D01*
X715417Y263800D01*
X715167Y264092D01*
X714792Y264300D01*
X714417Y264383D01*
X713958D01*
X713583Y264300D01*
X713250Y264092D01*
X713083Y263842D01*
X713000Y263550D01*
X713083Y263217D01*
X713250Y262967D01*
X713500Y262800D01*
X713833Y262717D01*
X714125Y262800D01*
X714417Y263008D01*
X714583Y263258D01*
X714625Y263550D01*
X714542Y263883D01*
X714333Y264133D01*
X713958Y264383D01*
G01X714458Y265858D02*
X714167Y266150D01*
X714000Y266400D01*
X713917Y266733D01*
X714000Y267025D01*
X714167Y267233D01*
X714417Y267400D01*
X714708Y267442D01*
X714958Y267400D01*
X715208Y267233D01*
X715417Y266983D01*
X715500Y266692D01*
X715417Y266358D01*
X715167Y266067D01*
X714792Y265900D01*
X714375Y265858D01*
X713833Y265942D01*
X713542Y266067D01*
X713250Y266275D01*
X713042Y266567D01*
X713000Y266858D01*
X713083Y267150D01*
X713292Y267358D01*
G01X710500Y253961D02*
X718500D01*
Y236361D01*
X710500D01*
Y253961D01*
G01X708800Y236161D02*
X703300D01*
G01X708800Y244161D02*
Y236161D01*
G01X703300Y244161D02*
X708800D01*
G01X717500Y224850D02*
X717458Y224517D01*
X717292Y224225D01*
X717042Y223975D01*
X716750Y223808D01*
X716417Y223725D01*
X716083D01*
X715750Y223808D01*
X715458Y223975D01*
X715208Y224225D01*
X715042Y224517D01*
X715000Y224850D01*
X715042Y225183D01*
X715208Y225475D01*
X715458Y225725D01*
X715750Y225892D01*
X716083Y225975D01*
X716417D01*
X716750Y225892D01*
X717042Y225725D01*
X717292Y225475D01*
X717458Y225183D01*
X717500Y224850D01*
G01X716833Y225183D02*
X717500Y225683D01*
G01Y227950D02*
X715000D01*
X715500Y227450D01*
G01X717500D02*
Y228450D01*
G01Y230967D02*
X716958Y231050D01*
X716500Y231175D01*
X716083Y231342D01*
X715625Y231550D01*
X715000Y231883D01*
Y230217D01*
G01X717500Y234650D02*
X715000D01*
X716792Y233108D01*
Y235192D01*
G01X713200Y215661D02*
X711100Y217461D01*
X713200Y219661D01*
G01X708208Y281267D02*
X708083Y281017D01*
X708000Y280725D01*
Y280392D01*
X708125Y280017D01*
X708333Y279725D01*
X708583Y279517D01*
X709000Y279350D01*
X709375Y279308D01*
X709750Y279392D01*
X710000Y279517D01*
X710250Y279767D01*
X710417Y280058D01*
X710500Y280350D01*
Y280642D01*
X710417Y280933D01*
X710292Y281183D01*
X710125Y281392D01*
G01X710500Y283950D02*
X708000D01*
X709792Y282408D01*
Y284492D01*
G01X708417Y285758D02*
X708167Y286008D01*
X708042Y286300D01*
X708000Y286633D01*
X708083Y287050D01*
X708292Y287342D01*
X708542Y287425D01*
X708792Y287383D01*
X709000Y287217D01*
X709417Y286383D01*
X709708Y286008D01*
X710125Y285758D01*
X710500Y285675D01*
Y287425D01*
G01Y289650D02*
X708000D01*
X708500Y289150D01*
G01X710500D02*
Y290150D01*
G01X747834Y276300D02*
X750334D01*
G01X747834Y275342D02*
Y277258D01*
G01X750334Y278567D02*
X747834D01*
Y279567D01*
X747959Y279900D01*
X748251Y280150D01*
X748584Y280233D01*
X748917Y280150D01*
X749167Y279942D01*
X749292Y279567D01*
Y278567D01*
G01X750334Y282500D02*
X747834D01*
X748334Y282000D01*
G01X750334D02*
Y283000D01*
G01Y286100D02*
X747834D01*
X749626Y284558D01*
Y286642D01*
G01X750334Y288617D02*
X749792Y288700D01*
X749334Y288825D01*
X748917Y288992D01*
X748459Y289200D01*
X747834Y289533D01*
Y287867D01*
G01X711208Y293767D02*
X711083Y293517D01*
X711000Y293225D01*
Y292892D01*
X711125Y292517D01*
X711333Y292225D01*
X711583Y292017D01*
X712000Y291850D01*
X712375Y291808D01*
X712750Y291892D01*
X713000Y292017D01*
X713250Y292267D01*
X713417Y292558D01*
X713500Y292850D01*
Y293142D01*
X713417Y293433D01*
X713292Y293683D01*
X713125Y293892D01*
G01X713500Y296450D02*
X711000D01*
X712792Y294908D01*
Y296992D01*
G01X711417Y298258D02*
X711167Y298508D01*
X711042Y298800D01*
X711000Y299133D01*
X711083Y299550D01*
X711292Y299842D01*
X711542Y299925D01*
X711792Y299883D01*
X712000Y299717D01*
X712417Y298883D01*
X712708Y298508D01*
X713125Y298258D01*
X713500Y298175D01*
Y299925D01*
G01Y302650D02*
X711000D01*
X712792Y301108D01*
Y303192D01*
G01X721362Y329492D02*
Y331992D01*
G01X723112D02*
Y329492D01*
G01Y330742D02*
X721362D01*
G01X724420Y329492D02*
Y331992D01*
X725254D01*
X725587Y331867D01*
X725837Y331700D01*
X726045Y331450D01*
X726212Y331159D01*
X726254Y330742D01*
X726212Y330325D01*
X726045Y330034D01*
X725837Y329784D01*
X725587Y329617D01*
X725254Y329492D01*
X724420D01*
G01X727520D02*
Y331992D01*
X728354D01*
X728687Y331867D01*
X728937Y331700D01*
X729145Y331450D01*
X729312Y331159D01*
X729354Y330742D01*
X729312Y330325D01*
X729145Y330034D01*
X728937Y329784D01*
X728687Y329617D01*
X728354Y329492D01*
X727520D01*
G01X730662Y329825D02*
X730995Y329617D01*
X731370Y329492D01*
X731704D01*
X732037Y329617D01*
X732287Y329825D01*
X732412Y330117D01*
X732329Y330409D01*
X732120Y330659D01*
X731745Y330825D01*
X731245Y330909D01*
X730954Y331075D01*
X730829Y331367D01*
X730912Y331659D01*
X731120Y331867D01*
X731412Y331992D01*
X731704D01*
X731995Y331909D01*
X732245Y331700D01*
G01X733595Y329492D02*
X734637Y331992D01*
X735679Y329492D01*
G01X735304Y330367D02*
X733970D01*
G01X736862Y329825D02*
X737195Y329617D01*
X737570Y329492D01*
X737904D01*
X738237Y329617D01*
X738487Y329825D01*
X738612Y330117D01*
X738529Y330409D01*
X738320Y330659D01*
X737945Y330825D01*
X737445Y330909D01*
X737154Y331075D01*
X737029Y331367D01*
X737112Y331659D01*
X737320Y331867D01*
X737612Y331992D01*
X737904D01*
X738195Y331909D01*
X738445Y331700D01*
G01X740045Y331575D02*
X740295Y331825D01*
X740587Y331950D01*
X740920Y331992D01*
X741337Y331909D01*
X741629Y331700D01*
X741712Y331450D01*
X741670Y331200D01*
X741504Y330992D01*
X740670Y330575D01*
X740295Y330284D01*
X740045Y329867D01*
X739962Y329492D01*
X741712D01*
G01X743229Y329784D02*
X743520Y329575D01*
X743854Y329492D01*
X744187Y329575D01*
X744479Y329825D01*
X744687Y330200D01*
X744770Y330575D01*
Y331034D01*
X744687Y331409D01*
X744479Y331742D01*
X744229Y331909D01*
X743937Y331992D01*
X743604Y331909D01*
X743354Y331742D01*
X743187Y331492D01*
X743104Y331159D01*
X743187Y330867D01*
X743395Y330575D01*
X743645Y330409D01*
X743937Y330367D01*
X744270Y330450D01*
X744520Y330659D01*
X744770Y331034D01*
G01X715187Y674248D02*
X720237D01*
Y772948D01*
X744887D01*
Y588548D01*
X720237D01*
Y647248D01*
X715187D01*
Y674248D01*
G01X707577Y619705D02*
Y622205D01*
X708618D01*
X708952Y622080D01*
X709160Y621913D01*
X709243Y621580D01*
X709160Y621247D01*
X708910Y621038D01*
X708618Y620913D01*
X707577D01*
G01X708618D02*
X709243Y619705D01*
G01X710593Y620080D02*
X710843Y619872D01*
X711135Y619747D01*
X711510Y619705D01*
X711885Y619788D01*
X712177Y619955D01*
X712385Y620247D01*
X712427Y620580D01*
X712343Y620913D01*
X712135Y621122D01*
X711843Y621288D01*
X711552Y621330D01*
X711260Y621288D01*
X710885Y621122D01*
X711010Y622205D01*
X712135D01*
G01X713818Y621788D02*
X714068Y622038D01*
X714360Y622163D01*
X714693Y622205D01*
X715110Y622122D01*
X715402Y621913D01*
X715485Y621663D01*
X715443Y621413D01*
X715277Y621205D01*
X714443Y620788D01*
X714068Y620497D01*
X713818Y620080D01*
X713735Y619705D01*
X715485D01*
G01X717002Y619997D02*
X717293Y619788D01*
X717627Y619705D01*
X717960Y619788D01*
X718252Y620038D01*
X718460Y620413D01*
X718543Y620788D01*
Y621247D01*
X718460Y621622D01*
X718252Y621955D01*
X718002Y622122D01*
X717710Y622205D01*
X717377Y622122D01*
X717127Y621955D01*
X716960Y621705D01*
X716877Y621372D01*
X716960Y621080D01*
X717168Y620788D01*
X717418Y620622D01*
X717710Y620580D01*
X718043Y620663D01*
X718293Y620872D01*
X718543Y621247D01*
G01X715300Y631917D02*
Y635917D01*
X707900D01*
G01X707577Y616005D02*
Y618505D01*
X708618D01*
X708952Y618380D01*
X709160Y618213D01*
X709243Y617880D01*
X709160Y617547D01*
X708910Y617338D01*
X708618Y617213D01*
X707577D01*
G01X708618D02*
X709243Y616005D01*
G01X710593Y616380D02*
X710843Y616172D01*
X711135Y616047D01*
X711510Y616005D01*
X711885Y616088D01*
X712177Y616255D01*
X712385Y616547D01*
X712427Y616880D01*
X712343Y617213D01*
X712135Y617422D01*
X711843Y617588D01*
X711552Y617630D01*
X711260Y617588D01*
X710885Y617422D01*
X711010Y618505D01*
X712135D01*
G01X713693Y616505D02*
X713943Y616213D01*
X714277Y616047D01*
X714652Y616005D01*
X714985Y616047D01*
X715318Y616255D01*
X715527Y616505D01*
X715568Y616755D01*
X715485Y617047D01*
X715193Y617255D01*
X714902Y617338D01*
X714527D01*
G01X714902D02*
X715152Y617463D01*
X715360Y617672D01*
X715443Y617922D01*
X715360Y618172D01*
X715152Y618380D01*
X714777Y618505D01*
X714402Y618463D01*
X714027Y618297D01*
G01X717710Y616005D02*
Y618505D01*
X717210Y618005D01*
G01Y616005D02*
X718210D01*
G01X715300Y627417D02*
Y631417D01*
X707900D01*
G01X707577Y623405D02*
Y625905D01*
X708618D01*
X708952Y625780D01*
X709160Y625613D01*
X709243Y625280D01*
X709160Y624947D01*
X708910Y624738D01*
X708618Y624613D01*
X707577D01*
G01X708618D02*
X709243Y623405D01*
G01X710593Y623780D02*
X710843Y623572D01*
X711135Y623447D01*
X711510Y623405D01*
X711885Y623488D01*
X712177Y623655D01*
X712385Y623947D01*
X712427Y624280D01*
X712343Y624613D01*
X712135Y624822D01*
X711843Y624988D01*
X711552Y625030D01*
X711260Y624988D01*
X710885Y624822D01*
X711010Y625905D01*
X712135D01*
G01X713693Y623905D02*
X713943Y623613D01*
X714277Y623447D01*
X714652Y623405D01*
X714985Y623447D01*
X715318Y623655D01*
X715527Y623905D01*
X715568Y624155D01*
X715485Y624447D01*
X715193Y624655D01*
X714902Y624738D01*
X714527D01*
G01X714902D02*
X715152Y624863D01*
X715360Y625072D01*
X715443Y625322D01*
X715360Y625572D01*
X715152Y625780D01*
X714777Y625905D01*
X714402Y625863D01*
X714027Y625697D01*
G01X716793Y623905D02*
X717043Y623613D01*
X717377Y623447D01*
X717752Y623405D01*
X718085Y623447D01*
X718418Y623655D01*
X718627Y623905D01*
X718668Y624155D01*
X718585Y624447D01*
X718293Y624655D01*
X718002Y624738D01*
X717627D01*
G01X718002D02*
X718252Y624863D01*
X718460Y625072D01*
X718543Y625322D01*
X718460Y625572D01*
X718252Y625780D01*
X717877Y625905D01*
X717502Y625863D01*
X717127Y625697D01*
G01X707900Y645917D02*
Y641917D01*
X715300D01*
G01X707400Y638717D02*
Y652117D01*
G01X746912Y687974D02*
Y690474D01*
X747953D01*
X748287Y690349D01*
X748495Y690182D01*
X748578Y689849D01*
X748495Y689516D01*
X748245Y689307D01*
X747953Y689182D01*
X746912D01*
G01X747953D02*
X748578Y687974D01*
G01X749928Y688349D02*
X750178Y688141D01*
X750470Y688016D01*
X750845Y687974D01*
X751220Y688057D01*
X751512Y688224D01*
X751720Y688516D01*
X751762Y688849D01*
X751678Y689182D01*
X751470Y689391D01*
X751178Y689557D01*
X750887Y689599D01*
X750595Y689557D01*
X750220Y689391D01*
X750345Y690474D01*
X751470D01*
G01X753153Y690057D02*
X753403Y690307D01*
X753695Y690432D01*
X754028Y690474D01*
X754445Y690391D01*
X754737Y690182D01*
X754820Y689932D01*
X754778Y689682D01*
X754612Y689474D01*
X753778Y689057D01*
X753403Y688766D01*
X753153Y688349D01*
X753070Y687974D01*
X754820D01*
G01X757045D02*
Y690474D01*
X756545Y689974D01*
G01Y687974D02*
X757545D01*
G01X753700Y675700D02*
Y679700D01*
X746300D01*
G01X710500Y706717D02*
X718500D01*
Y689117D01*
X710500D01*
Y706717D01*
G01X708800Y688917D02*
X703300D01*
G01X708800Y696917D02*
Y688917D01*
G01X717000Y677850D02*
X716958Y677517D01*
X716792Y677225D01*
X716542Y676975D01*
X716250Y676808D01*
X715917Y676725D01*
X715583D01*
X715250Y676808D01*
X714958Y676975D01*
X714708Y677225D01*
X714542Y677517D01*
X714500Y677850D01*
X714542Y678183D01*
X714708Y678475D01*
X714958Y678725D01*
X715250Y678892D01*
X715583Y678975D01*
X715917D01*
X716250Y678892D01*
X716542Y678725D01*
X716792Y678475D01*
X716958Y678183D01*
X717000Y677850D01*
G01X716333Y678183D02*
X717000Y678683D01*
G01Y680950D02*
X714500D01*
X715000Y680450D01*
G01X717000D02*
Y681450D01*
G01X714500Y684050D02*
X714583Y683717D01*
X714792Y683467D01*
X715042Y683300D01*
X715375Y683175D01*
X715750Y683133D01*
X716125Y683175D01*
X716458Y683300D01*
X716708Y683467D01*
X716917Y683717D01*
X717000Y684050D01*
X716917Y684383D01*
X716708Y684633D01*
X716458Y684800D01*
X716125Y684925D01*
X715750Y684967D01*
X715375Y684925D01*
X715042Y684800D01*
X714792Y684633D01*
X714583Y684383D01*
X714500Y684050D01*
G01X717000Y687150D02*
X714500D01*
X715000Y686650D01*
G01X717000D02*
Y687650D01*
G01X713200Y668417D02*
X711100Y670217D01*
X713200Y672417D01*
G01X750270Y651030D02*
X747770D01*
Y652071D01*
X747895Y652405D01*
X748062Y652613D01*
X748395Y652696D01*
X748728Y652613D01*
X748937Y652363D01*
X749062Y652071D01*
Y651030D01*
G01Y652071D02*
X750270Y652696D01*
G01X749895Y654046D02*
X750103Y654296D01*
X750228Y654588D01*
X750270Y654963D01*
X750187Y655338D01*
X750020Y655630D01*
X749728Y655838D01*
X749395Y655880D01*
X749062Y655796D01*
X748853Y655588D01*
X748687Y655296D01*
X748645Y655005D01*
X748687Y654713D01*
X748853Y654338D01*
X747770Y654463D01*
Y655588D01*
G01X748187Y657271D02*
X747937Y657521D01*
X747812Y657813D01*
X747770Y658146D01*
X747853Y658563D01*
X748062Y658855D01*
X748312Y658938D01*
X748562Y658896D01*
X748770Y658730D01*
X749187Y657896D01*
X749478Y657521D01*
X749895Y657271D01*
X750270Y657188D01*
Y658938D01*
G01X749895Y660246D02*
X750103Y660496D01*
X750228Y660788D01*
X750270Y661163D01*
X750187Y661538D01*
X750020Y661830D01*
X749728Y662038D01*
X749395Y662080D01*
X749062Y661996D01*
X748853Y661788D01*
X748687Y661496D01*
X748645Y661205D01*
X748687Y660913D01*
X748853Y660538D01*
X747770Y660663D01*
Y661788D01*
G01X748662Y694366D02*
X748412Y694491D01*
X748120Y694574D01*
X747787D01*
X747412Y694449D01*
X747120Y694241D01*
X746912Y693991D01*
X746745Y693574D01*
X746703Y693199D01*
X746787Y692824D01*
X746912Y692574D01*
X747162Y692324D01*
X747453Y692157D01*
X747745Y692074D01*
X748037D01*
X748328Y692157D01*
X748578Y692282D01*
X748787Y692449D01*
G01X750053Y694157D02*
X750303Y694407D01*
X750595Y694532D01*
X750928Y694574D01*
X751345Y694491D01*
X751637Y694282D01*
X751720Y694032D01*
X751678Y693782D01*
X751512Y693574D01*
X750678Y693157D01*
X750303Y692866D01*
X750053Y692449D01*
X749970Y692074D01*
X751720D01*
G01X753153Y693116D02*
X753445Y693407D01*
X753695Y693574D01*
X754028Y693657D01*
X754320Y693574D01*
X754528Y693407D01*
X754695Y693157D01*
X754737Y692866D01*
X754695Y692616D01*
X754528Y692366D01*
X754278Y692157D01*
X753987Y692074D01*
X753653Y692157D01*
X753362Y692407D01*
X753195Y692782D01*
X753153Y693199D01*
X753237Y693741D01*
X753362Y694032D01*
X753570Y694324D01*
X753862Y694532D01*
X754153Y694574D01*
X754445Y694491D01*
X754653Y694282D01*
G01X756962Y692074D02*
X757045Y692616D01*
X757170Y693074D01*
X757337Y693491D01*
X757545Y693949D01*
X757878Y694574D01*
X756212D01*
G01X715000Y708517D02*
X712500D01*
Y709558D01*
X712625Y709892D01*
X712792Y710100D01*
X713125Y710183D01*
X713458Y710100D01*
X713667Y709850D01*
X713792Y709558D01*
Y708517D01*
G01Y709558D02*
X715000Y710183D01*
G01X714625Y711533D02*
X714833Y711783D01*
X714958Y712075D01*
X715000Y712450D01*
X714917Y712825D01*
X714750Y713117D01*
X714458Y713325D01*
X714125Y713367D01*
X713792Y713283D01*
X713583Y713075D01*
X713417Y712783D01*
X713375Y712492D01*
X713417Y712200D01*
X713583Y711825D01*
X712500Y711950D01*
Y713075D01*
G01X712917Y714758D02*
X712667Y715008D01*
X712542Y715300D01*
X712500Y715633D01*
X712583Y716050D01*
X712792Y716342D01*
X713042Y716425D01*
X713292Y716383D01*
X713500Y716217D01*
X713917Y715383D01*
X714208Y715008D01*
X714625Y714758D01*
X715000Y714675D01*
Y716425D01*
G01X712500Y718650D02*
X712583Y718317D01*
X712792Y718067D01*
X713042Y717900D01*
X713375Y717775D01*
X713750Y717733D01*
X714125Y717775D01*
X714458Y717900D01*
X714708Y718067D01*
X714917Y718317D01*
X715000Y718650D01*
X714917Y718983D01*
X714708Y719233D01*
X714458Y719400D01*
X714125Y719525D01*
X713750Y719567D01*
X713375Y719525D01*
X713042Y719400D01*
X712792Y719233D01*
X712583Y718983D01*
X712500Y718650D01*
G01X708008Y734184D02*
X707883Y733934D01*
X707800Y733642D01*
Y733309D01*
X707925Y732934D01*
X708133Y732642D01*
X708383Y732434D01*
X708800Y732267D01*
X709175Y732225D01*
X709550Y732309D01*
X709800Y732434D01*
X710050Y732684D01*
X710217Y732975D01*
X710300Y733267D01*
Y733559D01*
X710217Y733850D01*
X710092Y734100D01*
X709925Y734309D01*
G01X708217Y735575D02*
X707967Y735825D01*
X707842Y736117D01*
X707800Y736450D01*
X707883Y736867D01*
X708092Y737159D01*
X708342Y737242D01*
X708592Y737200D01*
X708800Y737034D01*
X709217Y736200D01*
X709508Y735825D01*
X709925Y735575D01*
X710300Y735492D01*
Y737242D01*
G01X709258Y738675D02*
X708967Y738967D01*
X708800Y739217D01*
X708717Y739550D01*
X708800Y739842D01*
X708967Y740050D01*
X709217Y740217D01*
X709508Y740259D01*
X709758Y740217D01*
X710008Y740050D01*
X710217Y739800D01*
X710300Y739509D01*
X710217Y739175D01*
X709967Y738884D01*
X709592Y738717D01*
X709175Y738675D01*
X708633Y738759D01*
X708342Y738884D01*
X708050Y739092D01*
X707842Y739384D01*
X707800Y739675D01*
X707883Y739967D01*
X708092Y740175D01*
G01X709258Y741775D02*
X708967Y742067D01*
X708800Y742317D01*
X708717Y742650D01*
X708800Y742942D01*
X708967Y743150D01*
X709217Y743317D01*
X709508Y743359D01*
X709758Y743317D01*
X710008Y743150D01*
X710217Y742900D01*
X710300Y742609D01*
X710217Y742275D01*
X709967Y741984D01*
X709592Y741817D01*
X709175Y741775D01*
X708633Y741859D01*
X708342Y741984D01*
X708050Y742192D01*
X707842Y742484D01*
X707800Y742775D01*
X707883Y743067D01*
X708092Y743275D01*
G01X703300Y696917D02*
X708800D01*
G01X747500Y707350D02*
X750000D01*
G01X747500Y706392D02*
Y708308D01*
G01X750000Y709617D02*
X747500D01*
Y710617D01*
X747625Y710950D01*
X747917Y711200D01*
X748250Y711283D01*
X748583Y711200D01*
X748833Y710992D01*
X748958Y710617D01*
Y709617D01*
G01X750000Y713550D02*
X749958Y713842D01*
X749833Y714175D01*
X749625Y714383D01*
X749333Y714467D01*
X749042Y714383D01*
X748792Y714133D01*
X748667Y713758D01*
Y713342D01*
X748583Y713092D01*
X748375Y712883D01*
X748083Y712800D01*
X747792Y712925D01*
X747583Y713217D01*
X747500Y713550D01*
X747583Y713883D01*
X747792Y714175D01*
X748083Y714300D01*
X748375Y714217D01*
X748583Y714008D01*
X748667Y713758D01*
Y713342D01*
X748792Y712967D01*
X749042Y712717D01*
X749333Y712633D01*
X749625Y712717D01*
X749833Y712925D01*
X749958Y713258D01*
X750000Y713550D01*
G01Y716567D02*
X749458Y716650D01*
X749000Y716775D01*
X748583Y716942D01*
X748125Y717150D01*
X747500Y717483D01*
Y715817D01*
G01X725775Y778667D02*
Y781167D01*
G01X727525D02*
Y778667D01*
G01Y779917D02*
X725775D01*
G01X728833Y778667D02*
Y781167D01*
X729667D01*
X730000Y781042D01*
X730250Y780875D01*
X730458Y780625D01*
X730625Y780334D01*
X730667Y779917D01*
X730625Y779500D01*
X730458Y779209D01*
X730250Y778959D01*
X730000Y778792D01*
X729667Y778667D01*
X728833D01*
G01X731933D02*
Y781167D01*
X732767D01*
X733100Y781042D01*
X733350Y780875D01*
X733558Y780625D01*
X733725Y780334D01*
X733767Y779917D01*
X733725Y779500D01*
X733558Y779209D01*
X733350Y778959D01*
X733100Y778792D01*
X732767Y778667D01*
X731933D01*
G01X735075Y779000D02*
X735408Y778792D01*
X735783Y778667D01*
X736117D01*
X736450Y778792D01*
X736700Y779000D01*
X736825Y779292D01*
X736742Y779584D01*
X736533Y779834D01*
X736158Y780000D01*
X735658Y780084D01*
X735367Y780250D01*
X735242Y780542D01*
X735325Y780834D01*
X735533Y781042D01*
X735825Y781167D01*
X736117D01*
X736408Y781084D01*
X736658Y780875D01*
G01X738008Y778667D02*
X739050Y781167D01*
X740092Y778667D01*
G01X739717Y779542D02*
X738383D01*
G01X741275Y779000D02*
X741608Y778792D01*
X741983Y778667D01*
X742317D01*
X742650Y778792D01*
X742900Y779000D01*
X743025Y779292D01*
X742942Y779584D01*
X742733Y779834D01*
X742358Y780000D01*
X741858Y780084D01*
X741567Y780250D01*
X741442Y780542D01*
X741525Y780834D01*
X741733Y781042D01*
X742025Y781167D01*
X742317D01*
X742608Y781084D01*
X742858Y780875D01*
G01X745250Y778667D02*
Y781167D01*
X744750Y780667D01*
G01Y778667D02*
X745750D01*
G01X748267D02*
X748350Y779209D01*
X748475Y779667D01*
X748642Y780084D01*
X748850Y780542D01*
X749183Y781167D01*
X747517D01*
G01X710708Y746767D02*
X710583Y746517D01*
X710500Y746225D01*
Y745892D01*
X710625Y745517D01*
X710833Y745225D01*
X711083Y745017D01*
X711500Y744850D01*
X711875Y744808D01*
X712250Y744892D01*
X712500Y745017D01*
X712750Y745267D01*
X712917Y745558D01*
X713000Y745850D01*
Y746142D01*
X712917Y746433D01*
X712792Y746683D01*
X712625Y746892D01*
G01X710917Y748158D02*
X710667Y748408D01*
X710542Y748700D01*
X710500Y749033D01*
X710583Y749450D01*
X710792Y749742D01*
X711042Y749825D01*
X711292Y749783D01*
X711500Y749617D01*
X711917Y748783D01*
X712208Y748408D01*
X712625Y748158D01*
X713000Y748075D01*
Y749825D01*
G01X711958Y751258D02*
X711667Y751550D01*
X711500Y751800D01*
X711417Y752133D01*
X711500Y752425D01*
X711667Y752633D01*
X711917Y752800D01*
X712208Y752842D01*
X712458Y752800D01*
X712708Y752633D01*
X712917Y752383D01*
X713000Y752092D01*
X712917Y751758D01*
X712667Y751467D01*
X712292Y751300D01*
X711875Y751258D01*
X711333Y751342D01*
X711042Y751467D01*
X710750Y751675D01*
X710542Y751967D01*
X710500Y752258D01*
X710583Y752550D01*
X710792Y752758D01*
G01X713000Y755150D02*
X712958Y755442D01*
X712833Y755775D01*
X712625Y755983D01*
X712333Y756067D01*
X712042Y755983D01*
X711792Y755733D01*
X711667Y755358D01*
Y754942D01*
X711583Y754692D01*
X711375Y754483D01*
X711083Y754400D01*
X710792Y754525D01*
X710583Y754817D01*
X710500Y755150D01*
X710583Y755483D01*
X710792Y755775D01*
X711083Y755900D01*
X711375Y755817D01*
X711583Y755608D01*
X711667Y755358D01*
Y754942D01*
X711792Y754567D01*
X712042Y754317D01*
X712333Y754233D01*
X712625Y754317D01*
X712833Y754525D01*
X712958Y754858D01*
X713000Y755150D01*
G01X715187Y1127004D02*
X720237D01*
Y1225704D01*
X744887D01*
Y1041304D01*
X720237D01*
Y1100004D01*
X715187D01*
Y1127004D01*
G01X707117Y1072673D02*
Y1075173D01*
X708158D01*
X708492Y1075048D01*
X708700Y1074881D01*
X708783Y1074548D01*
X708700Y1074215D01*
X708450Y1074006D01*
X708158Y1073881D01*
X707117D01*
G01X708158D02*
X708783Y1072673D01*
G01X710258Y1074756D02*
X710508Y1075006D01*
X710800Y1075131D01*
X711133Y1075173D01*
X711550Y1075090D01*
X711842Y1074881D01*
X711925Y1074631D01*
X711883Y1074381D01*
X711717Y1074173D01*
X710883Y1073756D01*
X710508Y1073465D01*
X710258Y1073048D01*
X710175Y1072673D01*
X711925D01*
G01X713233Y1073048D02*
X713483Y1072840D01*
X713775Y1072715D01*
X714150Y1072673D01*
X714525Y1072756D01*
X714817Y1072923D01*
X715025Y1073215D01*
X715067Y1073548D01*
X714983Y1073881D01*
X714775Y1074090D01*
X714483Y1074256D01*
X714192Y1074298D01*
X713900Y1074256D01*
X713525Y1074090D01*
X713650Y1075173D01*
X714775D01*
G01X716333Y1073173D02*
X716583Y1072881D01*
X716917Y1072715D01*
X717292Y1072673D01*
X717625Y1072715D01*
X717958Y1072923D01*
X718167Y1073173D01*
X718208Y1073423D01*
X718125Y1073715D01*
X717833Y1073923D01*
X717542Y1074006D01*
X717167D01*
G01X717542D02*
X717792Y1074131D01*
X718000Y1074340D01*
X718083Y1074590D01*
X718000Y1074840D01*
X717792Y1075048D01*
X717417Y1075173D01*
X717042Y1075131D01*
X716667Y1074965D01*
G01X707117Y1068300D02*
Y1070800D01*
X708158D01*
X708492Y1070675D01*
X708700Y1070508D01*
X708783Y1070175D01*
X708700Y1069842D01*
X708450Y1069633D01*
X708158Y1069508D01*
X707117D01*
G01X708158D02*
X708783Y1068300D01*
G01X710258Y1070383D02*
X710508Y1070633D01*
X710800Y1070758D01*
X711133Y1070800D01*
X711550Y1070717D01*
X711842Y1070508D01*
X711925Y1070258D01*
X711883Y1070008D01*
X711717Y1069800D01*
X710883Y1069383D01*
X710508Y1069092D01*
X710258Y1068675D01*
X710175Y1068300D01*
X711925D01*
G01X713233Y1068675D02*
X713483Y1068467D01*
X713775Y1068342D01*
X714150Y1068300D01*
X714525Y1068383D01*
X714817Y1068550D01*
X715025Y1068842D01*
X715067Y1069175D01*
X714983Y1069508D01*
X714775Y1069717D01*
X714483Y1069883D01*
X714192Y1069925D01*
X713900Y1069883D01*
X713525Y1069717D01*
X713650Y1070800D01*
X714775D01*
G01X716458Y1069342D02*
X716750Y1069633D01*
X717000Y1069800D01*
X717333Y1069883D01*
X717625Y1069800D01*
X717833Y1069633D01*
X718000Y1069383D01*
X718042Y1069092D01*
X718000Y1068842D01*
X717833Y1068592D01*
X717583Y1068383D01*
X717292Y1068300D01*
X716958Y1068383D01*
X716667Y1068633D01*
X716500Y1069008D01*
X716458Y1069425D01*
X716542Y1069967D01*
X716667Y1070258D01*
X716875Y1070550D01*
X717167Y1070758D01*
X717458Y1070800D01*
X717750Y1070717D01*
X717958Y1070508D01*
G01X715300Y1079973D02*
Y1083973D01*
X707900D01*
G01X707117Y1076500D02*
Y1079000D01*
X708158D01*
X708492Y1078875D01*
X708700Y1078708D01*
X708783Y1078375D01*
X708700Y1078042D01*
X708450Y1077833D01*
X708158Y1077708D01*
X707117D01*
G01X708158D02*
X708783Y1076500D01*
G01X710258Y1078583D02*
X710508Y1078833D01*
X710800Y1078958D01*
X711133Y1079000D01*
X711550Y1078917D01*
X711842Y1078708D01*
X711925Y1078458D01*
X711883Y1078208D01*
X711717Y1078000D01*
X710883Y1077583D01*
X710508Y1077292D01*
X710258Y1076875D01*
X710175Y1076500D01*
X711925D01*
G01X713233Y1076875D02*
X713483Y1076667D01*
X713775Y1076542D01*
X714150Y1076500D01*
X714525Y1076583D01*
X714817Y1076750D01*
X715025Y1077042D01*
X715067Y1077375D01*
X714983Y1077708D01*
X714775Y1077917D01*
X714483Y1078083D01*
X714192Y1078125D01*
X713900Y1078083D01*
X713525Y1077917D01*
X713650Y1079000D01*
X714775D01*
G01X717250Y1076500D02*
X717542Y1076542D01*
X717875Y1076667D01*
X718083Y1076875D01*
X718167Y1077167D01*
X718083Y1077458D01*
X717833Y1077708D01*
X717458Y1077833D01*
X717042D01*
X716792Y1077917D01*
X716583Y1078125D01*
X716500Y1078417D01*
X716625Y1078708D01*
X716917Y1078917D01*
X717250Y1079000D01*
X717583Y1078917D01*
X717875Y1078708D01*
X718000Y1078417D01*
X717917Y1078125D01*
X717708Y1077917D01*
X717458Y1077833D01*
X717042D01*
X716667Y1077708D01*
X716417Y1077458D01*
X716333Y1077167D01*
X716417Y1076875D01*
X716625Y1076667D01*
X716958Y1076542D01*
X717250Y1076500D01*
G01X715300Y1084673D02*
Y1088673D01*
X707900D01*
G01Y1098673D02*
Y1094673D01*
X715300D01*
G01X707200Y1089973D02*
Y1103373D01*
G01X717500Y1130400D02*
X717458Y1130067D01*
X717292Y1129775D01*
X717042Y1129525D01*
X716750Y1129358D01*
X716417Y1129275D01*
X716083D01*
X715750Y1129358D01*
X715458Y1129525D01*
X715208Y1129775D01*
X715042Y1130067D01*
X715000Y1130400D01*
X715042Y1130733D01*
X715208Y1131025D01*
X715458Y1131275D01*
X715750Y1131442D01*
X716083Y1131525D01*
X716417D01*
X716750Y1131442D01*
X717042Y1131275D01*
X717292Y1131025D01*
X717458Y1130733D01*
X717500Y1130400D01*
G01X716833Y1130733D02*
X717500Y1131233D01*
G01X717000Y1132583D02*
X717292Y1132833D01*
X717458Y1133167D01*
X717500Y1133542D01*
X717458Y1133875D01*
X717250Y1134208D01*
X717000Y1134417D01*
X716750Y1134458D01*
X716458Y1134375D01*
X716250Y1134083D01*
X716167Y1133792D01*
Y1133417D01*
G01Y1133792D02*
X716042Y1134042D01*
X715833Y1134250D01*
X715583Y1134333D01*
X715333Y1134250D01*
X715125Y1134042D01*
X715000Y1133667D01*
X715042Y1133292D01*
X715208Y1132917D01*
G01X715000Y1136600D02*
X715083Y1136267D01*
X715292Y1136017D01*
X715542Y1135850D01*
X715875Y1135725D01*
X716250Y1135683D01*
X716625Y1135725D01*
X716958Y1135850D01*
X717208Y1136017D01*
X717417Y1136267D01*
X717500Y1136600D01*
X717417Y1136933D01*
X717208Y1137183D01*
X716958Y1137350D01*
X716625Y1137475D01*
X716250Y1137517D01*
X715875Y1137475D01*
X715542Y1137350D01*
X715292Y1137183D01*
X715083Y1136933D01*
X715000Y1136600D01*
G01X713200Y1121173D02*
X711100Y1122973D01*
X713200Y1125173D01*
G01X715000Y1161017D02*
X712500D01*
Y1162058D01*
X712625Y1162392D01*
X712792Y1162600D01*
X713125Y1162683D01*
X713458Y1162600D01*
X713667Y1162350D01*
X713792Y1162058D01*
Y1161017D01*
G01Y1162058D02*
X715000Y1162683D01*
G01X712917Y1164158D02*
X712667Y1164408D01*
X712542Y1164700D01*
X712500Y1165033D01*
X712583Y1165450D01*
X712792Y1165742D01*
X713042Y1165825D01*
X713292Y1165783D01*
X713500Y1165617D01*
X713917Y1164783D01*
X714208Y1164408D01*
X714625Y1164158D01*
X715000Y1164075D01*
Y1165825D01*
G01Y1168550D02*
X712500D01*
X714292Y1167008D01*
Y1169092D01*
G01X715000Y1171650D02*
X712500D01*
X714292Y1170108D01*
Y1172192D01*
G01X710500Y1159473D02*
X718500D01*
Y1141873D01*
X710500D01*
Y1159473D01*
G01X708800Y1141673D02*
X703300D01*
G01X708800Y1149673D02*
Y1141673D01*
G01X703300Y1149673D02*
X708800D01*
G01X707708Y1186767D02*
X707583Y1186517D01*
X707500Y1186225D01*
Y1185892D01*
X707625Y1185517D01*
X707833Y1185225D01*
X708083Y1185017D01*
X708500Y1184850D01*
X708875Y1184808D01*
X709250Y1184892D01*
X709500Y1185017D01*
X709750Y1185267D01*
X709917Y1185558D01*
X710000Y1185850D01*
Y1186142D01*
X709917Y1186433D01*
X709792Y1186683D01*
X709625Y1186892D01*
G01X710000Y1188950D02*
X707500D01*
X708000Y1188450D01*
G01X710000D02*
Y1189450D01*
G01X707500Y1192050D02*
X707583Y1191717D01*
X707792Y1191467D01*
X708042Y1191300D01*
X708375Y1191175D01*
X708750Y1191133D01*
X709125Y1191175D01*
X709458Y1191300D01*
X709708Y1191467D01*
X709917Y1191717D01*
X710000Y1192050D01*
X709917Y1192383D01*
X709708Y1192633D01*
X709458Y1192800D01*
X709125Y1192925D01*
X708750Y1192967D01*
X708375Y1192925D01*
X708042Y1192800D01*
X707792Y1192633D01*
X707583Y1192383D01*
X707500Y1192050D01*
G01X709708Y1194442D02*
X709917Y1194733D01*
X710000Y1195067D01*
X709917Y1195400D01*
X709667Y1195692D01*
X709292Y1195900D01*
X708917Y1195983D01*
X708458D01*
X708083Y1195900D01*
X707750Y1195692D01*
X707583Y1195442D01*
X707500Y1195150D01*
X707583Y1194817D01*
X707750Y1194567D01*
X708000Y1194400D01*
X708333Y1194317D01*
X708625Y1194400D01*
X708917Y1194608D01*
X709083Y1194858D01*
X709125Y1195150D01*
X709042Y1195483D01*
X708833Y1195733D01*
X708458Y1195983D01*
G01X711208Y1197767D02*
X711083Y1197517D01*
X711000Y1197225D01*
Y1196892D01*
X711125Y1196517D01*
X711333Y1196225D01*
X711583Y1196017D01*
X712000Y1195850D01*
X712375Y1195808D01*
X712750Y1195892D01*
X713000Y1196017D01*
X713250Y1196267D01*
X713417Y1196558D01*
X713500Y1196850D01*
Y1197142D01*
X713417Y1197433D01*
X713292Y1197683D01*
X713125Y1197892D01*
G01X713500Y1199950D02*
X711000D01*
X711500Y1199450D01*
G01X713500D02*
Y1200450D01*
G01Y1203050D02*
X711000D01*
X711500Y1202550D01*
G01X713500D02*
Y1203550D01*
G01X711417Y1205358D02*
X711167Y1205608D01*
X711042Y1205900D01*
X711000Y1206233D01*
X711083Y1206650D01*
X711292Y1206942D01*
X711542Y1207025D01*
X711792Y1206983D01*
X712000Y1206817D01*
X712417Y1205983D01*
X712708Y1205608D01*
X713125Y1205358D01*
X713500Y1205275D01*
Y1207025D01*
G01X738325Y1232500D02*
Y1235000D01*
G01X740075D02*
Y1232500D01*
G01Y1233750D02*
X738325D01*
G01X741383Y1232500D02*
Y1235000D01*
X742217D01*
X742550Y1234875D01*
X742800Y1234708D01*
X743008Y1234458D01*
X743175Y1234167D01*
X743217Y1233750D01*
X743175Y1233333D01*
X743008Y1233042D01*
X742800Y1232792D01*
X742550Y1232625D01*
X742217Y1232500D01*
X741383D01*
G01X744483D02*
Y1235000D01*
X745317D01*
X745650Y1234875D01*
X745900Y1234708D01*
X746108Y1234458D01*
X746275Y1234167D01*
X746317Y1233750D01*
X746275Y1233333D01*
X746108Y1233042D01*
X745900Y1232792D01*
X745650Y1232625D01*
X745317Y1232500D01*
X744483D01*
G01X747625Y1232833D02*
X747958Y1232625D01*
X748333Y1232500D01*
X748667D01*
X749000Y1232625D01*
X749250Y1232833D01*
X749375Y1233125D01*
X749292Y1233417D01*
X749083Y1233667D01*
X748708Y1233833D01*
X748208Y1233917D01*
X747917Y1234083D01*
X747792Y1234375D01*
X747875Y1234667D01*
X748083Y1234875D01*
X748375Y1235000D01*
X748667D01*
X748958Y1234917D01*
X749208Y1234708D01*
G01X750558Y1232500D02*
X751600Y1235000D01*
X752642Y1232500D01*
G01X752267Y1233375D02*
X750933D01*
G01X753825Y1232833D02*
X754158Y1232625D01*
X754533Y1232500D01*
X754867D01*
X755200Y1232625D01*
X755450Y1232833D01*
X755575Y1233125D01*
X755492Y1233417D01*
X755283Y1233667D01*
X754908Y1233833D01*
X754408Y1233917D01*
X754117Y1234083D01*
X753992Y1234375D01*
X754075Y1234667D01*
X754283Y1234875D01*
X754575Y1235000D01*
X754867D01*
X755158Y1234917D01*
X755408Y1234708D01*
G01X756883Y1232875D02*
X757133Y1232667D01*
X757425Y1232542D01*
X757800Y1232500D01*
X758175Y1232583D01*
X758467Y1232750D01*
X758675Y1233042D01*
X758717Y1233375D01*
X758633Y1233708D01*
X758425Y1233917D01*
X758133Y1234083D01*
X757842Y1234125D01*
X757550Y1234083D01*
X757175Y1233917D01*
X757300Y1235000D01*
X758425D01*
G01X800164Y1767D02*
Y6617D01*
X790514D01*
Y16717D01*
X794264D01*
Y27767D01*
X800164D01*
Y33667D01*
X879364D01*
Y27767D01*
X882264D01*
X885264Y24767D01*
Y16717D01*
X889014D01*
Y6617D01*
X879364D01*
Y1767D01*
X800164D01*
G01X794001Y38204D02*
Y69804D01*
X798701Y74504D01*
X817301D01*
X822001Y69804D01*
Y38204D01*
X794001D01*
G01X785776Y33527D02*
Y31027D01*
X787442D01*
G01X790542D02*
X788876D01*
Y33527D01*
X790542D01*
G01X789876Y32319D02*
X788876D01*
G01X791892Y31027D02*
Y33527D01*
X792726D01*
X793059Y33402D01*
X793309Y33235D01*
X793517Y32985D01*
X793684Y32694D01*
X793726Y32277D01*
X793684Y31860D01*
X793517Y31569D01*
X793309Y31319D01*
X793059Y31152D01*
X792726Y31027D01*
X791892D01*
G01X795909D02*
Y33527D01*
X795409Y33027D01*
G01Y31027D02*
X796409D01*
G01X752786Y144907D02*
X750286D01*
Y145948D01*
X750411Y146282D01*
X750578Y146490D01*
X750911Y146573D01*
X751244Y146490D01*
X751453Y146240D01*
X751578Y145948D01*
Y144907D01*
G01Y145948D02*
X752786Y146573D01*
G01Y148840D02*
X752744Y149132D01*
X752619Y149465D01*
X752411Y149673D01*
X752119Y149757D01*
X751828Y149673D01*
X751578Y149423D01*
X751453Y149048D01*
Y148632D01*
X751369Y148382D01*
X751161Y148173D01*
X750869Y148090D01*
X750578Y148215D01*
X750369Y148507D01*
X750286Y148840D01*
X750369Y149173D01*
X750578Y149465D01*
X750869Y149590D01*
X751161Y149507D01*
X751369Y149298D01*
X751453Y149048D01*
Y148632D01*
X751578Y148257D01*
X751828Y148007D01*
X752119Y147923D01*
X752411Y148007D01*
X752619Y148215D01*
X752744Y148548D01*
X752786Y148840D01*
G01X750286Y151940D02*
X750369Y151607D01*
X750578Y151357D01*
X750828Y151190D01*
X751161Y151065D01*
X751536Y151023D01*
X751911Y151065D01*
X752244Y151190D01*
X752494Y151357D01*
X752703Y151607D01*
X752786Y151940D01*
X752703Y152273D01*
X752494Y152523D01*
X752244Y152690D01*
X751911Y152815D01*
X751536Y152857D01*
X751161Y152815D01*
X750828Y152690D01*
X750578Y152523D01*
X750369Y152273D01*
X750286Y151940D01*
G01X752786Y155040D02*
X750286D01*
X750786Y154540D01*
G01X752786D02*
Y155540D01*
G01X751034Y195186D02*
Y197686D01*
X752075D01*
X752409Y197561D01*
X752617Y197394D01*
X752700Y197061D01*
X752617Y196728D01*
X752367Y196519D01*
X752075Y196394D01*
X751034D01*
G01X752075D02*
X752700Y195186D01*
G01X754884D02*
X754967Y195728D01*
X755092Y196186D01*
X755259Y196603D01*
X755467Y197061D01*
X755800Y197686D01*
X754134D01*
G01X757359Y195478D02*
X757650Y195269D01*
X757984Y195186D01*
X758317Y195269D01*
X758609Y195519D01*
X758817Y195894D01*
X758900Y196269D01*
Y196728D01*
X758817Y197103D01*
X758609Y197436D01*
X758359Y197603D01*
X758067Y197686D01*
X757734Y197603D01*
X757484Y197436D01*
X757317Y197186D01*
X757234Y196853D01*
X757317Y196561D01*
X757525Y196269D01*
X757775Y196103D01*
X758067Y196061D01*
X758400Y196144D01*
X758650Y196353D01*
X758900Y196728D01*
G01X761084Y195186D02*
X761167Y195728D01*
X761292Y196186D01*
X761459Y196603D01*
X761667Y197061D01*
X762000Y197686D01*
X760334D01*
G01X764613Y175602D02*
X764363Y175727D01*
X764071Y175810D01*
X763738D01*
X763363Y175685D01*
X763071Y175477D01*
X762863Y175227D01*
X762696Y174810D01*
X762654Y174435D01*
X762738Y174060D01*
X762863Y173810D01*
X763113Y173560D01*
X763404Y173393D01*
X763696Y173310D01*
X763988D01*
X764279Y173393D01*
X764529Y173518D01*
X764738Y173685D01*
G01X767296Y173310D02*
Y175810D01*
X765754Y174018D01*
X767838D01*
G01X769896Y173310D02*
Y175810D01*
X769396Y175310D01*
G01Y173310D02*
X770396D01*
G01X772079Y173685D02*
X772329Y173477D01*
X772621Y173352D01*
X772996Y173310D01*
X773371Y173393D01*
X773663Y173560D01*
X773871Y173852D01*
X773913Y174185D01*
X773829Y174518D01*
X773621Y174727D01*
X773329Y174893D01*
X773038Y174935D01*
X772746Y174893D01*
X772371Y174727D01*
X772496Y175810D01*
X773621D01*
G01X764485Y171494D02*
X764235Y171619D01*
X763943Y171702D01*
X763610D01*
X763235Y171577D01*
X762943Y171369D01*
X762735Y171119D01*
X762568Y170702D01*
X762526Y170327D01*
X762610Y169952D01*
X762735Y169702D01*
X762985Y169452D01*
X763276Y169285D01*
X763568Y169202D01*
X763860D01*
X764151Y169285D01*
X764401Y169410D01*
X764610Y169577D01*
G01X767168Y169202D02*
Y171702D01*
X765626Y169910D01*
X767710D01*
G01X769768Y169202D02*
Y171702D01*
X769268Y171202D01*
G01Y169202D02*
X770268D01*
G01X772076Y170244D02*
X772368Y170535D01*
X772618Y170702D01*
X772951Y170785D01*
X773243Y170702D01*
X773451Y170535D01*
X773618Y170285D01*
X773660Y169994D01*
X773618Y169744D01*
X773451Y169494D01*
X773201Y169285D01*
X772910Y169202D01*
X772576Y169285D01*
X772285Y169535D01*
X772118Y169910D01*
X772076Y170327D01*
X772160Y170869D01*
X772285Y171160D01*
X772493Y171452D01*
X772785Y171660D01*
X773076Y171702D01*
X773368Y171619D01*
X773576Y171410D01*
G01X752784Y201578D02*
X752534Y201703D01*
X752242Y201786D01*
X751909D01*
X751534Y201661D01*
X751242Y201453D01*
X751034Y201203D01*
X750867Y200786D01*
X750825Y200411D01*
X750909Y200036D01*
X751034Y199786D01*
X751284Y199536D01*
X751575Y199369D01*
X751867Y199286D01*
X752159D01*
X752450Y199369D01*
X752700Y199494D01*
X752909Y199661D01*
G01X755467Y199286D02*
Y201786D01*
X753925Y199994D01*
X756009D01*
G01X757275Y201369D02*
X757525Y201619D01*
X757817Y201744D01*
X758150Y201786D01*
X758567Y201703D01*
X758859Y201494D01*
X758942Y201244D01*
X758900Y200994D01*
X758734Y200786D01*
X757900Y200369D01*
X757525Y200078D01*
X757275Y199661D01*
X757192Y199286D01*
X758942D01*
G01X760250Y199786D02*
X760500Y199494D01*
X760834Y199328D01*
X761209Y199286D01*
X761542Y199328D01*
X761875Y199536D01*
X762084Y199786D01*
X762125Y200036D01*
X762042Y200328D01*
X761750Y200536D01*
X761459Y200619D01*
X761084D01*
G01X761459D02*
X761709Y200744D01*
X761917Y200953D01*
X762000Y201203D01*
X761917Y201453D01*
X761709Y201661D01*
X761334Y201786D01*
X760959Y201744D01*
X760584Y201578D01*
G01X789167Y623550D02*
Y655150D01*
X793867Y659850D01*
X812467D01*
X817167Y655150D01*
Y623550D01*
X789167D01*
G01X749949Y612632D02*
X749824Y612382D01*
X749741Y612090D01*
Y611757D01*
X749866Y611382D01*
X750074Y611090D01*
X750324Y610882D01*
X750741Y610715D01*
X751116Y610673D01*
X751491Y610757D01*
X751741Y610882D01*
X751991Y611132D01*
X752158Y611423D01*
X752241Y611715D01*
Y612007D01*
X752158Y612298D01*
X752033Y612548D01*
X751866Y612757D01*
G01X750158Y614023D02*
X749908Y614273D01*
X749783Y614565D01*
X749741Y614898D01*
X749824Y615315D01*
X750033Y615607D01*
X750283Y615690D01*
X750533Y615648D01*
X750741Y615482D01*
X751158Y614648D01*
X751449Y614273D01*
X751866Y614023D01*
X752241Y613940D01*
Y615690D01*
G01X751199Y617123D02*
X750908Y617415D01*
X750741Y617665D01*
X750658Y617998D01*
X750741Y618290D01*
X750908Y618498D01*
X751158Y618665D01*
X751449Y618707D01*
X751699Y618665D01*
X751949Y618498D01*
X752158Y618248D01*
X752241Y617957D01*
X752158Y617623D01*
X751908Y617332D01*
X751533Y617165D01*
X751116Y617123D01*
X750574Y617207D01*
X750283Y617332D01*
X749991Y617540D01*
X749783Y617832D01*
X749741Y618123D01*
X749824Y618415D01*
X750033Y618623D01*
G01X749741Y621015D02*
X749824Y620682D01*
X750033Y620432D01*
X750283Y620265D01*
X750616Y620140D01*
X750991Y620098D01*
X751366Y620140D01*
X751699Y620265D01*
X751949Y620432D01*
X752158Y620682D01*
X752241Y621015D01*
X752158Y621348D01*
X751949Y621598D01*
X751699Y621765D01*
X751366Y621890D01*
X750991Y621932D01*
X750616Y621890D01*
X750283Y621765D01*
X750033Y621598D01*
X749824Y621348D01*
X749741Y621015D01*
G01X750952Y631015D02*
X750827Y630765D01*
X750744Y630473D01*
Y630140D01*
X750869Y629765D01*
X751077Y629473D01*
X751327Y629265D01*
X751744Y629098D01*
X752119Y629056D01*
X752494Y629140D01*
X752744Y629265D01*
X752994Y629515D01*
X753161Y629806D01*
X753244Y630098D01*
Y630390D01*
X753161Y630681D01*
X753036Y630931D01*
X752869Y631140D01*
G01X751161Y632406D02*
X750911Y632656D01*
X750786Y632948D01*
X750744Y633281D01*
X750827Y633698D01*
X751036Y633990D01*
X751286Y634073D01*
X751536Y634031D01*
X751744Y633865D01*
X752161Y633031D01*
X752452Y632656D01*
X752869Y632406D01*
X753244Y632323D01*
Y634073D01*
G01X752869Y635381D02*
X753077Y635631D01*
X753202Y635923D01*
X753244Y636298D01*
X753161Y636673D01*
X752994Y636965D01*
X752702Y637173D01*
X752369Y637215D01*
X752036Y637131D01*
X751827Y636923D01*
X751661Y636631D01*
X751619Y636340D01*
X751661Y636048D01*
X751827Y635673D01*
X750744Y635798D01*
Y636923D01*
G01X752952Y638690D02*
X753161Y638981D01*
X753244Y639315D01*
X753161Y639648D01*
X752911Y639940D01*
X752536Y640148D01*
X752161Y640231D01*
X751702D01*
X751327Y640148D01*
X750994Y639940D01*
X750827Y639690D01*
X750744Y639398D01*
X750827Y639065D01*
X750994Y638815D01*
X751244Y638648D01*
X751577Y638565D01*
X751869Y638648D01*
X752161Y638856D01*
X752327Y639106D01*
X752369Y639398D01*
X752286Y639731D01*
X752077Y639981D01*
X751702Y640231D01*
G01X753378Y1070346D02*
X753128Y1070471D01*
X752836Y1070554D01*
X752503D01*
X752128Y1070429D01*
X751836Y1070221D01*
X751628Y1069971D01*
X751461Y1069554D01*
X751419Y1069179D01*
X751503Y1068804D01*
X751628Y1068554D01*
X751878Y1068304D01*
X752169Y1068137D01*
X752461Y1068054D01*
X752753D01*
X753044Y1068137D01*
X753294Y1068262D01*
X753503Y1068429D01*
G01X755561Y1068054D02*
Y1070554D01*
X755061Y1070054D01*
G01Y1068054D02*
X756061D01*
G01X758661Y1070554D02*
X758328Y1070471D01*
X758078Y1070262D01*
X757911Y1070012D01*
X757786Y1069679D01*
X757744Y1069304D01*
X757786Y1068929D01*
X757911Y1068596D01*
X758078Y1068346D01*
X758328Y1068137D01*
X758661Y1068054D01*
X758994Y1068137D01*
X759244Y1068346D01*
X759411Y1068596D01*
X759536Y1068929D01*
X759578Y1069304D01*
X759536Y1069679D01*
X759411Y1070012D01*
X759244Y1070262D01*
X758994Y1070471D01*
X758661Y1070554D01*
G01X762261Y1068054D02*
Y1070554D01*
X760719Y1068762D01*
X762803D01*
G01X753506Y1074442D02*
X753256Y1074567D01*
X752964Y1074650D01*
X752631D01*
X752256Y1074525D01*
X751964Y1074317D01*
X751756Y1074067D01*
X751589Y1073650D01*
X751547Y1073275D01*
X751631Y1072900D01*
X751756Y1072650D01*
X752006Y1072400D01*
X752297Y1072233D01*
X752589Y1072150D01*
X752881D01*
X753172Y1072233D01*
X753422Y1072358D01*
X753631Y1072525D01*
G01X755689Y1072150D02*
Y1074650D01*
X755189Y1074150D01*
G01Y1072150D02*
X756189D01*
G01X758789Y1074650D02*
X758456Y1074567D01*
X758206Y1074358D01*
X758039Y1074108D01*
X757914Y1073775D01*
X757872Y1073400D01*
X757914Y1073025D01*
X758039Y1072692D01*
X758206Y1072442D01*
X758456Y1072233D01*
X758789Y1072150D01*
X759122Y1072233D01*
X759372Y1072442D01*
X759539Y1072692D01*
X759664Y1073025D01*
X759706Y1073400D01*
X759664Y1073775D01*
X759539Y1074108D01*
X759372Y1074358D01*
X759122Y1074567D01*
X758789Y1074650D01*
G01X760972Y1072650D02*
X761222Y1072358D01*
X761556Y1072192D01*
X761931Y1072150D01*
X762264Y1072192D01*
X762597Y1072400D01*
X762806Y1072650D01*
X762847Y1072900D01*
X762764Y1073192D01*
X762472Y1073400D01*
X762181Y1073483D01*
X761806D01*
G01X762181D02*
X762431Y1073608D01*
X762639Y1073817D01*
X762722Y1074067D01*
X762639Y1074317D01*
X762431Y1074525D01*
X762056Y1074650D01*
X761681Y1074608D01*
X761306Y1074442D01*
G01X751446Y1127872D02*
X751321Y1127622D01*
X751238Y1127330D01*
Y1126997D01*
X751363Y1126622D01*
X751571Y1126330D01*
X751821Y1126122D01*
X752238Y1125955D01*
X752613Y1125913D01*
X752988Y1125997D01*
X753238Y1126122D01*
X753488Y1126372D01*
X753655Y1126663D01*
X753738Y1126955D01*
Y1127247D01*
X753655Y1127538D01*
X753530Y1127788D01*
X753363Y1127997D01*
G01X753738Y1130055D02*
X751238D01*
X751738Y1129555D01*
G01X753738D02*
Y1130555D01*
G01Y1133155D02*
X751238D01*
X751738Y1132655D01*
G01X753738D02*
Y1133655D01*
G01Y1136255D02*
X751238D01*
X751738Y1135755D01*
G01X753738D02*
Y1136755D01*
G01X765592Y1142466D02*
X763092D01*
Y1143507D01*
X763217Y1143841D01*
X763384Y1144049D01*
X763717Y1144132D01*
X764050Y1144049D01*
X764259Y1143799D01*
X764384Y1143507D01*
Y1142466D01*
G01Y1143507D02*
X765592Y1144132D01*
G01X763509Y1145607D02*
X763259Y1145857D01*
X763134Y1146149D01*
X763092Y1146482D01*
X763175Y1146899D01*
X763384Y1147191D01*
X763634Y1147274D01*
X763884Y1147232D01*
X764092Y1147066D01*
X764509Y1146232D01*
X764800Y1145857D01*
X765217Y1145607D01*
X765592Y1145524D01*
Y1147274D01*
G01Y1149999D02*
X763092D01*
X764884Y1148457D01*
Y1150541D01*
G01X765217Y1151682D02*
X765425Y1151932D01*
X765550Y1152224D01*
X765592Y1152599D01*
X765509Y1152974D01*
X765342Y1153266D01*
X765050Y1153474D01*
X764717Y1153516D01*
X764384Y1153432D01*
X764175Y1153224D01*
X764009Y1152932D01*
X763967Y1152641D01*
X764009Y1152349D01*
X764175Y1151974D01*
X763092Y1152099D01*
Y1153224D01*
G01X754500Y1153700D02*
X750500D01*
Y1146300D01*
G01X755000Y1172350D02*
X757500D01*
G01X755000Y1171392D02*
Y1173308D01*
G01X757500Y1174617D02*
X755000D01*
Y1175617D01*
X755125Y1175950D01*
X755417Y1176200D01*
X755750Y1176283D01*
X756083Y1176200D01*
X756333Y1175992D01*
X756458Y1175617D01*
Y1174617D01*
G01X755417Y1177758D02*
X755167Y1178008D01*
X755042Y1178300D01*
X755000Y1178633D01*
X755083Y1179050D01*
X755292Y1179342D01*
X755542Y1179425D01*
X755792Y1179383D01*
X756000Y1179217D01*
X756417Y1178383D01*
X756708Y1178008D01*
X757125Y1177758D01*
X757500Y1177675D01*
Y1179425D01*
G01Y1181567D02*
X756958Y1181650D01*
X756500Y1181775D01*
X756083Y1181942D01*
X755625Y1182150D01*
X755000Y1182483D01*
Y1180817D01*
G01X765801Y1156357D02*
X763301D01*
Y1157398D01*
X763426Y1157732D01*
X763593Y1157940D01*
X763926Y1158023D01*
X764259Y1157940D01*
X764468Y1157690D01*
X764593Y1157398D01*
Y1156357D01*
G01Y1157398D02*
X765801Y1158023D01*
G01X763718Y1159498D02*
X763468Y1159748D01*
X763343Y1160040D01*
X763301Y1160373D01*
X763384Y1160790D01*
X763593Y1161082D01*
X763843Y1161165D01*
X764093Y1161123D01*
X764301Y1160957D01*
X764718Y1160123D01*
X765009Y1159748D01*
X765426Y1159498D01*
X765801Y1159415D01*
Y1161165D01*
G01Y1163890D02*
X763301D01*
X765093Y1162348D01*
Y1164432D01*
G01X765509Y1165782D02*
X765718Y1166073D01*
X765801Y1166407D01*
X765718Y1166740D01*
X765468Y1167032D01*
X765093Y1167240D01*
X764718Y1167323D01*
X764259D01*
X763884Y1167240D01*
X763551Y1167032D01*
X763384Y1166782D01*
X763301Y1166490D01*
X763384Y1166157D01*
X763551Y1165907D01*
X763801Y1165740D01*
X764134Y1165657D01*
X764426Y1165740D01*
X764718Y1165948D01*
X764884Y1166198D01*
X764926Y1166490D01*
X764843Y1166823D01*
X764634Y1167073D01*
X764259Y1167323D01*
G01X794000Y1195650D02*
Y1227250D01*
X798700Y1231950D01*
X817300D01*
X822000Y1227250D01*
Y1195650D01*
X794000D01*
G01X836744Y63246D02*
Y60746D01*
G01X835786Y63246D02*
X837702D01*
G01X840761Y63038D02*
X840511Y63163D01*
X840219Y63246D01*
X839886D01*
X839511Y63121D01*
X839219Y62913D01*
X839011Y62663D01*
X838844Y62246D01*
X838802Y61871D01*
X838886Y61496D01*
X839011Y61246D01*
X839261Y60996D01*
X839552Y60829D01*
X839844Y60746D01*
X840136D01*
X840427Y60829D01*
X840677Y60954D01*
X840886Y61121D01*
G01X843444Y60746D02*
Y63246D01*
X841902Y61454D01*
X843986D01*
G01X837592Y57729D02*
X837342Y57854D01*
X837050Y57937D01*
X836717D01*
X836342Y57812D01*
X836050Y57604D01*
X835842Y57354D01*
X835675Y56937D01*
X835633Y56562D01*
X835717Y56187D01*
X835842Y55937D01*
X836092Y55687D01*
X836383Y55520D01*
X836675Y55437D01*
X836967D01*
X837258Y55520D01*
X837508Y55645D01*
X837717Y55812D01*
G01X840275Y55437D02*
Y57937D01*
X838733Y56145D01*
X840817D01*
G01X843375Y55437D02*
Y57937D01*
X841833Y56145D01*
X843917D01*
G01X840564Y45075D02*
X840314Y45200D01*
X840022Y45283D01*
X839689D01*
X839314Y45158D01*
X839022Y44950D01*
X838814Y44700D01*
X838647Y44283D01*
X838605Y43908D01*
X838689Y43533D01*
X838814Y43283D01*
X839064Y43033D01*
X839355Y42866D01*
X839647Y42783D01*
X839939D01*
X840230Y42866D01*
X840480Y42991D01*
X840689Y43158D01*
G01X843247Y42783D02*
Y45283D01*
X841705Y43491D01*
X843789D01*
G01X845847Y45283D02*
X845514Y45200D01*
X845264Y44991D01*
X845097Y44741D01*
X844972Y44408D01*
X844930Y44033D01*
X844972Y43658D01*
X845097Y43325D01*
X845264Y43075D01*
X845514Y42866D01*
X845847Y42783D01*
X846180Y42866D01*
X846430Y43075D01*
X846597Y43325D01*
X846722Y43658D01*
X846764Y44033D01*
X846722Y44408D01*
X846597Y44741D01*
X846430Y44991D01*
X846180Y45200D01*
X845847Y45283D01*
G01X840564Y41375D02*
X840314Y41500D01*
X840022Y41583D01*
X839689D01*
X839314Y41458D01*
X839022Y41250D01*
X838814Y41000D01*
X838647Y40583D01*
X838605Y40208D01*
X838689Y39833D01*
X838814Y39583D01*
X839064Y39333D01*
X839355Y39166D01*
X839647Y39083D01*
X839939D01*
X840230Y39166D01*
X840480Y39291D01*
X840689Y39458D01*
G01X843247Y39083D02*
Y41583D01*
X841705Y39791D01*
X843789D01*
G01X845055Y41166D02*
X845305Y41416D01*
X845597Y41541D01*
X845930Y41583D01*
X846347Y41500D01*
X846639Y41291D01*
X846722Y41041D01*
X846680Y40791D01*
X846514Y40583D01*
X845680Y40166D01*
X845305Y39875D01*
X845055Y39458D01*
X844972Y39083D01*
X846722D01*
G01X837592Y54278D02*
X837342Y54403D01*
X837050Y54486D01*
X836717D01*
X836342Y54361D01*
X836050Y54153D01*
X835842Y53903D01*
X835675Y53486D01*
X835633Y53111D01*
X835717Y52736D01*
X835842Y52486D01*
X836092Y52236D01*
X836383Y52069D01*
X836675Y51986D01*
X836967D01*
X837258Y52069D01*
X837508Y52194D01*
X837717Y52361D01*
G01X840275Y51986D02*
Y54486D01*
X838733Y52694D01*
X840817D01*
G01X842083Y53028D02*
X842375Y53319D01*
X842625Y53486D01*
X842958Y53569D01*
X843250Y53486D01*
X843458Y53319D01*
X843625Y53069D01*
X843667Y52778D01*
X843625Y52528D01*
X843458Y52278D01*
X843208Y52069D01*
X842917Y51986D01*
X842583Y52069D01*
X842292Y52319D01*
X842125Y52694D01*
X842083Y53111D01*
X842167Y53653D01*
X842292Y53944D01*
X842500Y54236D01*
X842792Y54444D01*
X843083Y54486D01*
X843375Y54403D01*
X843583Y54194D01*
G01X844954Y86869D02*
X844704Y86994D01*
X844412Y87077D01*
X844079D01*
X843704Y86952D01*
X843412Y86744D01*
X843204Y86494D01*
X843037Y86077D01*
X842995Y85702D01*
X843079Y85327D01*
X843204Y85077D01*
X843454Y84827D01*
X843745Y84660D01*
X844037Y84577D01*
X844329D01*
X844620Y84660D01*
X844870Y84785D01*
X845079Y84952D01*
G01X846220Y85077D02*
X846470Y84785D01*
X846804Y84619D01*
X847179Y84577D01*
X847512Y84619D01*
X847845Y84827D01*
X848054Y85077D01*
X848095Y85327D01*
X848012Y85619D01*
X847720Y85827D01*
X847429Y85910D01*
X847054D01*
G01X847429D02*
X847679Y86035D01*
X847887Y86244D01*
X847970Y86494D01*
X847887Y86744D01*
X847679Y86952D01*
X847304Y87077D01*
X846929Y87035D01*
X846554Y86869D01*
G01X849445Y86660D02*
X849695Y86910D01*
X849987Y87035D01*
X850320Y87077D01*
X850737Y86994D01*
X851029Y86785D01*
X851112Y86535D01*
X851070Y86285D01*
X850904Y86077D01*
X850070Y85660D01*
X849695Y85369D01*
X849445Y84952D01*
X849362Y84577D01*
X851112D01*
G01X803151Y85154D02*
Y82654D01*
G01X802193Y85154D02*
X804109D01*
G01X807168Y84946D02*
X806918Y85071D01*
X806626Y85154D01*
X806293D01*
X805918Y85029D01*
X805626Y84821D01*
X805418Y84571D01*
X805251Y84154D01*
X805209Y83779D01*
X805293Y83404D01*
X805418Y83154D01*
X805668Y82904D01*
X805959Y82737D01*
X806251Y82654D01*
X806543D01*
X806834Y82737D01*
X807084Y82862D01*
X807293Y83029D01*
G01X809351Y82654D02*
Y85154D01*
X808851Y84654D01*
G01Y82654D02*
X809851D01*
G01X812368D02*
X812451Y83196D01*
X812576Y83654D01*
X812743Y84071D01*
X812951Y84529D01*
X813284Y85154D01*
X811618D01*
G01X844428Y83141D02*
X844178Y83266D01*
X843886Y83349D01*
X843553D01*
X843178Y83224D01*
X842886Y83016D01*
X842678Y82766D01*
X842511Y82349D01*
X842469Y81974D01*
X842553Y81599D01*
X842678Y81349D01*
X842928Y81099D01*
X843219Y80932D01*
X843511Y80849D01*
X843803D01*
X844094Y80932D01*
X844344Y81057D01*
X844553Y81224D01*
G01X845694D02*
X845944Y81016D01*
X846236Y80891D01*
X846611Y80849D01*
X846986Y80932D01*
X847278Y81099D01*
X847486Y81391D01*
X847528Y81724D01*
X847444Y82057D01*
X847236Y82266D01*
X846944Y82432D01*
X846653Y82474D01*
X846361Y82432D01*
X845986Y82266D01*
X846111Y83349D01*
X847236D01*
G01X848794Y81349D02*
X849044Y81057D01*
X849378Y80891D01*
X849753Y80849D01*
X850086Y80891D01*
X850419Y81099D01*
X850628Y81349D01*
X850669Y81599D01*
X850586Y81891D01*
X850294Y82099D01*
X850003Y82182D01*
X849628D01*
G01X850003D02*
X850253Y82307D01*
X850461Y82516D01*
X850544Y82766D01*
X850461Y83016D01*
X850253Y83224D01*
X849878Y83349D01*
X849503Y83307D01*
X849128Y83141D01*
G01X852811Y80849D02*
Y83349D01*
X852311Y82849D01*
G01Y80849D02*
X853311D01*
G01X803935Y670488D02*
Y667988D01*
G01X802977Y670488D02*
X804893D01*
G01X807952Y670280D02*
X807702Y670405D01*
X807410Y670488D01*
X807077D01*
X806702Y670363D01*
X806410Y670155D01*
X806202Y669905D01*
X806035Y669488D01*
X805993Y669113D01*
X806077Y668738D01*
X806202Y668488D01*
X806452Y668238D01*
X806743Y668071D01*
X807035Y667988D01*
X807327D01*
X807618Y668071D01*
X807868Y668196D01*
X808077Y668363D01*
G01X810135Y667988D02*
Y670488D01*
X809635Y669988D01*
G01Y667988D02*
X810635D01*
G01X812318Y668363D02*
X812568Y668155D01*
X812860Y668030D01*
X813235Y667988D01*
X813610Y668071D01*
X813902Y668238D01*
X814110Y668530D01*
X814152Y668863D01*
X814068Y669196D01*
X813860Y669405D01*
X813568Y669571D01*
X813277Y669613D01*
X812985Y669571D01*
X812610Y669405D01*
X812735Y670488D01*
X813860D01*
G01X803050Y1242300D02*
Y1239800D01*
G01X802092Y1242300D02*
X804008D01*
G01X807067Y1242092D02*
X806817Y1242217D01*
X806525Y1242300D01*
X806192D01*
X805817Y1242175D01*
X805525Y1241967D01*
X805317Y1241717D01*
X805150Y1241300D01*
X805108Y1240925D01*
X805192Y1240550D01*
X805317Y1240300D01*
X805567Y1240050D01*
X805858Y1239883D01*
X806150Y1239800D01*
X806442D01*
X806733Y1239883D01*
X806983Y1240008D01*
X807192Y1240175D01*
G01X809250Y1239800D02*
Y1242300D01*
X808750Y1241800D01*
G01Y1239800D02*
X809750D01*
G01X811433Y1240300D02*
X811683Y1240008D01*
X812017Y1239842D01*
X812392Y1239800D01*
X812725Y1239842D01*
X813058Y1240050D01*
X813267Y1240300D01*
X813308Y1240550D01*
X813225Y1240842D01*
X812933Y1241050D01*
X812642Y1241133D01*
X812267D01*
G01X812642D02*
X812892Y1241258D01*
X813100Y1241467D01*
X813183Y1241717D01*
X813100Y1241967D01*
X812892Y1242175D01*
X812517Y1242300D01*
X812142Y1242258D01*
X811767Y1242092D01*
G01X846734Y1497264D02*
X844234D01*
Y1498305D01*
X844359Y1498639D01*
X844526Y1498847D01*
X844859Y1498930D01*
X845192Y1498847D01*
X845401Y1498597D01*
X845526Y1498305D01*
Y1497264D01*
G01Y1498305D02*
X846734Y1498930D01*
G01X846234Y1500280D02*
X846526Y1500530D01*
X846692Y1500864D01*
X846734Y1501239D01*
X846692Y1501572D01*
X846484Y1501905D01*
X846234Y1502114D01*
X845984Y1502155D01*
X845692Y1502072D01*
X845484Y1501780D01*
X845401Y1501489D01*
Y1501114D01*
G01Y1501489D02*
X845276Y1501739D01*
X845067Y1501947D01*
X844817Y1502030D01*
X844567Y1501947D01*
X844359Y1501739D01*
X844234Y1501364D01*
X844276Y1500989D01*
X844442Y1500614D01*
G01X845692Y1503505D02*
X845401Y1503797D01*
X845234Y1504047D01*
X845151Y1504380D01*
X845234Y1504672D01*
X845401Y1504880D01*
X845651Y1505047D01*
X845942Y1505089D01*
X846192Y1505047D01*
X846442Y1504880D01*
X846651Y1504630D01*
X846734Y1504339D01*
X846651Y1504005D01*
X846401Y1503714D01*
X846026Y1503547D01*
X845609Y1503505D01*
X845067Y1503589D01*
X844776Y1503714D01*
X844484Y1503922D01*
X844276Y1504214D01*
X844234Y1504505D01*
X844317Y1504797D01*
X844526Y1505005D01*
G01X845692Y1506605D02*
X845401Y1506897D01*
X845234Y1507147D01*
X845151Y1507480D01*
X845234Y1507772D01*
X845401Y1507980D01*
X845651Y1508147D01*
X845942Y1508189D01*
X846192Y1508147D01*
X846442Y1507980D01*
X846651Y1507730D01*
X846734Y1507439D01*
X846651Y1507105D01*
X846401Y1506814D01*
X846026Y1506647D01*
X845609Y1506605D01*
X845067Y1506689D01*
X844776Y1506814D01*
X844484Y1507022D01*
X844276Y1507314D01*
X844234Y1507605D01*
X844317Y1507897D01*
X844526Y1508105D01*
G01X839370Y1481679D02*
X839120Y1481804D01*
X838828Y1481887D01*
X838495D01*
X838120Y1481762D01*
X837828Y1481554D01*
X837620Y1481304D01*
X837453Y1480887D01*
X837411Y1480512D01*
X837495Y1480137D01*
X837620Y1479887D01*
X837870Y1479637D01*
X838161Y1479470D01*
X838453Y1479387D01*
X838745D01*
X839036Y1479470D01*
X839286Y1479595D01*
X839495Y1479762D01*
G01X840636D02*
X840886Y1479554D01*
X841178Y1479429D01*
X841553Y1479387D01*
X841928Y1479470D01*
X842220Y1479637D01*
X842428Y1479929D01*
X842470Y1480262D01*
X842386Y1480595D01*
X842178Y1480804D01*
X841886Y1480970D01*
X841595Y1481012D01*
X841303Y1480970D01*
X840928Y1480804D01*
X841053Y1481887D01*
X842178D01*
G01X843736Y1479887D02*
X843986Y1479595D01*
X844320Y1479429D01*
X844695Y1479387D01*
X845028Y1479429D01*
X845361Y1479637D01*
X845570Y1479887D01*
X845611Y1480137D01*
X845528Y1480429D01*
X845236Y1480637D01*
X844945Y1480720D01*
X844570D01*
G01X844945D02*
X845195Y1480845D01*
X845403Y1481054D01*
X845486Y1481304D01*
X845403Y1481554D01*
X845195Y1481762D01*
X844820Y1481887D01*
X844445Y1481845D01*
X844070Y1481679D01*
G01X846836Y1479762D02*
X847086Y1479554D01*
X847378Y1479429D01*
X847753Y1479387D01*
X848128Y1479470D01*
X848420Y1479637D01*
X848628Y1479929D01*
X848670Y1480262D01*
X848586Y1480595D01*
X848378Y1480804D01*
X848086Y1480970D01*
X847795Y1481012D01*
X847503Y1480970D01*
X847128Y1480804D01*
X847253Y1481887D01*
X848378D01*
G01X839370Y1486180D02*
X839120Y1486305D01*
X838828Y1486388D01*
X838495D01*
X838120Y1486263D01*
X837828Y1486055D01*
X837620Y1485805D01*
X837453Y1485388D01*
X837411Y1485013D01*
X837495Y1484638D01*
X837620Y1484388D01*
X837870Y1484138D01*
X838161Y1483971D01*
X838453Y1483888D01*
X838745D01*
X839036Y1483971D01*
X839286Y1484096D01*
X839495Y1484263D01*
G01X840636D02*
X840886Y1484055D01*
X841178Y1483930D01*
X841553Y1483888D01*
X841928Y1483971D01*
X842220Y1484138D01*
X842428Y1484430D01*
X842470Y1484763D01*
X842386Y1485096D01*
X842178Y1485305D01*
X841886Y1485471D01*
X841595Y1485513D01*
X841303Y1485471D01*
X840928Y1485305D01*
X841053Y1486388D01*
X842178D01*
G01X843736Y1484388D02*
X843986Y1484096D01*
X844320Y1483930D01*
X844695Y1483888D01*
X845028Y1483930D01*
X845361Y1484138D01*
X845570Y1484388D01*
X845611Y1484638D01*
X845528Y1484930D01*
X845236Y1485138D01*
X844945Y1485221D01*
X844570D01*
G01X844945D02*
X845195Y1485346D01*
X845403Y1485555D01*
X845486Y1485805D01*
X845403Y1486055D01*
X845195Y1486263D01*
X844820Y1486388D01*
X844445Y1486346D01*
X844070Y1486180D01*
G01X846961Y1484930D02*
X847253Y1485221D01*
X847503Y1485388D01*
X847836Y1485471D01*
X848128Y1485388D01*
X848336Y1485221D01*
X848503Y1484971D01*
X848545Y1484680D01*
X848503Y1484430D01*
X848336Y1484180D01*
X848086Y1483971D01*
X847795Y1483888D01*
X847461Y1483971D01*
X847170Y1484221D01*
X847003Y1484596D01*
X846961Y1485013D01*
X847045Y1485555D01*
X847170Y1485846D01*
X847378Y1486138D01*
X847670Y1486346D01*
X847961Y1486388D01*
X848253Y1486305D01*
X848461Y1486096D01*
G01X835559Y1543928D02*
Y1546428D01*
X836600D01*
X836934Y1546303D01*
X837142Y1546136D01*
X837225Y1545803D01*
X837142Y1545470D01*
X836892Y1545261D01*
X836600Y1545136D01*
X835559D01*
G01X836600D02*
X837225Y1543928D01*
G01X839492D02*
Y1546428D01*
X838992Y1545928D01*
G01Y1543928D02*
X839992D01*
G01X841675Y1544428D02*
X841925Y1544136D01*
X842259Y1543970D01*
X842634Y1543928D01*
X842967Y1543970D01*
X843300Y1544178D01*
X843509Y1544428D01*
X843550Y1544678D01*
X843467Y1544970D01*
X843175Y1545178D01*
X842884Y1545261D01*
X842509D01*
G01X842884D02*
X843134Y1545386D01*
X843342Y1545595D01*
X843425Y1545845D01*
X843342Y1546095D01*
X843134Y1546303D01*
X842759Y1546428D01*
X842384Y1546386D01*
X842009Y1546220D01*
G01X844400Y1536800D02*
Y1540800D01*
X837000D01*
G01X830272Y1526486D02*
X832064D01*
X832439Y1526653D01*
X832689Y1526986D01*
X832772Y1527403D01*
X832689Y1527820D01*
X832439Y1528153D01*
X832064Y1528320D01*
X830272D01*
G01X832772Y1531003D02*
X830272D01*
X832064Y1529461D01*
Y1531545D01*
G01X832772Y1533603D02*
X832730Y1533895D01*
X832605Y1534228D01*
X832397Y1534436D01*
X832105Y1534520D01*
X831814Y1534436D01*
X831564Y1534186D01*
X831439Y1533811D01*
Y1533395D01*
X831355Y1533145D01*
X831147Y1532936D01*
X830855Y1532853D01*
X830564Y1532978D01*
X830355Y1533270D01*
X830272Y1533603D01*
X830355Y1533936D01*
X830564Y1534228D01*
X830855Y1534353D01*
X831147Y1534270D01*
X831355Y1534061D01*
X831439Y1533811D01*
Y1533395D01*
X831564Y1533020D01*
X831814Y1532770D01*
X832105Y1532686D01*
X832397Y1532770D01*
X832605Y1532978D01*
X832730Y1533311D01*
X832772Y1533603D01*
G01X851458Y1525691D02*
X838058D01*
G01Y1535691D02*
X851458D01*
G01X838058Y1525691D02*
Y1535691D01*
G01X820034Y1558128D02*
Y1560628D01*
X820868D01*
X821201Y1560503D01*
X821451Y1560336D01*
X821659Y1560086D01*
X821826Y1559795D01*
X821868Y1559378D01*
X821826Y1558961D01*
X821659Y1558670D01*
X821451Y1558420D01*
X821201Y1558253D01*
X820868Y1558128D01*
X820034D01*
G01X823218D02*
Y1560628D01*
X824218D01*
X824551Y1560503D01*
X824801Y1560211D01*
X824884Y1559878D01*
X824801Y1559545D01*
X824593Y1559295D01*
X824218Y1559170D01*
X823218D01*
G01X827484Y1559461D02*
X827651Y1559586D01*
X827776Y1559795D01*
X827859Y1560086D01*
X827776Y1560336D01*
X827609Y1560503D01*
X827318Y1560628D01*
X826193D01*
Y1558128D01*
X827568D01*
X827859Y1558295D01*
X828026Y1558545D01*
X828109Y1558836D01*
X828026Y1559128D01*
X827776Y1559378D01*
X827484Y1559461D01*
X826193D01*
G01X830251Y1558128D02*
Y1560628D01*
X829751Y1560128D01*
G01Y1558128D02*
X830751D01*
G01X818072Y1581294D02*
X921672D01*
Y1658268D01*
X818072D01*
Y1581294D01*
G01X872046Y35595D02*
Y38095D01*
X873087D01*
X873421Y37970D01*
X873629Y37803D01*
X873712Y37470D01*
X873629Y37137D01*
X873379Y36928D01*
X873087Y36803D01*
X872046D01*
G01X873087D02*
X873712Y35595D01*
G01X875979D02*
Y38095D01*
X875479Y37595D01*
G01Y35595D02*
X876479D01*
G01X879079Y38095D02*
X878746Y38012D01*
X878496Y37803D01*
X878329Y37553D01*
X878204Y37220D01*
X878162Y36845D01*
X878204Y36470D01*
X878329Y36137D01*
X878496Y35887D01*
X878746Y35678D01*
X879079Y35595D01*
X879412Y35678D01*
X879662Y35887D01*
X879829Y36137D01*
X879954Y36470D01*
X879996Y36845D01*
X879954Y37220D01*
X879829Y37553D01*
X879662Y37803D01*
X879412Y38012D01*
X879079Y38095D01*
G01X882179D02*
X881846Y38012D01*
X881596Y37803D01*
X881429Y37553D01*
X881304Y37220D01*
X881262Y36845D01*
X881304Y36470D01*
X881429Y36137D01*
X881596Y35887D01*
X881846Y35678D01*
X882179Y35595D01*
X882512Y35678D01*
X882762Y35887D01*
X882929Y36137D01*
X883054Y36470D01*
X883096Y36845D01*
X883054Y37220D01*
X882929Y37553D01*
X882762Y37803D01*
X882512Y38012D01*
X882179Y38095D01*
G01X885779Y35595D02*
Y38095D01*
X884237Y36303D01*
X886321D01*
G01X879800Y43500D02*
Y39500D01*
X887200D01*
G01X884979Y50870D02*
Y68870D01*
G01X873779Y50870D02*
X884979D01*
G01X846579D02*
Y68870D01*
G01X857779Y50870D02*
X846579D01*
G01X856512Y91150D02*
X875212D01*
Y80850D01*
X856512D01*
Y91150D01*
G01X884979Y68870D02*
X873779D01*
G01X846579D02*
X857779D01*
G01X860567Y357600D02*
Y360100D01*
X861608D01*
X861942Y359975D01*
X862150Y359808D01*
X862233Y359475D01*
X862150Y359142D01*
X861900Y358933D01*
X861608Y358808D01*
X860567D01*
G01X861608D02*
X862233Y357600D01*
G01X863708Y359683D02*
X863958Y359933D01*
X864250Y360058D01*
X864583Y360100D01*
X865000Y360017D01*
X865292Y359808D01*
X865375Y359558D01*
X865333Y359308D01*
X865167Y359100D01*
X864333Y358683D01*
X863958Y358392D01*
X863708Y357975D01*
X863625Y357600D01*
X865375D01*
G01X867600Y360100D02*
X867267Y360017D01*
X867017Y359808D01*
X866850Y359558D01*
X866725Y359225D01*
X866683Y358850D01*
X866725Y358475D01*
X866850Y358142D01*
X867017Y357892D01*
X867267Y357683D01*
X867600Y357600D01*
X867933Y357683D01*
X868183Y357892D01*
X868350Y358142D01*
X868475Y358475D01*
X868517Y358850D01*
X868475Y359225D01*
X868350Y359558D01*
X868183Y359808D01*
X867933Y360017D01*
X867600Y360100D01*
G01X870700D02*
X870367Y360017D01*
X870117Y359808D01*
X869950Y359558D01*
X869825Y359225D01*
X869783Y358850D01*
X869825Y358475D01*
X869950Y358142D01*
X870117Y357892D01*
X870367Y357683D01*
X870700Y357600D01*
X871033Y357683D01*
X871283Y357892D01*
X871450Y358142D01*
X871575Y358475D01*
X871617Y358850D01*
X871575Y359225D01*
X871450Y359558D01*
X871283Y359808D01*
X871033Y360017D01*
X870700Y360100D01*
G01X880250Y357100D02*
Y361100D01*
X872850D01*
G01X859468Y377560D02*
Y380060D01*
X860509D01*
X860843Y379935D01*
X861051Y379768D01*
X861134Y379435D01*
X861051Y379102D01*
X860801Y378893D01*
X860509Y378768D01*
X859468D01*
G01X860509D02*
X861134Y377560D01*
G01X862693Y377852D02*
X862984Y377643D01*
X863318Y377560D01*
X863651Y377643D01*
X863943Y377893D01*
X864151Y378268D01*
X864234Y378643D01*
Y379102D01*
X864151Y379477D01*
X863943Y379810D01*
X863693Y379977D01*
X863401Y380060D01*
X863068Y379977D01*
X862818Y379810D01*
X862651Y379560D01*
X862568Y379227D01*
X862651Y378935D01*
X862859Y378643D01*
X863109Y378477D01*
X863401Y378435D01*
X863734Y378518D01*
X863984Y378727D01*
X864234Y379102D01*
G01X865793Y377852D02*
X866084Y377643D01*
X866418Y377560D01*
X866751Y377643D01*
X867043Y377893D01*
X867251Y378268D01*
X867334Y378643D01*
Y379102D01*
X867251Y379477D01*
X867043Y379810D01*
X866793Y379977D01*
X866501Y380060D01*
X866168Y379977D01*
X865918Y379810D01*
X865751Y379560D01*
X865668Y379227D01*
X865751Y378935D01*
X865959Y378643D01*
X866209Y378477D01*
X866501Y378435D01*
X866834Y378518D01*
X867084Y378727D01*
X867334Y379102D01*
G01X868809Y378602D02*
X869101Y378893D01*
X869351Y379060D01*
X869684Y379143D01*
X869976Y379060D01*
X870184Y378893D01*
X870351Y378643D01*
X870393Y378352D01*
X870351Y378102D01*
X870184Y377852D01*
X869934Y377643D01*
X869643Y377560D01*
X869309Y377643D01*
X869018Y377893D01*
X868851Y378268D01*
X868809Y378685D01*
X868893Y379227D01*
X869018Y379518D01*
X869226Y379810D01*
X869518Y380018D01*
X869809Y380060D01*
X870101Y379977D01*
X870309Y379768D01*
G01X872857Y380495D02*
Y376495D01*
X880257D01*
G01X852871Y442962D02*
Y445462D01*
X853912D01*
X854246Y445337D01*
X854454Y445170D01*
X854537Y444837D01*
X854454Y444504D01*
X854204Y444295D01*
X853912Y444170D01*
X852871D01*
G01X853912D02*
X854537Y442962D01*
G01X856804D02*
Y445462D01*
X856304Y444962D01*
G01Y442962D02*
X857304D01*
G01X858987Y443337D02*
X859237Y443129D01*
X859529Y443004D01*
X859904Y442962D01*
X860279Y443045D01*
X860571Y443212D01*
X860779Y443504D01*
X860821Y443837D01*
X860737Y444170D01*
X860529Y444379D01*
X860237Y444545D01*
X859946Y444587D01*
X859654Y444545D01*
X859279Y444379D01*
X859404Y445462D01*
X860529D01*
G01X862296Y443254D02*
X862587Y443045D01*
X862921Y442962D01*
X863254Y443045D01*
X863546Y443295D01*
X863754Y443670D01*
X863837Y444045D01*
Y444504D01*
X863754Y444879D01*
X863546Y445212D01*
X863296Y445379D01*
X863004Y445462D01*
X862671Y445379D01*
X862421Y445212D01*
X862254Y444962D01*
X862171Y444629D01*
X862254Y444337D01*
X862462Y444045D01*
X862712Y443879D01*
X863004Y443837D01*
X863337Y443920D01*
X863587Y444129D01*
X863837Y444504D01*
G01X880054Y443462D02*
Y447462D01*
X872654D01*
G01X852917Y447700D02*
Y450200D01*
X853958D01*
X854292Y450075D01*
X854500Y449908D01*
X854583Y449575D01*
X854500Y449242D01*
X854250Y449033D01*
X853958Y448908D01*
X852917D01*
G01X853958D02*
X854583Y447700D01*
G01X856850D02*
Y450200D01*
X856350Y449700D01*
G01Y447700D02*
X857350D01*
G01X859867D02*
X859950Y448242D01*
X860075Y448700D01*
X860242Y449117D01*
X860450Y449575D01*
X860783Y450200D01*
X859117D01*
G01X863050Y447700D02*
X863342Y447742D01*
X863675Y447867D01*
X863883Y448075D01*
X863967Y448367D01*
X863883Y448658D01*
X863633Y448908D01*
X863258Y449033D01*
X862842D01*
X862592Y449117D01*
X862383Y449325D01*
X862300Y449617D01*
X862425Y449908D01*
X862717Y450117D01*
X863050Y450200D01*
X863383Y450117D01*
X863675Y449908D01*
X863800Y449617D01*
X863717Y449325D01*
X863508Y449117D01*
X863258Y449033D01*
X862842D01*
X862467Y448908D01*
X862217Y448658D01*
X862133Y448367D01*
X862217Y448075D01*
X862425Y447867D01*
X862758Y447742D01*
X863050Y447700D01*
G01X880100Y448200D02*
Y452200D01*
X872700D01*
G01X852917Y452400D02*
Y454900D01*
X853958D01*
X854292Y454775D01*
X854500Y454608D01*
X854583Y454275D01*
X854500Y453942D01*
X854250Y453733D01*
X853958Y453608D01*
X852917D01*
G01X853958D02*
X854583Y452400D01*
G01X856850D02*
Y454900D01*
X856350Y454400D01*
G01Y452400D02*
X857350D01*
G01X859950D02*
X860242Y452442D01*
X860575Y452567D01*
X860783Y452775D01*
X860867Y453067D01*
X860783Y453358D01*
X860533Y453608D01*
X860158Y453733D01*
X859742D01*
X859492Y453817D01*
X859283Y454025D01*
X859200Y454317D01*
X859325Y454608D01*
X859617Y454817D01*
X859950Y454900D01*
X860283Y454817D01*
X860575Y454608D01*
X860700Y454317D01*
X860617Y454025D01*
X860408Y453817D01*
X860158Y453733D01*
X859742D01*
X859367Y453608D01*
X859117Y453358D01*
X859033Y453067D01*
X859117Y452775D01*
X859325Y452567D01*
X859658Y452442D01*
X859950Y452400D01*
G01X863050D02*
Y454900D01*
X862550Y454400D01*
G01Y452400D02*
X863550D01*
G01X880100Y452900D02*
Y456900D01*
X872700D01*
G01X853817Y470267D02*
Y472767D01*
X854858D01*
X855192Y472642D01*
X855400Y472475D01*
X855483Y472142D01*
X855400Y471809D01*
X855150Y471600D01*
X854858Y471475D01*
X853817D01*
G01X854858D02*
X855483Y470267D01*
G01X856958Y471309D02*
X857250Y471600D01*
X857500Y471767D01*
X857833Y471850D01*
X858125Y471767D01*
X858333Y471600D01*
X858500Y471350D01*
X858542Y471059D01*
X858500Y470809D01*
X858333Y470559D01*
X858083Y470350D01*
X857792Y470267D01*
X857458Y470350D01*
X857167Y470600D01*
X857000Y470975D01*
X856958Y471392D01*
X857042Y471934D01*
X857167Y472225D01*
X857375Y472517D01*
X857667Y472725D01*
X857958Y472767D01*
X858250Y472684D01*
X858458Y472475D01*
G01X860850Y470267D02*
Y472767D01*
X860350Y472267D01*
G01Y470267D02*
X861350D01*
G01X863950D02*
X864242Y470309D01*
X864575Y470434D01*
X864783Y470642D01*
X864867Y470934D01*
X864783Y471225D01*
X864533Y471475D01*
X864158Y471600D01*
X863742D01*
X863492Y471684D01*
X863283Y471892D01*
X863200Y472184D01*
X863325Y472475D01*
X863617Y472684D01*
X863950Y472767D01*
X864283Y472684D01*
X864575Y472475D01*
X864700Y472184D01*
X864617Y471892D01*
X864408Y471684D01*
X864158Y471600D01*
X863742D01*
X863367Y471475D01*
X863117Y471225D01*
X863033Y470934D01*
X863117Y470642D01*
X863325Y470434D01*
X863658Y470309D01*
X863950Y470267D01*
G01X880200Y469100D02*
Y473100D01*
X872800D01*
G01X852971Y457062D02*
Y459562D01*
X854012D01*
X854346Y459437D01*
X854554Y459270D01*
X854637Y458937D01*
X854554Y458604D01*
X854304Y458395D01*
X854012Y458270D01*
X852971D01*
G01X854012D02*
X854637Y457062D01*
G01X856904D02*
Y459562D01*
X856404Y459062D01*
G01Y457062D02*
X857404D01*
G01X859087Y457437D02*
X859337Y457229D01*
X859629Y457104D01*
X860004Y457062D01*
X860379Y457145D01*
X860671Y457312D01*
X860879Y457604D01*
X860921Y457937D01*
X860837Y458270D01*
X860629Y458479D01*
X860337Y458645D01*
X860046Y458687D01*
X859754Y458645D01*
X859379Y458479D01*
X859504Y459562D01*
X860629D01*
G01X863021Y457062D02*
X863104Y457604D01*
X863229Y458062D01*
X863396Y458479D01*
X863604Y458937D01*
X863937Y459562D01*
X862271D01*
G01X880154Y457562D02*
Y461562D01*
X872754D01*
G01X851410Y462005D02*
Y464505D01*
X852451D01*
X852785Y464380D01*
X852993Y464213D01*
X853076Y463880D01*
X852993Y463547D01*
X852743Y463338D01*
X852451Y463213D01*
X851410D01*
G01X852451D02*
X853076Y462005D01*
G01X855343D02*
Y464505D01*
X854843Y464005D01*
G01Y462005D02*
X855843D01*
G01X858443Y464505D02*
X858110Y464422D01*
X857860Y464213D01*
X857693Y463963D01*
X857568Y463630D01*
X857526Y463255D01*
X857568Y462880D01*
X857693Y462547D01*
X857860Y462297D01*
X858110Y462088D01*
X858443Y462005D01*
X858776Y462088D01*
X859026Y462297D01*
X859193Y462547D01*
X859318Y462880D01*
X859360Y463255D01*
X859318Y463630D01*
X859193Y463963D01*
X859026Y464213D01*
X858776Y464422D01*
X858443Y464505D01*
G01X861543D02*
X861210Y464422D01*
X860960Y464213D01*
X860793Y463963D01*
X860668Y463630D01*
X860626Y463255D01*
X860668Y462880D01*
X860793Y462547D01*
X860960Y462297D01*
X861210Y462088D01*
X861543Y462005D01*
X861876Y462088D01*
X862126Y462297D01*
X862293Y462547D01*
X862418Y462880D01*
X862460Y463255D01*
X862418Y463630D01*
X862293Y463963D01*
X862126Y464213D01*
X861876Y464422D01*
X861543Y464505D01*
G01X864643Y462005D02*
Y464505D01*
X864143Y464005D01*
G01Y462005D02*
X865143D01*
G01X880143Y462505D02*
Y466505D01*
X872743D01*
G01X888800Y503800D02*
Y501300D01*
G01X887842Y503800D02*
X889758D01*
G01X891067Y501300D02*
Y503800D01*
X892067D01*
X892400Y503675D01*
X892650Y503383D01*
X892733Y503050D01*
X892650Y502717D01*
X892442Y502467D01*
X892067Y502342D01*
X891067D01*
G01X894208Y503383D02*
X894458Y503633D01*
X894750Y503758D01*
X895083Y503800D01*
X895500Y503717D01*
X895792Y503508D01*
X895875Y503258D01*
X895833Y503008D01*
X895667Y502800D01*
X894833Y502383D01*
X894458Y502092D01*
X894208Y501675D01*
X894125Y501300D01*
X895875D01*
G01X898100Y503800D02*
X897767Y503717D01*
X897517Y503508D01*
X897350Y503258D01*
X897225Y502925D01*
X897183Y502550D01*
X897225Y502175D01*
X897350Y501842D01*
X897517Y501592D01*
X897767Y501383D01*
X898100Y501300D01*
X898433Y501383D01*
X898683Y501592D01*
X898850Y501842D01*
X898975Y502175D01*
X899017Y502550D01*
X898975Y502925D01*
X898850Y503258D01*
X898683Y503508D01*
X898433Y503717D01*
X898100Y503800D01*
G01X900283Y501800D02*
X900533Y501508D01*
X900867Y501342D01*
X901242Y501300D01*
X901575Y501342D01*
X901908Y501550D01*
X902117Y501800D01*
X902158Y502050D01*
X902075Y502342D01*
X901783Y502550D01*
X901492Y502633D01*
X901117D01*
G01X901492D02*
X901742Y502758D01*
X901950Y502967D01*
X902033Y503217D01*
X901950Y503467D01*
X901742Y503675D01*
X901367Y503800D01*
X900992Y503758D01*
X900617Y503592D01*
G01X866110Y545905D02*
Y548405D01*
X867151D01*
X867485Y548280D01*
X867693Y548113D01*
X867776Y547780D01*
X867693Y547447D01*
X867443Y547238D01*
X867151Y547113D01*
X866110D01*
G01X867151D02*
X867776Y545905D01*
G01X870043D02*
Y548405D01*
X869543Y547905D01*
G01Y545905D02*
X870543D01*
G01X873143Y548405D02*
X872810Y548322D01*
X872560Y548113D01*
X872393Y547863D01*
X872268Y547530D01*
X872226Y547155D01*
X872268Y546780D01*
X872393Y546447D01*
X872560Y546197D01*
X872810Y545988D01*
X873143Y545905D01*
X873476Y545988D01*
X873726Y546197D01*
X873893Y546447D01*
X874018Y546780D01*
X874060Y547155D01*
X874018Y547530D01*
X873893Y547863D01*
X873726Y548113D01*
X873476Y548322D01*
X873143Y548405D01*
G01X876243D02*
X875910Y548322D01*
X875660Y548113D01*
X875493Y547863D01*
X875368Y547530D01*
X875326Y547155D01*
X875368Y546780D01*
X875493Y546447D01*
X875660Y546197D01*
X875910Y545988D01*
X876243Y545905D01*
X876576Y545988D01*
X876826Y546197D01*
X876993Y546447D01*
X877118Y546780D01*
X877160Y547155D01*
X877118Y547530D01*
X876993Y547863D01*
X876826Y548113D01*
X876576Y548322D01*
X876243Y548405D01*
G01X878551Y547988D02*
X878801Y548238D01*
X879093Y548363D01*
X879426Y548405D01*
X879843Y548322D01*
X880135Y548113D01*
X880218Y547863D01*
X880176Y547613D01*
X880010Y547405D01*
X879176Y546988D01*
X878801Y546697D01*
X878551Y546280D01*
X878468Y545905D01*
X880218D01*
G01X881343Y540405D02*
Y544405D01*
X873943D01*
G01X888869Y538087D02*
Y535587D01*
G01X887911Y538087D02*
X889827D01*
G01X891136Y535587D02*
Y538087D01*
X892136D01*
X892469Y537962D01*
X892719Y537670D01*
X892802Y537337D01*
X892719Y537004D01*
X892511Y536754D01*
X892136Y536629D01*
X891136D01*
G01X894277Y537670D02*
X894527Y537920D01*
X894819Y538045D01*
X895152Y538087D01*
X895569Y538004D01*
X895861Y537795D01*
X895944Y537545D01*
X895902Y537295D01*
X895736Y537087D01*
X894902Y536670D01*
X894527Y536379D01*
X894277Y535962D01*
X894194Y535587D01*
X895944D01*
G01X898169D02*
Y538087D01*
X897669Y537587D01*
G01Y535587D02*
X898669D01*
G01X901269D02*
Y538087D01*
X900769Y537587D01*
G01Y535587D02*
X901769D01*
G01X888943Y523305D02*
Y520805D01*
G01X887985Y523305D02*
X889901D01*
G01X891210Y520805D02*
Y523305D01*
X892210D01*
X892543Y523180D01*
X892793Y522888D01*
X892876Y522555D01*
X892793Y522222D01*
X892585Y521972D01*
X892210Y521847D01*
X891210D01*
G01X894351Y522888D02*
X894601Y523138D01*
X894893Y523263D01*
X895226Y523305D01*
X895643Y523222D01*
X895935Y523013D01*
X896018Y522763D01*
X895976Y522513D01*
X895810Y522305D01*
X894976Y521888D01*
X894601Y521597D01*
X894351Y521180D01*
X894268Y520805D01*
X896018D01*
G01X898243Y523305D02*
X897910Y523222D01*
X897660Y523013D01*
X897493Y522763D01*
X897368Y522430D01*
X897326Y522055D01*
X897368Y521680D01*
X897493Y521347D01*
X897660Y521097D01*
X897910Y520888D01*
X898243Y520805D01*
X898576Y520888D01*
X898826Y521097D01*
X898993Y521347D01*
X899118Y521680D01*
X899160Y522055D01*
X899118Y522430D01*
X898993Y522763D01*
X898826Y523013D01*
X898576Y523222D01*
X898243Y523305D01*
G01X900551Y521847D02*
X900843Y522138D01*
X901093Y522305D01*
X901426Y522388D01*
X901718Y522305D01*
X901926Y522138D01*
X902093Y521888D01*
X902135Y521597D01*
X902093Y521347D01*
X901926Y521097D01*
X901676Y520888D01*
X901385Y520805D01*
X901051Y520888D01*
X900760Y521138D01*
X900593Y521513D01*
X900551Y521930D01*
X900635Y522472D01*
X900760Y522763D01*
X900968Y523055D01*
X901260Y523263D01*
X901551Y523305D01*
X901843Y523222D01*
X902051Y523013D01*
G01X888943Y516705D02*
Y514205D01*
G01X887985Y516705D02*
X889901D01*
G01X891210Y514205D02*
Y516705D01*
X892210D01*
X892543Y516580D01*
X892793Y516288D01*
X892876Y515955D01*
X892793Y515622D01*
X892585Y515372D01*
X892210Y515247D01*
X891210D01*
G01X894351Y516288D02*
X894601Y516538D01*
X894893Y516663D01*
X895226Y516705D01*
X895643Y516622D01*
X895935Y516413D01*
X896018Y516163D01*
X895976Y515913D01*
X895810Y515705D01*
X894976Y515288D01*
X894601Y514997D01*
X894351Y514580D01*
X894268Y514205D01*
X896018D01*
G01X898243Y516705D02*
X897910Y516622D01*
X897660Y516413D01*
X897493Y516163D01*
X897368Y515830D01*
X897326Y515455D01*
X897368Y515080D01*
X897493Y514747D01*
X897660Y514497D01*
X897910Y514288D01*
X898243Y514205D01*
X898576Y514288D01*
X898826Y514497D01*
X898993Y514747D01*
X899118Y515080D01*
X899160Y515455D01*
X899118Y515830D01*
X898993Y516163D01*
X898826Y516413D01*
X898576Y516622D01*
X898243Y516705D01*
G01X900426Y514580D02*
X900676Y514372D01*
X900968Y514247D01*
X901343Y514205D01*
X901718Y514288D01*
X902010Y514455D01*
X902218Y514747D01*
X902260Y515080D01*
X902176Y515413D01*
X901968Y515622D01*
X901676Y515788D01*
X901385Y515830D01*
X901093Y515788D01*
X900718Y515622D01*
X900843Y516705D01*
X901968D01*
G01X888869Y530487D02*
Y527987D01*
G01X887911Y530487D02*
X889827D01*
G01X891136Y527987D02*
Y530487D01*
X892136D01*
X892469Y530362D01*
X892719Y530070D01*
X892802Y529737D01*
X892719Y529404D01*
X892511Y529154D01*
X892136Y529029D01*
X891136D01*
G01X894277Y530070D02*
X894527Y530320D01*
X894819Y530445D01*
X895152Y530487D01*
X895569Y530404D01*
X895861Y530195D01*
X895944Y529945D01*
X895902Y529695D01*
X895736Y529487D01*
X894902Y529070D01*
X894527Y528779D01*
X894277Y528362D01*
X894194Y527987D01*
X895944D01*
G01X897377Y530070D02*
X897627Y530320D01*
X897919Y530445D01*
X898252Y530487D01*
X898669Y530404D01*
X898961Y530195D01*
X899044Y529945D01*
X899002Y529695D01*
X898836Y529487D01*
X898002Y529070D01*
X897627Y528779D01*
X897377Y528362D01*
X897294Y527987D01*
X899044D01*
G01X901269Y530487D02*
X900936Y530404D01*
X900686Y530195D01*
X900519Y529945D01*
X900394Y529612D01*
X900352Y529237D01*
X900394Y528862D01*
X900519Y528529D01*
X900686Y528279D01*
X900936Y528070D01*
X901269Y527987D01*
X901602Y528070D01*
X901852Y528279D01*
X902019Y528529D01*
X902144Y528862D01*
X902186Y529237D01*
X902144Y529612D01*
X902019Y529945D01*
X901852Y530195D01*
X901602Y530404D01*
X901269Y530487D01*
G01X873269Y554187D02*
Y551687D01*
G01X872311Y554187D02*
X874227D01*
G01X875536Y551687D02*
Y554187D01*
X876536D01*
X876869Y554062D01*
X877119Y553770D01*
X877202Y553437D01*
X877119Y553104D01*
X876911Y552854D01*
X876536Y552729D01*
X875536D01*
G01X878677Y553770D02*
X878927Y554020D01*
X879219Y554145D01*
X879552Y554187D01*
X879969Y554104D01*
X880261Y553895D01*
X880344Y553645D01*
X880302Y553395D01*
X880136Y553187D01*
X879302Y552770D01*
X878927Y552479D01*
X878677Y552062D01*
X878594Y551687D01*
X880344D01*
G01X881777Y553770D02*
X882027Y554020D01*
X882319Y554145D01*
X882652Y554187D01*
X883069Y554104D01*
X883361Y553895D01*
X883444Y553645D01*
X883402Y553395D01*
X883236Y553187D01*
X882402Y552770D01*
X882027Y552479D01*
X881777Y552062D01*
X881694Y551687D01*
X883444D01*
G01X884877Y552729D02*
X885169Y553020D01*
X885419Y553187D01*
X885752Y553270D01*
X886044Y553187D01*
X886252Y553020D01*
X886419Y552770D01*
X886461Y552479D01*
X886419Y552229D01*
X886252Y551979D01*
X886002Y551770D01*
X885711Y551687D01*
X885377Y551770D01*
X885086Y552020D01*
X884919Y552395D01*
X884877Y552812D01*
X884961Y553354D01*
X885086Y553645D01*
X885294Y553937D01*
X885586Y554145D01*
X885877Y554187D01*
X886169Y554104D01*
X886377Y553895D01*
G01X888943Y510405D02*
Y507905D01*
G01X887985Y510405D02*
X889901D01*
G01X891210Y507905D02*
Y510405D01*
X892210D01*
X892543Y510280D01*
X892793Y509988D01*
X892876Y509655D01*
X892793Y509322D01*
X892585Y509072D01*
X892210Y508947D01*
X891210D01*
G01X894351Y509988D02*
X894601Y510238D01*
X894893Y510363D01*
X895226Y510405D01*
X895643Y510322D01*
X895935Y510113D01*
X896018Y509863D01*
X895976Y509613D01*
X895810Y509405D01*
X894976Y508988D01*
X894601Y508697D01*
X894351Y508280D01*
X894268Y507905D01*
X896018D01*
G01X898243Y510405D02*
X897910Y510322D01*
X897660Y510113D01*
X897493Y509863D01*
X897368Y509530D01*
X897326Y509155D01*
X897368Y508780D01*
X897493Y508447D01*
X897660Y508197D01*
X897910Y507988D01*
X898243Y507905D01*
X898576Y507988D01*
X898826Y508197D01*
X898993Y508447D01*
X899118Y508780D01*
X899160Y509155D01*
X899118Y509530D01*
X898993Y509863D01*
X898826Y510113D01*
X898576Y510322D01*
X898243Y510405D01*
G01X901843Y507905D02*
Y510405D01*
X900301Y508613D01*
X902385D01*
G01X865869Y588087D02*
Y585587D01*
G01X864911Y588087D02*
X866827D01*
G01X868136Y585587D02*
Y588087D01*
X869136D01*
X869469Y587962D01*
X869719Y587670D01*
X869802Y587337D01*
X869719Y587004D01*
X869511Y586754D01*
X869136Y586629D01*
X868136D01*
G01X871277Y587670D02*
X871527Y587920D01*
X871819Y588045D01*
X872152Y588087D01*
X872569Y588004D01*
X872861Y587795D01*
X872944Y587545D01*
X872902Y587295D01*
X872736Y587087D01*
X871902Y586670D01*
X871527Y586379D01*
X871277Y585962D01*
X871194Y585587D01*
X872944D01*
G01X874377Y587670D02*
X874627Y587920D01*
X874919Y588045D01*
X875252Y588087D01*
X875669Y588004D01*
X875961Y587795D01*
X876044Y587545D01*
X876002Y587295D01*
X875836Y587087D01*
X875002Y586670D01*
X874627Y586379D01*
X874377Y585962D01*
X874294Y585587D01*
X876044D01*
G01X877352Y585962D02*
X877602Y585754D01*
X877894Y585629D01*
X878269Y585587D01*
X878644Y585670D01*
X878936Y585837D01*
X879144Y586129D01*
X879186Y586462D01*
X879102Y586795D01*
X878894Y587004D01*
X878602Y587170D01*
X878311Y587212D01*
X878019Y587170D01*
X877644Y587004D01*
X877769Y588087D01*
X878894D01*
G01X865943Y594105D02*
Y591605D01*
G01X864985Y594105D02*
X866901D01*
G01X868210Y591605D02*
Y594105D01*
X869210D01*
X869543Y593980D01*
X869793Y593688D01*
X869876Y593355D01*
X869793Y593022D01*
X869585Y592772D01*
X869210Y592647D01*
X868210D01*
G01X871351Y593688D02*
X871601Y593938D01*
X871893Y594063D01*
X872226Y594105D01*
X872643Y594022D01*
X872935Y593813D01*
X873018Y593563D01*
X872976Y593313D01*
X872810Y593105D01*
X871976Y592688D01*
X871601Y592397D01*
X871351Y591980D01*
X871268Y591605D01*
X873018D01*
G01X875243Y594105D02*
X874910Y594022D01*
X874660Y593813D01*
X874493Y593563D01*
X874368Y593230D01*
X874326Y592855D01*
X874368Y592480D01*
X874493Y592147D01*
X874660Y591897D01*
X874910Y591688D01*
X875243Y591605D01*
X875576Y591688D01*
X875826Y591897D01*
X875993Y592147D01*
X876118Y592480D01*
X876160Y592855D01*
X876118Y593230D01*
X875993Y593563D01*
X875826Y593813D01*
X875576Y594022D01*
X875243Y594105D01*
G01X878343Y591605D02*
X878635Y591647D01*
X878968Y591772D01*
X879176Y591980D01*
X879260Y592272D01*
X879176Y592563D01*
X878926Y592813D01*
X878551Y592938D01*
X878135D01*
X877885Y593022D01*
X877676Y593230D01*
X877593Y593522D01*
X877718Y593813D01*
X878010Y594022D01*
X878343Y594105D01*
X878676Y594022D01*
X878968Y593813D01*
X879093Y593522D01*
X879010Y593230D01*
X878801Y593022D01*
X878551Y592938D01*
X878135D01*
X877760Y592813D01*
X877510Y592563D01*
X877426Y592272D01*
X877510Y591980D01*
X877718Y591772D01*
X878051Y591647D01*
X878343Y591605D01*
G01X865943Y600205D02*
Y597705D01*
G01X864985Y600205D02*
X866901D01*
G01X868210Y597705D02*
Y600205D01*
X869210D01*
X869543Y600080D01*
X869793Y599788D01*
X869876Y599455D01*
X869793Y599122D01*
X869585Y598872D01*
X869210Y598747D01*
X868210D01*
G01X871351Y599788D02*
X871601Y600038D01*
X871893Y600163D01*
X872226Y600205D01*
X872643Y600122D01*
X872935Y599913D01*
X873018Y599663D01*
X872976Y599413D01*
X872810Y599205D01*
X871976Y598788D01*
X871601Y598497D01*
X871351Y598080D01*
X871268Y597705D01*
X873018D01*
G01X875243Y600205D02*
X874910Y600122D01*
X874660Y599913D01*
X874493Y599663D01*
X874368Y599330D01*
X874326Y598955D01*
X874368Y598580D01*
X874493Y598247D01*
X874660Y597997D01*
X874910Y597788D01*
X875243Y597705D01*
X875576Y597788D01*
X875826Y597997D01*
X875993Y598247D01*
X876118Y598580D01*
X876160Y598955D01*
X876118Y599330D01*
X875993Y599663D01*
X875826Y599913D01*
X875576Y600122D01*
X875243Y600205D01*
G01X878260Y597705D02*
X878343Y598247D01*
X878468Y598705D01*
X878635Y599122D01*
X878843Y599580D01*
X879176Y600205D01*
X877510D01*
G01X865843Y606505D02*
Y604005D01*
G01X864885Y606505D02*
X866801D01*
G01X868110Y604005D02*
Y606505D01*
X869110D01*
X869443Y606380D01*
X869693Y606088D01*
X869776Y605755D01*
X869693Y605422D01*
X869485Y605172D01*
X869110Y605047D01*
X868110D01*
G01X871251Y606088D02*
X871501Y606338D01*
X871793Y606463D01*
X872126Y606505D01*
X872543Y606422D01*
X872835Y606213D01*
X872918Y605963D01*
X872876Y605713D01*
X872710Y605505D01*
X871876Y605088D01*
X871501Y604797D01*
X871251Y604380D01*
X871168Y604005D01*
X872918D01*
G01X875143Y606505D02*
X874810Y606422D01*
X874560Y606213D01*
X874393Y605963D01*
X874268Y605630D01*
X874226Y605255D01*
X874268Y604880D01*
X874393Y604547D01*
X874560Y604297D01*
X874810Y604088D01*
X875143Y604005D01*
X875476Y604088D01*
X875726Y604297D01*
X875893Y604547D01*
X876018Y604880D01*
X876060Y605255D01*
X876018Y605630D01*
X875893Y605963D01*
X875726Y606213D01*
X875476Y606422D01*
X875143Y606505D01*
G01X877535Y604297D02*
X877826Y604088D01*
X878160Y604005D01*
X878493Y604088D01*
X878785Y604338D01*
X878993Y604713D01*
X879076Y605088D01*
Y605547D01*
X878993Y605922D01*
X878785Y606255D01*
X878535Y606422D01*
X878243Y606505D01*
X877910Y606422D01*
X877660Y606255D01*
X877493Y606005D01*
X877410Y605672D01*
X877493Y605380D01*
X877701Y605088D01*
X877951Y604922D01*
X878243Y604880D01*
X878576Y604963D01*
X878826Y605172D01*
X879076Y605547D01*
G01X865843Y612905D02*
Y610405D01*
G01X864885Y612905D02*
X866801D01*
G01X868110Y610405D02*
Y612905D01*
X869110D01*
X869443Y612780D01*
X869693Y612488D01*
X869776Y612155D01*
X869693Y611822D01*
X869485Y611572D01*
X869110Y611447D01*
X868110D01*
G01X871251Y612488D02*
X871501Y612738D01*
X871793Y612863D01*
X872126Y612905D01*
X872543Y612822D01*
X872835Y612613D01*
X872918Y612363D01*
X872876Y612113D01*
X872710Y611905D01*
X871876Y611488D01*
X871501Y611197D01*
X871251Y610780D01*
X871168Y610405D01*
X872918D01*
G01X875143D02*
Y612905D01*
X874643Y612405D01*
G01Y610405D02*
X875643D01*
G01X878243Y612905D02*
X877910Y612822D01*
X877660Y612613D01*
X877493Y612363D01*
X877368Y612030D01*
X877326Y611655D01*
X877368Y611280D01*
X877493Y610947D01*
X877660Y610697D01*
X877910Y610488D01*
X878243Y610405D01*
X878576Y610488D01*
X878826Y610697D01*
X878993Y610947D01*
X879118Y611280D01*
X879160Y611655D01*
X879118Y612030D01*
X878993Y612363D01*
X878826Y612613D01*
X878576Y612822D01*
X878243Y612905D01*
G01X867370Y670754D02*
X867245Y670504D01*
X867162Y670212D01*
Y669879D01*
X867287Y669504D01*
X867495Y669212D01*
X867745Y669004D01*
X868162Y668837D01*
X868537Y668795D01*
X868912Y668879D01*
X869162Y669004D01*
X869412Y669254D01*
X869579Y669545D01*
X869662Y669837D01*
Y670129D01*
X869579Y670420D01*
X869454Y670670D01*
X869287Y670879D01*
G01X869662Y672937D02*
X867162D01*
X867662Y672437D01*
G01X869662D02*
Y673437D01*
G01X869162Y675120D02*
X869454Y675370D01*
X869620Y675704D01*
X869662Y676079D01*
X869620Y676412D01*
X869412Y676745D01*
X869162Y676954D01*
X868912Y676995D01*
X868620Y676912D01*
X868412Y676620D01*
X868329Y676329D01*
Y675954D01*
G01Y676329D02*
X868204Y676579D01*
X867995Y676787D01*
X867745Y676870D01*
X867495Y676787D01*
X867287Y676579D01*
X867162Y676204D01*
X867204Y675829D01*
X867370Y675454D01*
G01X869662Y679637D02*
X867162D01*
X868954Y678095D01*
Y680179D01*
G01X864950Y687750D02*
Y706450D01*
X875250D01*
Y687750D01*
X864950D01*
G01X877284Y670891D02*
X877159Y670641D01*
X877076Y670349D01*
Y670016D01*
X877201Y669641D01*
X877409Y669349D01*
X877659Y669141D01*
X878076Y668974D01*
X878451Y668932D01*
X878826Y669016D01*
X879076Y669141D01*
X879326Y669391D01*
X879493Y669682D01*
X879576Y669974D01*
Y670266D01*
X879493Y670557D01*
X879368Y670807D01*
X879201Y671016D01*
G01X879576Y673074D02*
X877076D01*
X877576Y672574D01*
G01X879576D02*
Y673574D01*
G01X879076Y675257D02*
X879368Y675507D01*
X879534Y675841D01*
X879576Y676216D01*
X879534Y676549D01*
X879326Y676882D01*
X879076Y677091D01*
X878826Y677132D01*
X878534Y677049D01*
X878326Y676757D01*
X878243Y676466D01*
Y676091D01*
G01Y676466D02*
X878118Y676716D01*
X877909Y676924D01*
X877659Y677007D01*
X877409Y676924D01*
X877201Y676716D01*
X877076Y676341D01*
X877118Y675966D01*
X877284Y675591D01*
G01X879076Y678357D02*
X879368Y678607D01*
X879534Y678941D01*
X879576Y679316D01*
X879534Y679649D01*
X879326Y679982D01*
X879076Y680191D01*
X878826Y680232D01*
X878534Y680149D01*
X878326Y679857D01*
X878243Y679566D01*
Y679191D01*
G01Y679566D02*
X878118Y679816D01*
X877909Y680024D01*
X877659Y680107D01*
X877409Y680024D01*
X877201Y679816D01*
X877076Y679441D01*
X877118Y679066D01*
X877284Y678691D01*
G01X889790Y813103D02*
Y815603D01*
X890831D01*
X891165Y815478D01*
X891373Y815311D01*
X891456Y814978D01*
X891373Y814645D01*
X891123Y814436D01*
X890831Y814311D01*
X889790D01*
G01X890831D02*
X891456Y813103D01*
G01X894223D02*
Y815603D01*
X892681Y813811D01*
X894765D01*
G01X896823Y813103D02*
Y815603D01*
X896323Y815103D01*
G01Y813103D02*
X897323D01*
G01X899131Y814145D02*
X899423Y814436D01*
X899673Y814603D01*
X900006Y814686D01*
X900298Y814603D01*
X900506Y814436D01*
X900673Y814186D01*
X900715Y813895D01*
X900673Y813645D01*
X900506Y813395D01*
X900256Y813186D01*
X899965Y813103D01*
X899631Y813186D01*
X899340Y813436D01*
X899173Y813811D01*
X899131Y814228D01*
X899215Y814770D01*
X899340Y815061D01*
X899548Y815353D01*
X899840Y815561D01*
X900131Y815603D01*
X900423Y815520D01*
X900631Y815311D01*
G01X877573Y818103D02*
Y814103D01*
X884973D01*
G01X853537Y813320D02*
Y815820D01*
X854578D01*
X854912Y815695D01*
X855120Y815528D01*
X855203Y815195D01*
X855120Y814862D01*
X854870Y814653D01*
X854578Y814528D01*
X853537D01*
G01X854578D02*
X855203Y813320D01*
G01X857970D02*
Y815820D01*
X856428Y814028D01*
X858512D01*
G01X860570Y815820D02*
X860237Y815737D01*
X859987Y815528D01*
X859820Y815278D01*
X859695Y814945D01*
X859653Y814570D01*
X859695Y814195D01*
X859820Y813862D01*
X859987Y813612D01*
X860237Y813403D01*
X860570Y813320D01*
X860903Y813403D01*
X861153Y813612D01*
X861320Y813862D01*
X861445Y814195D01*
X861487Y814570D01*
X861445Y814945D01*
X861320Y815278D01*
X861153Y815528D01*
X860903Y815737D01*
X860570Y815820D01*
G01X862962Y813612D02*
X863253Y813403D01*
X863587Y813320D01*
X863920Y813403D01*
X864212Y813653D01*
X864420Y814028D01*
X864503Y814403D01*
Y814862D01*
X864420Y815237D01*
X864212Y815570D01*
X863962Y815737D01*
X863670Y815820D01*
X863337Y815737D01*
X863087Y815570D01*
X862920Y815320D01*
X862837Y814987D01*
X862920Y814695D01*
X863128Y814403D01*
X863378Y814237D01*
X863670Y814195D01*
X864003Y814278D01*
X864253Y814487D01*
X864503Y814862D01*
G01X869123Y816580D02*
Y812580D01*
X876523D01*
G01X892334Y800517D02*
X889834D01*
Y801558D01*
X889959Y801892D01*
X890126Y802100D01*
X890459Y802183D01*
X890792Y802100D01*
X891001Y801850D01*
X891126Y801558D01*
Y800517D01*
G01Y801558D02*
X892334Y802183D01*
G01Y804950D02*
X889834D01*
X891626Y803408D01*
Y805492D01*
G01X892334Y807550D02*
X889834D01*
X890334Y807050D01*
G01X892334D02*
Y808050D01*
G01X890251Y809858D02*
X890001Y810108D01*
X889876Y810400D01*
X889834Y810733D01*
X889917Y811150D01*
X890126Y811442D01*
X890376Y811525D01*
X890626Y811483D01*
X890834Y811317D01*
X891251Y810483D01*
X891542Y810108D01*
X891959Y809858D01*
X892334Y809775D01*
Y811525D01*
G01X876673Y805903D02*
X880673D01*
Y813303D01*
G01X896334Y800517D02*
X893834D01*
Y801558D01*
X893959Y801892D01*
X894126Y802100D01*
X894459Y802183D01*
X894792Y802100D01*
X895001Y801850D01*
X895126Y801558D01*
Y800517D01*
G01Y801558D02*
X896334Y802183D01*
G01X895292Y803658D02*
X895001Y803950D01*
X894834Y804200D01*
X894751Y804533D01*
X894834Y804825D01*
X895001Y805033D01*
X895251Y805200D01*
X895542Y805242D01*
X895792Y805200D01*
X896042Y805033D01*
X896251Y804783D01*
X896334Y804492D01*
X896251Y804158D01*
X896001Y803867D01*
X895626Y803700D01*
X895209Y803658D01*
X894667Y803742D01*
X894376Y803867D01*
X894084Y804075D01*
X893876Y804367D01*
X893834Y804658D01*
X893917Y804950D01*
X894126Y805158D01*
G01X893834Y807550D02*
X893917Y807217D01*
X894126Y806967D01*
X894376Y806800D01*
X894709Y806675D01*
X895084Y806633D01*
X895459Y806675D01*
X895792Y806800D01*
X896042Y806967D01*
X896251Y807217D01*
X896334Y807550D01*
X896251Y807883D01*
X896042Y808133D01*
X895792Y808300D01*
X895459Y808425D01*
X895084Y808467D01*
X894709Y808425D01*
X894376Y808300D01*
X894126Y808133D01*
X893917Y807883D01*
X893834Y807550D01*
G01X896042Y809942D02*
X896251Y810233D01*
X896334Y810567D01*
X896251Y810900D01*
X896001Y811192D01*
X895626Y811400D01*
X895251Y811483D01*
X894792D01*
X894417Y811400D01*
X894084Y811192D01*
X893917Y810942D01*
X893834Y810650D01*
X893917Y810317D01*
X894084Y810067D01*
X894334Y809900D01*
X894667Y809817D01*
X894959Y809900D01*
X895251Y810108D01*
X895417Y810358D01*
X895459Y810650D01*
X895376Y810983D01*
X895167Y811233D01*
X894792Y811483D01*
G01X881400Y805932D02*
X885400D01*
Y813332D01*
G01X889281Y826761D02*
X891073D01*
X891448Y826928D01*
X891698Y827261D01*
X891781Y827678D01*
X891698Y828095D01*
X891448Y828428D01*
X891073Y828595D01*
X889281D01*
G01X891781Y830778D02*
X889281D01*
X889781Y830278D01*
G01X891781D02*
Y831278D01*
G01X890739Y833086D02*
X890448Y833378D01*
X890281Y833628D01*
X890198Y833961D01*
X890281Y834253D01*
X890448Y834461D01*
X890698Y834628D01*
X890989Y834670D01*
X891239Y834628D01*
X891489Y834461D01*
X891698Y834211D01*
X891781Y833920D01*
X891698Y833586D01*
X891448Y833295D01*
X891073Y833128D01*
X890656Y833086D01*
X890114Y833170D01*
X889823Y833295D01*
X889531Y833503D01*
X889323Y833795D01*
X889281Y834086D01*
X889364Y834378D01*
X889573Y834586D01*
G01X884223Y833403D02*
X872323D01*
G01X884223Y841403D02*
Y833403D01*
G01X872323D02*
Y841403D01*
G01X873923Y837403D02*
X872323Y839003D01*
G01X873923Y837403D02*
X872323Y835803D01*
G01X864297Y824456D02*
X864172Y824206D01*
X864089Y823914D01*
Y823581D01*
X864214Y823206D01*
X864422Y822914D01*
X864672Y822706D01*
X865089Y822539D01*
X865464Y822497D01*
X865839Y822581D01*
X866089Y822706D01*
X866339Y822956D01*
X866506Y823247D01*
X866589Y823539D01*
Y823831D01*
X866506Y824122D01*
X866381Y824372D01*
X866214Y824581D01*
G01Y825722D02*
X866422Y825972D01*
X866547Y826264D01*
X866589Y826639D01*
X866506Y827014D01*
X866339Y827306D01*
X866047Y827514D01*
X865714Y827556D01*
X865381Y827472D01*
X865172Y827264D01*
X865006Y826972D01*
X864964Y826681D01*
X865006Y826389D01*
X865172Y826014D01*
X864089Y826139D01*
Y827264D01*
G01X866589Y829656D02*
X866047Y829739D01*
X865589Y829864D01*
X865172Y830031D01*
X864714Y830239D01*
X864089Y830572D01*
Y828906D01*
G01X868797Y824956D02*
X868672Y824706D01*
X868589Y824414D01*
Y824081D01*
X868714Y823706D01*
X868922Y823414D01*
X869172Y823206D01*
X869589Y823039D01*
X869964Y822997D01*
X870339Y823081D01*
X870589Y823206D01*
X870839Y823456D01*
X871006Y823747D01*
X871089Y824039D01*
Y824331D01*
X871006Y824622D01*
X870881Y824872D01*
X870714Y825081D01*
G01X870047Y826347D02*
X869756Y826639D01*
X869589Y826889D01*
X869506Y827222D01*
X869589Y827514D01*
X869756Y827722D01*
X870006Y827889D01*
X870297Y827931D01*
X870547Y827889D01*
X870797Y827722D01*
X871006Y827472D01*
X871089Y827181D01*
X871006Y826847D01*
X870756Y826556D01*
X870381Y826389D01*
X869964Y826347D01*
X869422Y826431D01*
X869131Y826556D01*
X868839Y826764D01*
X868631Y827056D01*
X868589Y827347D01*
X868672Y827639D01*
X868881Y827847D01*
G01X871089Y830239D02*
X871047Y830531D01*
X870922Y830864D01*
X870714Y831072D01*
X870422Y831156D01*
X870131Y831072D01*
X869881Y830822D01*
X869756Y830447D01*
Y830031D01*
X869672Y829781D01*
X869464Y829572D01*
X869172Y829489D01*
X868881Y829614D01*
X868672Y829906D01*
X868589Y830239D01*
X868672Y830572D01*
X868881Y830864D01*
X869172Y830989D01*
X869464Y830906D01*
X869672Y830697D01*
X869756Y830447D01*
Y830031D01*
X869881Y829656D01*
X870131Y829406D01*
X870422Y829322D01*
X870714Y829406D01*
X870922Y829614D01*
X871047Y829947D01*
X871089Y830239D01*
G01X855407Y819977D02*
X855157Y820102D01*
X854865Y820185D01*
X854532D01*
X854157Y820060D01*
X853865Y819852D01*
X853657Y819602D01*
X853490Y819185D01*
X853448Y818810D01*
X853532Y818435D01*
X853657Y818185D01*
X853907Y817935D01*
X854198Y817768D01*
X854490Y817685D01*
X854782D01*
X855073Y817768D01*
X855323Y817893D01*
X855532Y818060D01*
G01X857590Y817685D02*
Y820185D01*
X857090Y819685D01*
G01Y817685D02*
X858090D01*
G01X859898Y819768D02*
X860148Y820018D01*
X860440Y820143D01*
X860773Y820185D01*
X861190Y820102D01*
X861482Y819893D01*
X861565Y819643D01*
X861523Y819393D01*
X861357Y819185D01*
X860523Y818768D01*
X860148Y818477D01*
X859898Y818060D01*
X859815Y817685D01*
X861565D01*
G01X863790D02*
X864082Y817727D01*
X864415Y817852D01*
X864623Y818060D01*
X864707Y818352D01*
X864623Y818643D01*
X864373Y818893D01*
X863998Y819018D01*
X863582D01*
X863332Y819102D01*
X863123Y819310D01*
X863040Y819602D01*
X863165Y819893D01*
X863457Y820102D01*
X863790Y820185D01*
X864123Y820102D01*
X864415Y819893D01*
X864540Y819602D01*
X864457Y819310D01*
X864248Y819102D01*
X863998Y819018D01*
X863582D01*
X863207Y818893D01*
X862957Y818643D01*
X862873Y818352D01*
X862957Y818060D01*
X863165Y817852D01*
X863498Y817727D01*
X863790Y817685D01*
G01X867800Y861017D02*
X865300D01*
Y862058D01*
X865425Y862392D01*
X865592Y862600D01*
X865925Y862683D01*
X866258Y862600D01*
X866467Y862350D01*
X866592Y862058D01*
Y861017D01*
G01Y862058D02*
X867800Y862683D01*
G01Y865450D02*
X865300D01*
X867092Y863908D01*
Y865992D01*
G01X867800Y868050D02*
X865300D01*
X865800Y867550D01*
G01X867800D02*
Y868550D01*
G01X867425Y870233D02*
X867633Y870483D01*
X867758Y870775D01*
X867800Y871150D01*
X867717Y871525D01*
X867550Y871817D01*
X867258Y872025D01*
X866925Y872067D01*
X866592Y871983D01*
X866383Y871775D01*
X866217Y871483D01*
X866175Y871192D01*
X866217Y870900D01*
X866383Y870525D01*
X865300Y870650D01*
Y871775D01*
G01X879673Y867103D02*
X875673D01*
Y859703D01*
G01X888517Y860367D02*
Y862867D01*
X889558D01*
X889892Y862742D01*
X890100Y862575D01*
X890183Y862242D01*
X890100Y861909D01*
X889850Y861700D01*
X889558Y861575D01*
X888517D01*
G01X889558D02*
X890183Y860367D01*
G01X892950D02*
Y862867D01*
X891408Y861075D01*
X893492D01*
G01X895550Y860367D02*
Y862867D01*
X895050Y862367D01*
G01Y860367D02*
X896050D01*
G01X898650D02*
Y862867D01*
X898150Y862367D01*
G01Y860367D02*
X899150D01*
G01X891303Y854727D02*
Y858727D01*
X883903D01*
G01X863117Y855600D02*
Y858100D01*
X864158D01*
X864492Y857975D01*
X864700Y857808D01*
X864783Y857475D01*
X864700Y857142D01*
X864450Y856933D01*
X864158Y856808D01*
X863117D01*
G01X864158D02*
X864783Y855600D01*
G01X867550D02*
Y858100D01*
X866008Y856308D01*
X868092D01*
G01X870150Y855600D02*
Y858100D01*
X869650Y857600D01*
G01Y855600D02*
X870650D01*
G01X873250D02*
X873542Y855642D01*
X873875Y855767D01*
X874083Y855975D01*
X874167Y856267D01*
X874083Y856558D01*
X873833Y856808D01*
X873458Y856933D01*
X873042D01*
X872792Y857017D01*
X872583Y857225D01*
X872500Y857517D01*
X872625Y857808D01*
X872917Y858017D01*
X873250Y858100D01*
X873583Y858017D01*
X873875Y857808D01*
X874000Y857517D01*
X873917Y857225D01*
X873708Y857017D01*
X873458Y856933D01*
X873042D01*
X872667Y856808D01*
X872417Y856558D01*
X872333Y856267D01*
X872417Y855975D01*
X872625Y855767D01*
X872958Y855642D01*
X873250Y855600D01*
G01X875673Y858903D02*
Y854903D01*
X883073D01*
G01X872133Y861117D02*
X869633D01*
Y862158D01*
X869758Y862492D01*
X869925Y862700D01*
X870258Y862783D01*
X870591Y862700D01*
X870800Y862450D01*
X870925Y862158D01*
Y861117D01*
G01Y862158D02*
X872133Y862783D01*
G01X871091Y864258D02*
X870800Y864550D01*
X870633Y864800D01*
X870550Y865133D01*
X870633Y865425D01*
X870800Y865633D01*
X871050Y865800D01*
X871341Y865842D01*
X871591Y865800D01*
X871841Y865633D01*
X872050Y865383D01*
X872133Y865092D01*
X872050Y864758D01*
X871800Y864467D01*
X871425Y864300D01*
X871008Y864258D01*
X870466Y864342D01*
X870175Y864467D01*
X869883Y864675D01*
X869675Y864967D01*
X869633Y865258D01*
X869716Y865550D01*
X869925Y865758D01*
G01X869633Y868150D02*
X869716Y867817D01*
X869925Y867567D01*
X870175Y867400D01*
X870508Y867275D01*
X870883Y867233D01*
X871258Y867275D01*
X871591Y867400D01*
X871841Y867567D01*
X872050Y867817D01*
X872133Y868150D01*
X872050Y868483D01*
X871841Y868733D01*
X871591Y868900D01*
X871258Y869025D01*
X870883Y869067D01*
X870508Y869025D01*
X870175Y868900D01*
X869925Y868733D01*
X869716Y868483D01*
X869633Y868150D01*
G01X872133Y871250D02*
X872091Y871542D01*
X871966Y871875D01*
X871758Y872083D01*
X871466Y872167D01*
X871175Y872083D01*
X870925Y871833D01*
X870800Y871458D01*
Y871042D01*
X870716Y870792D01*
X870508Y870583D01*
X870216Y870500D01*
X869925Y870625D01*
X869716Y870917D01*
X869633Y871250D01*
X869716Y871583D01*
X869925Y871875D01*
X870216Y872000D01*
X870508Y871917D01*
X870716Y871708D01*
X870800Y871458D01*
Y871042D01*
X870925Y870667D01*
X871175Y870417D01*
X871466Y870333D01*
X871758Y870417D01*
X871966Y870625D01*
X872091Y870958D01*
X872133Y871250D01*
G01X884400Y867068D02*
X880400D01*
Y859668D01*
G01X872323Y841403D02*
X884223D01*
G01X887500Y930533D02*
X889292D01*
X889667Y930700D01*
X889917Y931033D01*
X890000Y931450D01*
X889917Y931867D01*
X889667Y932200D01*
X889292Y932367D01*
X887500D01*
G01X890000Y934467D02*
X889458Y934550D01*
X889000Y934675D01*
X888583Y934842D01*
X888125Y935050D01*
X887500Y935383D01*
Y933717D01*
G01X888827Y956837D02*
X886327D01*
Y957878D01*
X886452Y958212D01*
X886619Y958420D01*
X886952Y958503D01*
X887285Y958420D01*
X887494Y958170D01*
X887619Y957878D01*
Y956837D01*
G01Y957878D02*
X888827Y958503D01*
G01X887785Y959978D02*
X887494Y960270D01*
X887327Y960520D01*
X887244Y960853D01*
X887327Y961145D01*
X887494Y961353D01*
X887744Y961520D01*
X888035Y961562D01*
X888285Y961520D01*
X888535Y961353D01*
X888744Y961103D01*
X888827Y960812D01*
X888744Y960478D01*
X888494Y960187D01*
X888119Y960020D01*
X887702Y959978D01*
X887160Y960062D01*
X886869Y960187D01*
X886577Y960395D01*
X886369Y960687D01*
X886327Y960978D01*
X886410Y961270D01*
X886619Y961478D01*
G01X888827Y963870D02*
X888785Y964162D01*
X888660Y964495D01*
X888452Y964703D01*
X888160Y964787D01*
X887869Y964703D01*
X887619Y964453D01*
X887494Y964078D01*
Y963662D01*
X887410Y963412D01*
X887202Y963203D01*
X886910Y963120D01*
X886619Y963245D01*
X886410Y963537D01*
X886327Y963870D01*
X886410Y964203D01*
X886619Y964495D01*
X886910Y964620D01*
X887202Y964537D01*
X887410Y964328D01*
X887494Y964078D01*
Y963662D01*
X887619Y963287D01*
X887869Y963037D01*
X888160Y962953D01*
X888452Y963037D01*
X888660Y963245D01*
X888785Y963578D01*
X888827Y963870D01*
G01X893074Y956585D02*
X890574D01*
Y957626D01*
X890699Y957960D01*
X890866Y958168D01*
X891199Y958251D01*
X891532Y958168D01*
X891741Y957918D01*
X891866Y957626D01*
Y956585D01*
G01Y957626D02*
X893074Y958251D01*
G01Y960435D02*
X892532Y960518D01*
X892074Y960643D01*
X891657Y960810D01*
X891199Y961018D01*
X890574Y961351D01*
Y959685D01*
G01X892574Y962701D02*
X892866Y962951D01*
X893032Y963285D01*
X893074Y963660D01*
X893032Y963993D01*
X892824Y964326D01*
X892574Y964535D01*
X892324Y964576D01*
X892032Y964493D01*
X891824Y964201D01*
X891741Y963910D01*
Y963535D01*
G01Y963910D02*
X891616Y964160D01*
X891407Y964368D01*
X891157Y964451D01*
X890907Y964368D01*
X890699Y964160D01*
X890574Y963785D01*
X890616Y963410D01*
X890782Y963035D01*
G01X884607Y956649D02*
X882107D01*
Y957690D01*
X882232Y958024D01*
X882399Y958232D01*
X882732Y958315D01*
X883065Y958232D01*
X883274Y957982D01*
X883399Y957690D01*
Y956649D01*
G01Y957690D02*
X884607Y958315D01*
G01Y960499D02*
X884065Y960582D01*
X883607Y960707D01*
X883190Y960874D01*
X882732Y961082D01*
X882107Y961415D01*
Y959749D01*
G01X884607Y964182D02*
X882107D01*
X883899Y962640D01*
Y964724D01*
G01X889600Y975767D02*
X887100D01*
Y976808D01*
X887225Y977142D01*
X887392Y977350D01*
X887725Y977433D01*
X888058Y977350D01*
X888267Y977100D01*
X888392Y976808D01*
Y975767D01*
G01Y976808D02*
X889600Y977433D01*
G01X887517Y978908D02*
X887267Y979158D01*
X887142Y979450D01*
X887100Y979783D01*
X887183Y980200D01*
X887392Y980492D01*
X887642Y980575D01*
X887892Y980533D01*
X888100Y980367D01*
X888517Y979533D01*
X888808Y979158D01*
X889225Y978908D01*
X889600Y978825D01*
Y980575D01*
G01X889308Y982092D02*
X889517Y982383D01*
X889600Y982717D01*
X889517Y983050D01*
X889267Y983342D01*
X888892Y983550D01*
X888517Y983633D01*
X888058D01*
X887683Y983550D01*
X887350Y983342D01*
X887183Y983092D01*
X887100Y982800D01*
X887183Y982467D01*
X887350Y982217D01*
X887600Y982050D01*
X887933Y981967D01*
X888225Y982050D01*
X888517Y982258D01*
X888683Y982508D01*
X888725Y982800D01*
X888642Y983133D01*
X888433Y983383D01*
X888058Y983633D01*
G01X894100Y975767D02*
X891600D01*
Y976808D01*
X891725Y977142D01*
X891892Y977350D01*
X892225Y977433D01*
X892558Y977350D01*
X892767Y977100D01*
X892892Y976808D01*
Y975767D01*
G01Y976808D02*
X894100Y977433D01*
G01X893600Y978783D02*
X893892Y979033D01*
X894058Y979367D01*
X894100Y979742D01*
X894058Y980075D01*
X893850Y980408D01*
X893600Y980617D01*
X893350Y980658D01*
X893058Y980575D01*
X892850Y980283D01*
X892767Y979992D01*
Y979617D01*
G01Y979992D02*
X892642Y980242D01*
X892433Y980450D01*
X892183Y980533D01*
X891933Y980450D01*
X891725Y980242D01*
X891600Y979867D01*
X891642Y979492D01*
X891808Y979117D01*
G01X893725Y981883D02*
X893933Y982133D01*
X894058Y982425D01*
X894100Y982800D01*
X894017Y983175D01*
X893850Y983467D01*
X893558Y983675D01*
X893225Y983717D01*
X892892Y983633D01*
X892683Y983425D01*
X892517Y983133D01*
X892475Y982842D01*
X892517Y982550D01*
X892683Y982175D01*
X891600Y982300D01*
Y983425D01*
G01X885100Y975767D02*
X882600D01*
Y976808D01*
X882725Y977142D01*
X882892Y977350D01*
X883225Y977433D01*
X883558Y977350D01*
X883767Y977100D01*
X883892Y976808D01*
Y975767D01*
G01Y976808D02*
X885100Y977433D01*
G01X884600Y978783D02*
X884892Y979033D01*
X885058Y979367D01*
X885100Y979742D01*
X885058Y980075D01*
X884850Y980408D01*
X884600Y980617D01*
X884350Y980658D01*
X884058Y980575D01*
X883850Y980283D01*
X883767Y979992D01*
Y979617D01*
G01Y979992D02*
X883642Y980242D01*
X883433Y980450D01*
X883183Y980533D01*
X882933Y980450D01*
X882725Y980242D01*
X882600Y979867D01*
X882642Y979492D01*
X882808Y979117D01*
G01X885100Y982800D02*
X882600D01*
X883100Y982300D01*
G01X885100D02*
Y983300D01*
G01X880600Y975767D02*
X878100D01*
Y976808D01*
X878225Y977142D01*
X878392Y977350D01*
X878725Y977433D01*
X879058Y977350D01*
X879267Y977100D01*
X879392Y976808D01*
Y975767D01*
G01Y976808D02*
X880600Y977433D01*
G01X880100Y978783D02*
X880392Y979033D01*
X880558Y979367D01*
X880600Y979742D01*
X880558Y980075D01*
X880350Y980408D01*
X880100Y980617D01*
X879850Y980658D01*
X879558Y980575D01*
X879350Y980283D01*
X879267Y979992D01*
Y979617D01*
G01Y979992D02*
X879142Y980242D01*
X878933Y980450D01*
X878683Y980533D01*
X878433Y980450D01*
X878225Y980242D01*
X878100Y979867D01*
X878142Y979492D01*
X878308Y979117D01*
G01X879558Y982008D02*
X879267Y982300D01*
X879100Y982550D01*
X879017Y982883D01*
X879100Y983175D01*
X879267Y983383D01*
X879517Y983550D01*
X879808Y983592D01*
X880058Y983550D01*
X880308Y983383D01*
X880517Y983133D01*
X880600Y982842D01*
X880517Y982508D01*
X880267Y982217D01*
X879892Y982050D01*
X879475Y982008D01*
X878933Y982092D01*
X878642Y982217D01*
X878350Y982425D01*
X878142Y982717D01*
X878100Y983008D01*
X878183Y983300D01*
X878392Y983508D01*
G01X880500Y956667D02*
X878000D01*
Y957708D01*
X878125Y958042D01*
X878292Y958250D01*
X878625Y958333D01*
X878958Y958250D01*
X879167Y958000D01*
X879292Y957708D01*
Y956667D01*
G01Y957708D02*
X880500Y958333D01*
G01X879458Y959808D02*
X879167Y960100D01*
X879000Y960350D01*
X878917Y960683D01*
X879000Y960975D01*
X879167Y961183D01*
X879417Y961350D01*
X879708Y961392D01*
X879958Y961350D01*
X880208Y961183D01*
X880417Y960933D01*
X880500Y960642D01*
X880417Y960308D01*
X880167Y960017D01*
X879792Y959850D01*
X879375Y959808D01*
X878833Y959892D01*
X878542Y960017D01*
X878250Y960225D01*
X878042Y960517D01*
X878000Y960808D01*
X878083Y961100D01*
X878292Y961308D01*
G01X880208Y962992D02*
X880417Y963283D01*
X880500Y963617D01*
X880417Y963950D01*
X880167Y964242D01*
X879792Y964450D01*
X879417Y964533D01*
X878958D01*
X878583Y964450D01*
X878250Y964242D01*
X878083Y963992D01*
X878000Y963700D01*
X878083Y963367D01*
X878250Y963117D01*
X878500Y962950D01*
X878833Y962867D01*
X879125Y962950D01*
X879417Y963158D01*
X879583Y963408D01*
X879625Y963700D01*
X879542Y964033D01*
X879333Y964283D01*
X878958Y964533D01*
G01X889143Y995573D02*
X890935D01*
X891310Y995740D01*
X891560Y996073D01*
X891643Y996490D01*
X891560Y996907D01*
X891310Y997240D01*
X890935Y997407D01*
X889143D01*
G01X891643Y1000090D02*
X889143D01*
X890935Y998548D01*
Y1000632D01*
G01X865948Y1356874D02*
X863448D01*
Y1357915D01*
X863573Y1358249D01*
X863740Y1358457D01*
X864073Y1358540D01*
X864406Y1358457D01*
X864615Y1358207D01*
X864740Y1357915D01*
Y1356874D01*
G01Y1357915D02*
X865948Y1358540D01*
G01X863865Y1360015D02*
X863615Y1360265D01*
X863490Y1360557D01*
X863448Y1360890D01*
X863531Y1361307D01*
X863740Y1361599D01*
X863990Y1361682D01*
X864240Y1361640D01*
X864448Y1361474D01*
X864865Y1360640D01*
X865156Y1360265D01*
X865573Y1360015D01*
X865948Y1359932D01*
Y1361682D01*
G01Y1363907D02*
X865906Y1364199D01*
X865781Y1364532D01*
X865573Y1364740D01*
X865281Y1364824D01*
X864990Y1364740D01*
X864740Y1364490D01*
X864615Y1364115D01*
Y1363699D01*
X864531Y1363449D01*
X864323Y1363240D01*
X864031Y1363157D01*
X863740Y1363282D01*
X863531Y1363574D01*
X863448Y1363907D01*
X863531Y1364240D01*
X863740Y1364532D01*
X864031Y1364657D01*
X864323Y1364574D01*
X864531Y1364365D01*
X864615Y1364115D01*
Y1363699D01*
X864740Y1363324D01*
X864990Y1363074D01*
X865281Y1362990D01*
X865573Y1363074D01*
X865781Y1363282D01*
X865906Y1363615D01*
X865948Y1363907D01*
G01X879448Y1353107D02*
X883448D01*
Y1360507D01*
G01X861248Y1356874D02*
X858748D01*
Y1357915D01*
X858873Y1358249D01*
X859040Y1358457D01*
X859373Y1358540D01*
X859706Y1358457D01*
X859915Y1358207D01*
X860040Y1357915D01*
Y1356874D01*
G01Y1357915D02*
X861248Y1358540D01*
G01X859165Y1360015D02*
X858915Y1360265D01*
X858790Y1360557D01*
X858748Y1360890D01*
X858831Y1361307D01*
X859040Y1361599D01*
X859290Y1361682D01*
X859540Y1361640D01*
X859748Y1361474D01*
X860165Y1360640D01*
X860456Y1360265D01*
X860873Y1360015D01*
X861248Y1359932D01*
Y1361682D01*
G01X860748Y1362990D02*
X861040Y1363240D01*
X861206Y1363574D01*
X861248Y1363949D01*
X861206Y1364282D01*
X860998Y1364615D01*
X860748Y1364824D01*
X860498Y1364865D01*
X860206Y1364782D01*
X859998Y1364490D01*
X859915Y1364199D01*
Y1363824D01*
G01Y1364199D02*
X859790Y1364449D01*
X859581Y1364657D01*
X859331Y1364740D01*
X859081Y1364657D01*
X858873Y1364449D01*
X858748Y1364074D01*
X858790Y1363699D01*
X858956Y1363324D01*
G01X878748Y1360507D02*
X874748D01*
Y1353107D01*
G01X865920Y1343705D02*
X863420D01*
Y1344746D01*
X863545Y1345080D01*
X863712Y1345288D01*
X864045Y1345371D01*
X864378Y1345288D01*
X864587Y1345038D01*
X864712Y1344746D01*
Y1343705D01*
G01Y1344746D02*
X865920Y1345371D01*
G01Y1347638D02*
X863420D01*
X863920Y1347138D01*
G01X865920D02*
Y1348138D01*
G01X865545Y1349821D02*
X865753Y1350071D01*
X865878Y1350363D01*
X865920Y1350738D01*
X865837Y1351113D01*
X865670Y1351405D01*
X865378Y1351613D01*
X865045Y1351655D01*
X864712Y1351571D01*
X864503Y1351363D01*
X864337Y1351071D01*
X864295Y1350780D01*
X864337Y1350488D01*
X864503Y1350113D01*
X863420Y1350238D01*
Y1351363D01*
G01X865920Y1353838D02*
X865878Y1354130D01*
X865753Y1354463D01*
X865545Y1354671D01*
X865253Y1354755D01*
X864962Y1354671D01*
X864712Y1354421D01*
X864587Y1354046D01*
Y1353630D01*
X864503Y1353380D01*
X864295Y1353171D01*
X864003Y1353088D01*
X863712Y1353213D01*
X863503Y1353505D01*
X863420Y1353838D01*
X863503Y1354171D01*
X863712Y1354463D01*
X864003Y1354588D01*
X864295Y1354505D01*
X864503Y1354296D01*
X864587Y1354046D01*
Y1353630D01*
X864712Y1353255D01*
X864962Y1353005D01*
X865253Y1352921D01*
X865545Y1353005D01*
X865753Y1353213D01*
X865878Y1353546D01*
X865920Y1353838D01*
G01X879420Y1344988D02*
X883420D01*
Y1352388D01*
G01X861200Y1343867D02*
X858700D01*
Y1344908D01*
X858825Y1345242D01*
X858992Y1345450D01*
X859325Y1345533D01*
X859658Y1345450D01*
X859867Y1345200D01*
X859992Y1344908D01*
Y1343867D01*
G01Y1344908D02*
X861200Y1345533D01*
G01X859117Y1347008D02*
X858867Y1347258D01*
X858742Y1347550D01*
X858700Y1347883D01*
X858783Y1348300D01*
X858992Y1348592D01*
X859242Y1348675D01*
X859492Y1348633D01*
X859700Y1348467D01*
X860117Y1347633D01*
X860408Y1347258D01*
X860825Y1347008D01*
X861200Y1346925D01*
Y1348675D01*
G01Y1351400D02*
X858700D01*
X860492Y1349858D01*
Y1351942D01*
G01X878740Y1352414D02*
X874740D01*
Y1345014D01*
G01X848439Y1358528D02*
Y1361028D01*
X849480D01*
X849814Y1360903D01*
X850022Y1360736D01*
X850105Y1360403D01*
X850022Y1360070D01*
X849772Y1359861D01*
X849480Y1359736D01*
X848439D01*
G01X849480D02*
X850105Y1358528D01*
G01X851580Y1360611D02*
X851830Y1360861D01*
X852122Y1360986D01*
X852455Y1361028D01*
X852872Y1360945D01*
X853164Y1360736D01*
X853247Y1360486D01*
X853205Y1360236D01*
X853039Y1360028D01*
X852205Y1359611D01*
X851830Y1359320D01*
X851580Y1358903D01*
X851497Y1358528D01*
X853247D01*
G01X854680Y1359570D02*
X854972Y1359861D01*
X855222Y1360028D01*
X855555Y1360111D01*
X855847Y1360028D01*
X856055Y1359861D01*
X856222Y1359611D01*
X856264Y1359320D01*
X856222Y1359070D01*
X856055Y1358820D01*
X855805Y1358611D01*
X855514Y1358528D01*
X855180Y1358611D01*
X854889Y1358861D01*
X854722Y1359236D01*
X854680Y1359653D01*
X854764Y1360195D01*
X854889Y1360486D01*
X855097Y1360778D01*
X855389Y1360986D01*
X855680Y1361028D01*
X855972Y1360945D01*
X856180Y1360736D01*
G01X874072Y1356528D02*
Y1360528D01*
X866672D01*
G01X849600Y1364900D02*
Y1362400D01*
G01X848642Y1364900D02*
X850558D01*
G01X851867Y1362400D02*
Y1364900D01*
X852867D01*
X853200Y1364775D01*
X853450Y1364483D01*
X853533Y1364150D01*
X853450Y1363817D01*
X853242Y1363567D01*
X852867Y1363442D01*
X851867D01*
G01X855008Y1364483D02*
X855258Y1364733D01*
X855550Y1364858D01*
X855883Y1364900D01*
X856300Y1364817D01*
X856592Y1364608D01*
X856675Y1364358D01*
X856633Y1364108D01*
X856467Y1363900D01*
X855633Y1363483D01*
X855258Y1363192D01*
X855008Y1362775D01*
X854925Y1362400D01*
X856675D01*
G01X863464Y1369317D02*
X863339Y1369067D01*
X863256Y1368775D01*
Y1368442D01*
X863381Y1368067D01*
X863589Y1367775D01*
X863839Y1367567D01*
X864256Y1367400D01*
X864631Y1367358D01*
X865006Y1367442D01*
X865256Y1367567D01*
X865506Y1367817D01*
X865673Y1368108D01*
X865756Y1368400D01*
Y1368692D01*
X865673Y1368983D01*
X865548Y1369233D01*
X865381Y1369442D01*
G01X865756Y1372000D02*
X863256D01*
X865048Y1370458D01*
Y1372542D01*
G01X859164Y1368917D02*
X859039Y1368667D01*
X858956Y1368375D01*
Y1368042D01*
X859081Y1367667D01*
X859289Y1367375D01*
X859539Y1367167D01*
X859956Y1367000D01*
X860331Y1366958D01*
X860706Y1367042D01*
X860956Y1367167D01*
X861206Y1367417D01*
X861373Y1367708D01*
X861456Y1368000D01*
Y1368292D01*
X861373Y1368583D01*
X861248Y1368833D01*
X861081Y1369042D01*
G01Y1370183D02*
X861289Y1370433D01*
X861414Y1370725D01*
X861456Y1371100D01*
X861373Y1371475D01*
X861206Y1371767D01*
X860914Y1371975D01*
X860581Y1372017D01*
X860248Y1371933D01*
X860039Y1371725D01*
X859873Y1371433D01*
X859831Y1371142D01*
X859873Y1370850D01*
X860039Y1370475D01*
X858956Y1370600D01*
Y1371725D01*
G01X859179Y1379912D02*
Y1382412D01*
X860220D01*
X860554Y1382287D01*
X860762Y1382120D01*
X860845Y1381787D01*
X860762Y1381454D01*
X860512Y1381245D01*
X860220Y1381120D01*
X859179D01*
G01X860220D02*
X860845Y1379912D01*
G01X862320Y1381995D02*
X862570Y1382245D01*
X862862Y1382370D01*
X863195Y1382412D01*
X863612Y1382329D01*
X863904Y1382120D01*
X863987Y1381870D01*
X863945Y1381620D01*
X863779Y1381412D01*
X862945Y1380995D01*
X862570Y1380704D01*
X862320Y1380287D01*
X862237Y1379912D01*
X863987D01*
G01X865420Y1381995D02*
X865670Y1382245D01*
X865962Y1382370D01*
X866295Y1382412D01*
X866712Y1382329D01*
X867004Y1382120D01*
X867087Y1381870D01*
X867045Y1381620D01*
X866879Y1381412D01*
X866045Y1380995D01*
X865670Y1380704D01*
X865420Y1380287D01*
X865337Y1379912D01*
X867087D01*
G01X883312Y1378412D02*
Y1382412D01*
X875912D01*
G01X859178Y1375246D02*
Y1377746D01*
X860219D01*
X860553Y1377621D01*
X860761Y1377454D01*
X860844Y1377121D01*
X860761Y1376788D01*
X860511Y1376579D01*
X860219Y1376454D01*
X859178D01*
G01X860219D02*
X860844Y1375246D01*
G01X862319Y1377329D02*
X862569Y1377579D01*
X862861Y1377704D01*
X863194Y1377746D01*
X863611Y1377663D01*
X863903Y1377454D01*
X863986Y1377204D01*
X863944Y1376954D01*
X863778Y1376746D01*
X862944Y1376329D01*
X862569Y1376038D01*
X862319Y1375621D01*
X862236Y1375246D01*
X863986D01*
G01X866211D02*
Y1377746D01*
X865711Y1377246D01*
G01Y1375246D02*
X866711D01*
G01X883311Y1373746D02*
Y1377746D01*
X875911D01*
G01X883945Y1414814D02*
X881445D01*
Y1415855D01*
X881570Y1416189D01*
X881737Y1416397D01*
X882070Y1416480D01*
X882403Y1416397D01*
X882612Y1416147D01*
X882737Y1415855D01*
Y1414814D01*
G01Y1415855D02*
X883945Y1416480D01*
G01Y1419247D02*
X881445D01*
X883237Y1417705D01*
Y1419789D01*
G01X881862Y1421055D02*
X881612Y1421305D01*
X881487Y1421597D01*
X881445Y1421930D01*
X881528Y1422347D01*
X881737Y1422639D01*
X881987Y1422722D01*
X882237Y1422680D01*
X882445Y1422514D01*
X882862Y1421680D01*
X883153Y1421305D01*
X883570Y1421055D01*
X883945Y1420972D01*
Y1422722D01*
G01X882903Y1424155D02*
X882612Y1424447D01*
X882445Y1424697D01*
X882362Y1425030D01*
X882445Y1425322D01*
X882612Y1425530D01*
X882862Y1425697D01*
X883153Y1425739D01*
X883403Y1425697D01*
X883653Y1425530D01*
X883862Y1425280D01*
X883945Y1424989D01*
X883862Y1424655D01*
X883612Y1424364D01*
X883237Y1424197D01*
X882820Y1424155D01*
X882278Y1424239D01*
X881987Y1424364D01*
X881695Y1424572D01*
X881487Y1424864D01*
X881445Y1425155D01*
X881528Y1425447D01*
X881737Y1425655D01*
G01X884445Y1412997D02*
X880445D01*
Y1405597D01*
G01X878945Y1414814D02*
X876445D01*
Y1415855D01*
X876570Y1416189D01*
X876737Y1416397D01*
X877070Y1416480D01*
X877403Y1416397D01*
X877612Y1416147D01*
X877737Y1415855D01*
Y1414814D01*
G01Y1415855D02*
X878945Y1416480D01*
G01Y1419247D02*
X876445D01*
X878237Y1417705D01*
Y1419789D01*
G01X876862Y1421055D02*
X876612Y1421305D01*
X876487Y1421597D01*
X876445Y1421930D01*
X876528Y1422347D01*
X876737Y1422639D01*
X876987Y1422722D01*
X877237Y1422680D01*
X877445Y1422514D01*
X877862Y1421680D01*
X878153Y1421305D01*
X878570Y1421055D01*
X878945Y1420972D01*
Y1422722D01*
G01X878570Y1424030D02*
X878778Y1424280D01*
X878903Y1424572D01*
X878945Y1424947D01*
X878862Y1425322D01*
X878695Y1425614D01*
X878403Y1425822D01*
X878070Y1425864D01*
X877737Y1425780D01*
X877528Y1425572D01*
X877362Y1425280D01*
X877320Y1424989D01*
X877362Y1424697D01*
X877528Y1424322D01*
X876445Y1424447D01*
Y1425572D01*
G01X879445Y1412997D02*
X875445D01*
Y1405597D01*
G01X888292Y1414931D02*
X885792D01*
Y1415972D01*
X885917Y1416306D01*
X886084Y1416514D01*
X886417Y1416597D01*
X886750Y1416514D01*
X886959Y1416264D01*
X887084Y1415972D01*
Y1414931D01*
G01Y1415972D02*
X888292Y1416597D01*
G01X887792Y1417947D02*
X888084Y1418197D01*
X888250Y1418531D01*
X888292Y1418906D01*
X888250Y1419239D01*
X888042Y1419572D01*
X887792Y1419781D01*
X887542Y1419822D01*
X887250Y1419739D01*
X887042Y1419447D01*
X886959Y1419156D01*
Y1418781D01*
G01Y1419156D02*
X886834Y1419406D01*
X886625Y1419614D01*
X886375Y1419697D01*
X886125Y1419614D01*
X885917Y1419406D01*
X885792Y1419031D01*
X885834Y1418656D01*
X886000Y1418281D01*
G01X888292Y1421964D02*
X888250Y1422256D01*
X888125Y1422589D01*
X887917Y1422797D01*
X887625Y1422881D01*
X887334Y1422797D01*
X887084Y1422547D01*
X886959Y1422172D01*
Y1421756D01*
X886875Y1421506D01*
X886667Y1421297D01*
X886375Y1421214D01*
X886084Y1421339D01*
X885875Y1421631D01*
X885792Y1421964D01*
X885875Y1422297D01*
X886084Y1422589D01*
X886375Y1422714D01*
X886667Y1422631D01*
X886875Y1422422D01*
X886959Y1422172D01*
Y1421756D01*
X887084Y1421381D01*
X887334Y1421131D01*
X887625Y1421047D01*
X887917Y1421131D01*
X888125Y1421339D01*
X888250Y1421672D01*
X888292Y1421964D01*
G01X885792Y1425064D02*
X885875Y1424731D01*
X886084Y1424481D01*
X886334Y1424314D01*
X886667Y1424189D01*
X887042Y1424147D01*
X887417Y1424189D01*
X887750Y1424314D01*
X888000Y1424481D01*
X888209Y1424731D01*
X888292Y1425064D01*
X888209Y1425397D01*
X888000Y1425647D01*
X887750Y1425814D01*
X887417Y1425939D01*
X887042Y1425981D01*
X886667Y1425939D01*
X886334Y1425814D01*
X886084Y1425647D01*
X885875Y1425397D01*
X885792Y1425064D01*
G01X888792Y1413114D02*
X884792D01*
Y1405714D01*
G01X880000Y1433800D02*
X884000D01*
Y1441200D01*
G01X859639Y1432906D02*
X857139D01*
Y1433947D01*
X857264Y1434281D01*
X857431Y1434489D01*
X857764Y1434572D01*
X858097Y1434489D01*
X858306Y1434239D01*
X858431Y1433947D01*
Y1432906D01*
G01Y1433947D02*
X859639Y1434572D01*
G01Y1436839D02*
X857139D01*
X857639Y1436339D01*
G01X859639D02*
Y1437339D01*
G01Y1439856D02*
X859097Y1439939D01*
X858639Y1440064D01*
X858222Y1440231D01*
X857764Y1440439D01*
X857139Y1440772D01*
Y1439106D01*
G01X859139Y1442122D02*
X859431Y1442372D01*
X859597Y1442706D01*
X859639Y1443081D01*
X859597Y1443414D01*
X859389Y1443747D01*
X859139Y1443956D01*
X858889Y1443997D01*
X858597Y1443914D01*
X858389Y1443622D01*
X858306Y1443331D01*
Y1442956D01*
G01Y1443331D02*
X858181Y1443581D01*
X857972Y1443789D01*
X857722Y1443872D01*
X857472Y1443789D01*
X857264Y1443581D01*
X857139Y1443206D01*
X857181Y1442831D01*
X857347Y1442456D01*
G01X870500Y1441200D02*
X866500D01*
Y1433800D01*
G01X888500Y1441200D02*
X884500D01*
Y1433800D01*
G01X864050Y1432840D02*
X861550D01*
Y1433881D01*
X861675Y1434215D01*
X861842Y1434423D01*
X862175Y1434506D01*
X862508Y1434423D01*
X862717Y1434173D01*
X862842Y1433881D01*
Y1432840D01*
G01Y1433881D02*
X864050Y1434506D01*
G01Y1436773D02*
X861550D01*
X862050Y1436273D01*
G01X864050D02*
Y1437273D01*
G01X863675Y1438956D02*
X863883Y1439206D01*
X864008Y1439498D01*
X864050Y1439873D01*
X863967Y1440248D01*
X863800Y1440540D01*
X863508Y1440748D01*
X863175Y1440790D01*
X862842Y1440706D01*
X862633Y1440498D01*
X862467Y1440206D01*
X862425Y1439915D01*
X862467Y1439623D01*
X862633Y1439248D01*
X861550Y1439373D01*
Y1440498D01*
G01X864050Y1442973D02*
X861550D01*
X862050Y1442473D01*
G01X864050D02*
Y1443473D01*
G01X871000Y1433800D02*
X875000D01*
Y1441200D01*
G01X892558Y1432148D02*
X890058D01*
Y1433189D01*
X890183Y1433523D01*
X890350Y1433731D01*
X890683Y1433814D01*
X891016Y1433731D01*
X891225Y1433481D01*
X891350Y1433189D01*
Y1432148D01*
G01Y1433189D02*
X892558Y1433814D01*
G01Y1436081D02*
X890058D01*
X890558Y1435581D01*
G01X892558D02*
Y1436581D01*
G01Y1439098D02*
X892016Y1439181D01*
X891558Y1439306D01*
X891141Y1439473D01*
X890683Y1439681D01*
X890058Y1440014D01*
Y1438348D01*
G01X891516Y1441489D02*
X891225Y1441781D01*
X891058Y1442031D01*
X890975Y1442364D01*
X891058Y1442656D01*
X891225Y1442864D01*
X891475Y1443031D01*
X891766Y1443073D01*
X892016Y1443031D01*
X892266Y1442864D01*
X892475Y1442614D01*
X892558Y1442323D01*
X892475Y1441989D01*
X892225Y1441698D01*
X891850Y1441531D01*
X891433Y1441489D01*
X890891Y1441573D01*
X890600Y1441698D01*
X890308Y1441906D01*
X890100Y1442198D01*
X890058Y1442489D01*
X890141Y1442781D01*
X890350Y1442989D01*
G01X879500Y1441200D02*
X875500D01*
Y1433800D01*
G01X868500Y1456983D02*
X870292D01*
X870667Y1457150D01*
X870917Y1457483D01*
X871000Y1457900D01*
X870917Y1458317D01*
X870667Y1458650D01*
X870292Y1458817D01*
X868500D01*
G01X871000Y1461000D02*
X868500D01*
X869000Y1460500D01*
G01X871000D02*
Y1461500D01*
G01Y1464100D02*
X870958Y1464392D01*
X870833Y1464725D01*
X870625Y1464933D01*
X870333Y1465017D01*
X870042Y1464933D01*
X869792Y1464683D01*
X869667Y1464308D01*
Y1463892D01*
X869583Y1463642D01*
X869375Y1463433D01*
X869083Y1463350D01*
X868792Y1463475D01*
X868583Y1463767D01*
X868500Y1464100D01*
X868583Y1464433D01*
X868792Y1464725D01*
X869083Y1464850D01*
X869375Y1464767D01*
X869583Y1464558D01*
X869667Y1464308D01*
Y1463892D01*
X869792Y1463517D01*
X870042Y1463267D01*
X870333Y1463183D01*
X870625Y1463267D01*
X870833Y1463475D01*
X870958Y1463808D01*
X871000Y1464100D01*
G01X874211Y1445661D02*
Y1466661D01*
X905861D01*
Y1455661D01*
X874211D01*
G01Y1464311D02*
X877361Y1461161D01*
X874211Y1458011D01*
G01X864258Y1477188D02*
X861758D01*
Y1478229D01*
X861883Y1478563D01*
X862050Y1478771D01*
X862383Y1478854D01*
X862716Y1478771D01*
X862925Y1478521D01*
X863050Y1478229D01*
Y1477188D01*
G01Y1478229D02*
X864258Y1478854D01*
G01Y1481121D02*
X861758D01*
X862258Y1480621D01*
G01X864258D02*
Y1481621D01*
G01Y1484138D02*
X863716Y1484221D01*
X863258Y1484346D01*
X862841Y1484513D01*
X862383Y1484721D01*
X861758Y1485054D01*
Y1483388D01*
G01X864258Y1487821D02*
X861758D01*
X863550Y1486279D01*
Y1488363D01*
G01X891050Y1480600D02*
X895050D01*
Y1488000D01*
G01X890833Y1515967D02*
X888333D01*
Y1517008D01*
X888458Y1517342D01*
X888625Y1517550D01*
X888958Y1517633D01*
X889291Y1517550D01*
X889500Y1517300D01*
X889625Y1517008D01*
Y1515967D01*
G01Y1517008D02*
X890833Y1517633D01*
G01Y1519900D02*
X888333D01*
X888833Y1519400D01*
G01X890833D02*
Y1520400D01*
G01Y1523000D02*
X888333D01*
X888833Y1522500D01*
G01X890833D02*
Y1523500D01*
G01X888333Y1526100D02*
X888416Y1525767D01*
X888625Y1525517D01*
X888875Y1525350D01*
X889208Y1525225D01*
X889583Y1525183D01*
X889958Y1525225D01*
X890291Y1525350D01*
X890541Y1525517D01*
X890750Y1525767D01*
X890833Y1526100D01*
X890750Y1526433D01*
X890541Y1526683D01*
X890291Y1526850D01*
X889958Y1526975D01*
X889583Y1527017D01*
X889208Y1526975D01*
X888875Y1526850D01*
X888625Y1526683D01*
X888416Y1526433D01*
X888333Y1526100D01*
G01X890833Y1529117D02*
X890291Y1529200D01*
X889833Y1529325D01*
X889416Y1529492D01*
X888958Y1529700D01*
X888333Y1530033D01*
Y1528367D01*
G01X890333Y1499467D02*
X887833D01*
Y1500508D01*
X887958Y1500842D01*
X888125Y1501050D01*
X888458Y1501133D01*
X888791Y1501050D01*
X889000Y1500800D01*
X889125Y1500508D01*
Y1499467D01*
G01Y1500508D02*
X890333Y1501133D01*
G01Y1503400D02*
X887833D01*
X888333Y1502900D01*
G01X890333D02*
Y1503900D01*
G01Y1506500D02*
X887833D01*
X888333Y1506000D01*
G01X890333D02*
Y1507000D01*
G01X889833Y1508683D02*
X890125Y1508933D01*
X890291Y1509267D01*
X890333Y1509642D01*
X890291Y1509975D01*
X890083Y1510308D01*
X889833Y1510517D01*
X889583Y1510558D01*
X889291Y1510475D01*
X889083Y1510183D01*
X889000Y1509892D01*
Y1509517D01*
G01Y1509892D02*
X888875Y1510142D01*
X888666Y1510350D01*
X888416Y1510433D01*
X888166Y1510350D01*
X887958Y1510142D01*
X887833Y1509767D01*
X887875Y1509392D01*
X888041Y1509017D01*
G01X890333Y1512700D02*
X887833D01*
X888333Y1512200D01*
G01X890333D02*
Y1513200D01*
G01X898365Y1521992D02*
X894365D01*
Y1514592D01*
G01X853158Y1477188D02*
X850658D01*
Y1478229D01*
X850783Y1478563D01*
X850950Y1478771D01*
X851283Y1478854D01*
X851616Y1478771D01*
X851825Y1478521D01*
X851950Y1478229D01*
Y1477188D01*
G01Y1478229D02*
X853158Y1478854D01*
G01Y1481121D02*
X850658D01*
X851158Y1480621D01*
G01X853158D02*
Y1481621D01*
G01X852783Y1483304D02*
X852991Y1483554D01*
X853116Y1483846D01*
X853158Y1484221D01*
X853075Y1484596D01*
X852908Y1484888D01*
X852616Y1485096D01*
X852283Y1485138D01*
X851950Y1485054D01*
X851741Y1484846D01*
X851575Y1484554D01*
X851533Y1484263D01*
X851575Y1483971D01*
X851741Y1483596D01*
X850658Y1483721D01*
Y1484846D01*
G01X852116Y1486529D02*
X851825Y1486821D01*
X851658Y1487071D01*
X851575Y1487404D01*
X851658Y1487696D01*
X851825Y1487904D01*
X852075Y1488071D01*
X852366Y1488113D01*
X852616Y1488071D01*
X852866Y1487904D01*
X853075Y1487654D01*
X853158Y1487363D01*
X853075Y1487029D01*
X852825Y1486738D01*
X852450Y1486571D01*
X852033Y1486529D01*
X851491Y1486613D01*
X851200Y1486738D01*
X850908Y1486946D01*
X850700Y1487238D01*
X850658Y1487529D01*
X850741Y1487821D01*
X850950Y1488029D01*
G01X877321Y1480561D02*
X881321D01*
Y1487961D01*
G01X856858Y1477188D02*
X854358D01*
Y1478229D01*
X854483Y1478563D01*
X854650Y1478771D01*
X854983Y1478854D01*
X855316Y1478771D01*
X855525Y1478521D01*
X855650Y1478229D01*
Y1477188D01*
G01Y1478229D02*
X856858Y1478854D01*
G01Y1481121D02*
X854358D01*
X854858Y1480621D01*
G01X856858D02*
Y1481621D01*
G01Y1484138D02*
X856316Y1484221D01*
X855858Y1484346D01*
X855441Y1484513D01*
X854983Y1484721D01*
X854358Y1485054D01*
Y1483388D01*
G01X854775Y1486529D02*
X854525Y1486779D01*
X854400Y1487071D01*
X854358Y1487404D01*
X854441Y1487821D01*
X854650Y1488113D01*
X854900Y1488196D01*
X855150Y1488154D01*
X855358Y1487988D01*
X855775Y1487154D01*
X856066Y1486779D01*
X856483Y1486529D01*
X856858Y1486446D01*
Y1488196D01*
G01X881947Y1480570D02*
X885947D01*
Y1487970D01*
G01X860558Y1477188D02*
X858058D01*
Y1478229D01*
X858183Y1478563D01*
X858350Y1478771D01*
X858683Y1478854D01*
X859016Y1478771D01*
X859225Y1478521D01*
X859350Y1478229D01*
Y1477188D01*
G01Y1478229D02*
X860558Y1478854D01*
G01Y1481121D02*
X858058D01*
X858558Y1480621D01*
G01X860558D02*
Y1481621D01*
G01Y1484721D02*
X858058D01*
X859850Y1483179D01*
Y1485263D01*
G01X860558Y1487321D02*
X860516Y1487613D01*
X860391Y1487946D01*
X860183Y1488154D01*
X859891Y1488238D01*
X859600Y1488154D01*
X859350Y1487904D01*
X859225Y1487529D01*
Y1487113D01*
X859141Y1486863D01*
X858933Y1486654D01*
X858641Y1486571D01*
X858350Y1486696D01*
X858141Y1486988D01*
X858058Y1487321D01*
X858141Y1487654D01*
X858350Y1487946D01*
X858641Y1488071D01*
X858933Y1487988D01*
X859141Y1487779D01*
X859225Y1487529D01*
Y1487113D01*
X859350Y1486738D01*
X859600Y1486488D01*
X859891Y1486404D01*
X860183Y1486488D01*
X860391Y1486696D01*
X860516Y1487029D01*
X860558Y1487321D01*
G01X890600Y1487950D02*
X886600D01*
Y1480550D01*
G01X868264Y1496803D02*
X865764D01*
Y1497844D01*
X865889Y1498178D01*
X866056Y1498386D01*
X866389Y1498469D01*
X866722Y1498386D01*
X866931Y1498136D01*
X867056Y1497844D01*
Y1496803D01*
G01Y1497844D02*
X868264Y1498469D01*
G01Y1500736D02*
X865764D01*
X866264Y1500236D01*
G01X868264D02*
Y1501236D01*
G01X867764Y1502919D02*
X868056Y1503169D01*
X868222Y1503503D01*
X868264Y1503878D01*
X868222Y1504211D01*
X868014Y1504544D01*
X867764Y1504753D01*
X867514Y1504794D01*
X867222Y1504711D01*
X867014Y1504419D01*
X866931Y1504128D01*
Y1503753D01*
G01Y1504128D02*
X866806Y1504378D01*
X866597Y1504586D01*
X866347Y1504669D01*
X866097Y1504586D01*
X865889Y1504378D01*
X865764Y1504003D01*
X865806Y1503628D01*
X865972Y1503253D01*
G01X868264Y1506936D02*
X865764D01*
X866264Y1506436D01*
G01X868264D02*
Y1507436D01*
G01X858000Y1499300D02*
X862000D01*
Y1506700D01*
G01X848500Y1499300D02*
X852500D01*
Y1506700D01*
G01X849627Y1511825D02*
X849585Y1511492D01*
X849419Y1511200D01*
X849169Y1510950D01*
X848877Y1510783D01*
X848544Y1510700D01*
X848210D01*
X847877Y1510783D01*
X847585Y1510950D01*
X847335Y1511200D01*
X847169Y1511492D01*
X847127Y1511825D01*
X847169Y1512158D01*
X847335Y1512450D01*
X847585Y1512700D01*
X847877Y1512867D01*
X848210Y1512950D01*
X848544D01*
X848877Y1512867D01*
X849169Y1512700D01*
X849419Y1512450D01*
X849585Y1512158D01*
X849627Y1511825D01*
G01X848960Y1512158D02*
X849627Y1512658D01*
G01X847544Y1514133D02*
X847294Y1514383D01*
X847169Y1514675D01*
X847127Y1515008D01*
X847210Y1515425D01*
X847419Y1515717D01*
X847669Y1515800D01*
X847919Y1515758D01*
X848127Y1515592D01*
X848544Y1514758D01*
X848835Y1514383D01*
X849252Y1514133D01*
X849627Y1514050D01*
Y1515800D01*
G01Y1518025D02*
X847127D01*
X847627Y1517525D01*
G01X849627D02*
Y1518525D01*
G01X865000Y1508000D02*
Y1522000D01*
G01X852000Y1508000D02*
X865000D01*
G01X852000Y1522000D02*
Y1508000D01*
G01X878250Y1515266D02*
Y1517766D01*
X879084D01*
X879417Y1517641D01*
X879667Y1517474D01*
X879875Y1517224D01*
X880042Y1516933D01*
X880084Y1516516D01*
X880042Y1516099D01*
X879875Y1515808D01*
X879667Y1515558D01*
X879417Y1515391D01*
X879084Y1515266D01*
X878250D01*
G01X882767D02*
Y1517766D01*
X881225Y1515974D01*
X883309D01*
G01X885367Y1515266D02*
Y1517766D01*
X884867Y1517266D01*
G01Y1515266D02*
X885867D01*
G01X898335Y1530408D02*
X894335D01*
Y1523008D01*
G01X870220Y1542150D02*
Y1544650D01*
X871261D01*
X871595Y1544525D01*
X871803Y1544358D01*
X871886Y1544025D01*
X871803Y1543692D01*
X871553Y1543483D01*
X871261Y1543358D01*
X870220D01*
G01X871261D02*
X871886Y1542150D01*
G01X874153D02*
Y1544650D01*
X873653Y1544150D01*
G01Y1542150D02*
X874653D01*
G01X876336Y1542650D02*
X876586Y1542358D01*
X876920Y1542192D01*
X877295Y1542150D01*
X877628Y1542192D01*
X877961Y1542400D01*
X878170Y1542650D01*
X878211Y1542900D01*
X878128Y1543192D01*
X877836Y1543400D01*
X877545Y1543483D01*
X877170D01*
G01X877545D02*
X877795Y1543608D01*
X878003Y1543817D01*
X878086Y1544067D01*
X878003Y1544317D01*
X877795Y1544525D01*
X877420Y1544650D01*
X877045Y1544608D01*
X876670Y1544442D01*
G01X880353Y1544650D02*
X880020Y1544567D01*
X879770Y1544358D01*
X879603Y1544108D01*
X879478Y1543775D01*
X879436Y1543400D01*
X879478Y1543025D01*
X879603Y1542692D01*
X879770Y1542442D01*
X880020Y1542233D01*
X880353Y1542150D01*
X880686Y1542233D01*
X880936Y1542442D01*
X881103Y1542692D01*
X881228Y1543025D01*
X881270Y1543400D01*
X881228Y1543775D01*
X881103Y1544108D01*
X880936Y1544358D01*
X880686Y1544567D01*
X880353Y1544650D01*
G01X873908Y1521720D02*
Y1525720D01*
X866508D01*
G01X867533Y1547417D02*
X867200Y1547459D01*
X866908Y1547625D01*
X866658Y1547875D01*
X866491Y1548167D01*
X866408Y1548500D01*
Y1548834D01*
X866491Y1549167D01*
X866658Y1549459D01*
X866908Y1549709D01*
X867200Y1549875D01*
X867533Y1549917D01*
X867866Y1549875D01*
X868158Y1549709D01*
X868408Y1549459D01*
X868575Y1549167D01*
X868658Y1548834D01*
Y1548500D01*
X868575Y1548167D01*
X868408Y1547875D01*
X868158Y1547625D01*
X867866Y1547459D01*
X867533Y1547417D01*
G01X867866Y1548084D02*
X868366Y1547417D01*
G01X869841Y1549500D02*
X870091Y1549750D01*
X870383Y1549875D01*
X870716Y1549917D01*
X871133Y1549834D01*
X871425Y1549625D01*
X871508Y1549375D01*
X871466Y1549125D01*
X871300Y1548917D01*
X870466Y1548500D01*
X870091Y1548209D01*
X869841Y1547792D01*
X869758Y1547417D01*
X871508D01*
G01X872941Y1549500D02*
X873191Y1549750D01*
X873483Y1549875D01*
X873816Y1549917D01*
X874233Y1549834D01*
X874525Y1549625D01*
X874608Y1549375D01*
X874566Y1549125D01*
X874400Y1548917D01*
X873566Y1548500D01*
X873191Y1548209D01*
X872941Y1547792D01*
X872858Y1547417D01*
X874608D01*
G01X874958Y1526437D02*
Y1540437D01*
G01X861958Y1526437D02*
X874958D01*
G01X861958Y1540437D02*
Y1526437D01*
G01X874958Y1540437D02*
X861958D01*
G01X865000Y1522000D02*
X852000D01*
G01X851458Y1535691D02*
Y1525691D01*
G01X893479Y1546376D02*
X890979D01*
Y1547417D01*
X891104Y1547751D01*
X891271Y1547959D01*
X891604Y1548042D01*
X891937Y1547959D01*
X892146Y1547709D01*
X892271Y1547417D01*
Y1546376D01*
G01Y1547417D02*
X893479Y1548042D01*
G01Y1550309D02*
X890979D01*
X891479Y1549809D01*
G01X893479D02*
Y1550809D01*
G01X891396Y1552617D02*
X891146Y1552867D01*
X891021Y1553159D01*
X890979Y1553492D01*
X891062Y1553909D01*
X891271Y1554201D01*
X891521Y1554284D01*
X891771Y1554242D01*
X891979Y1554076D01*
X892396Y1553242D01*
X892687Y1552867D01*
X893104Y1552617D01*
X893479Y1552534D01*
Y1554284D01*
G01X893187Y1555801D02*
X893396Y1556092D01*
X893479Y1556426D01*
X893396Y1556759D01*
X893146Y1557051D01*
X892771Y1557259D01*
X892396Y1557342D01*
X891937D01*
X891562Y1557259D01*
X891229Y1557051D01*
X891062Y1556801D01*
X890979Y1556509D01*
X891062Y1556176D01*
X891229Y1555926D01*
X891479Y1555759D01*
X891812Y1555676D01*
X892104Y1555759D01*
X892396Y1555967D01*
X892562Y1556217D01*
X892604Y1556509D01*
X892521Y1556842D01*
X892312Y1557092D01*
X891937Y1557342D01*
G01X892979Y1558692D02*
X893271Y1558942D01*
X893437Y1559276D01*
X893479Y1559651D01*
X893437Y1559984D01*
X893229Y1560317D01*
X892979Y1560526D01*
X892729Y1560567D01*
X892437Y1560484D01*
X892229Y1560192D01*
X892146Y1559901D01*
Y1559526D01*
G01Y1559901D02*
X892021Y1560151D01*
X891812Y1560359D01*
X891562Y1560442D01*
X891312Y1560359D01*
X891104Y1560151D01*
X890979Y1559776D01*
X891021Y1559401D01*
X891187Y1559026D01*
G01X850960Y1543948D02*
X850835Y1543698D01*
X850752Y1543406D01*
Y1543073D01*
X850877Y1542698D01*
X851085Y1542406D01*
X851335Y1542198D01*
X851752Y1542031D01*
X852127Y1541989D01*
X852502Y1542073D01*
X852752Y1542198D01*
X853002Y1542448D01*
X853169Y1542739D01*
X853252Y1543031D01*
Y1543323D01*
X853169Y1543614D01*
X853044Y1543864D01*
X852877Y1544073D01*
G01X852210Y1545339D02*
X851919Y1545631D01*
X851752Y1545881D01*
X851669Y1546214D01*
X851752Y1546506D01*
X851919Y1546714D01*
X852169Y1546881D01*
X852460Y1546923D01*
X852710Y1546881D01*
X852960Y1546714D01*
X853169Y1546464D01*
X853252Y1546173D01*
X853169Y1545839D01*
X852919Y1545548D01*
X852544Y1545381D01*
X852127Y1545339D01*
X851585Y1545423D01*
X851294Y1545548D01*
X851002Y1545756D01*
X850794Y1546048D01*
X850752Y1546339D01*
X850835Y1546631D01*
X851044Y1546839D01*
G01X853252Y1549231D02*
X853210Y1549523D01*
X853085Y1549856D01*
X852877Y1550064D01*
X852585Y1550148D01*
X852294Y1550064D01*
X852044Y1549814D01*
X851919Y1549439D01*
Y1549023D01*
X851835Y1548773D01*
X851627Y1548564D01*
X851335Y1548481D01*
X851044Y1548606D01*
X850835Y1548898D01*
X850752Y1549231D01*
X850835Y1549564D01*
X851044Y1549856D01*
X851335Y1549981D01*
X851627Y1549898D01*
X851835Y1549689D01*
X851919Y1549439D01*
Y1549023D01*
X852044Y1548648D01*
X852294Y1548398D01*
X852585Y1548314D01*
X852877Y1548398D01*
X853085Y1548606D01*
X853210Y1548939D01*
X853252Y1549231D01*
G01Y1552331D02*
X853210Y1552623D01*
X853085Y1552956D01*
X852877Y1553164D01*
X852585Y1553248D01*
X852294Y1553164D01*
X852044Y1552914D01*
X851919Y1552539D01*
Y1552123D01*
X851835Y1551873D01*
X851627Y1551664D01*
X851335Y1551581D01*
X851044Y1551706D01*
X850835Y1551998D01*
X850752Y1552331D01*
X850835Y1552664D01*
X851044Y1552956D01*
X851335Y1553081D01*
X851627Y1552998D01*
X851835Y1552789D01*
X851919Y1552539D01*
Y1552123D01*
X852044Y1551748D01*
X852294Y1551498D01*
X852585Y1551414D01*
X852877Y1551498D01*
X853085Y1551706D01*
X853210Y1552039D01*
X853252Y1552331D01*
G01X886000Y1535868D02*
Y1519768D01*
G01X879000Y1535868D02*
X886000D01*
G01X879000Y1519768D02*
Y1535868D01*
G01X886000Y1519768D02*
X879000D01*
G01X846939Y1584894D02*
Y1588894D01*
X848539D01*
X849072Y1588694D01*
X849472Y1588227D01*
X849605Y1587694D01*
X849472Y1587161D01*
X849139Y1586761D01*
X848539Y1586561D01*
X846939D01*
G01X851939Y1584894D02*
Y1587561D01*
G01Y1587027D02*
X852272Y1587294D01*
X852605Y1587494D01*
X853072Y1587561D01*
X853405Y1587494D01*
X853805Y1587294D01*
G01X856472Y1586694D02*
X858605D01*
X858405Y1587161D01*
X858072Y1587427D01*
X857605Y1587561D01*
X857139Y1587494D01*
X856739Y1587294D01*
X856472Y1586827D01*
X856339Y1586427D01*
Y1586027D01*
X856472Y1585627D01*
X856805Y1585227D01*
X857205Y1584961D01*
X857672Y1584894D01*
X858139Y1585027D01*
X858605Y1585427D01*
G01X861072Y1585361D02*
X861405Y1585094D01*
X861872Y1584894D01*
X862272D01*
X862672Y1585027D01*
X862939Y1585227D01*
X863072Y1585494D01*
X863005Y1585894D01*
X862739Y1586094D01*
X861539Y1586494D01*
X861272Y1586961D01*
X861405Y1587294D01*
X861672Y1587494D01*
X862072Y1587561D01*
X862472Y1587494D01*
X862872Y1587294D01*
G01X865672Y1585361D02*
X866005Y1585094D01*
X866472Y1584894D01*
X866872D01*
X867272Y1585027D01*
X867539Y1585227D01*
X867672Y1585494D01*
X867605Y1585894D01*
X867339Y1586094D01*
X866139Y1586494D01*
X865872Y1586961D01*
X866005Y1587294D01*
X866272Y1587494D01*
X866672Y1587561D01*
X867072Y1587494D01*
X867472Y1587294D01*
G01X874605Y1584894D02*
Y1588894D01*
X877139D01*
G01X876205Y1586961D02*
X874605D01*
G01X880472Y1587561D02*
Y1584894D01*
G01Y1588627D02*
X880339Y1588694D01*
Y1588827D01*
X880472Y1588894D01*
X880605Y1588827D01*
Y1588694D01*
X880472Y1588627D01*
G01X885072Y1588894D02*
Y1584894D01*
G01X884139Y1587561D02*
X886005D01*
G01X858672Y1668527D02*
X859205Y1668194D01*
X859805Y1667994D01*
X860339D01*
X860872Y1668194D01*
X861272Y1668527D01*
X861472Y1668994D01*
X861339Y1669461D01*
X861005Y1669861D01*
X860405Y1670127D01*
X859605Y1670261D01*
X859139Y1670527D01*
X858939Y1670994D01*
X859072Y1671461D01*
X859405Y1671794D01*
X859872Y1671994D01*
X860339D01*
X860805Y1671861D01*
X861205Y1671527D01*
G01X864672Y1667994D02*
Y1671994D01*
G01X869272Y1670661D02*
Y1667994D01*
G01Y1671727D02*
X869139Y1671794D01*
Y1671927D01*
X869272Y1671994D01*
X869405Y1671927D01*
Y1671794D01*
X869272Y1671727D01*
G01X873872Y1671994D02*
Y1667994D01*
G01X872939Y1670661D02*
X874805D01*
G01X1017713Y-98257D02*
Y-103307D01*
X1116413D01*
Y-127957D01*
X932013D01*
Y-103307D01*
X990713D01*
Y-98257D01*
X1017713D01*
G01X963426Y-235D02*
X925726D01*
Y352165D01*
X963426D01*
Y-235D01*
G01Y378898D02*
X925726D01*
Y731298D01*
X963426D01*
Y378898D01*
G01X937217Y781500D02*
Y784000D01*
X938300Y781917D01*
X939383Y784000D01*
Y781500D01*
G01X941400D02*
X941067Y781542D01*
X940775Y781708D01*
X940525Y781958D01*
X940358Y782250D01*
X940275Y782583D01*
Y782917D01*
X940358Y783250D01*
X940525Y783542D01*
X940775Y783792D01*
X941067Y783958D01*
X941400Y784000D01*
X941733Y783958D01*
X942025Y783792D01*
X942275Y783542D01*
X942442Y783250D01*
X942525Y782917D01*
Y782583D01*
X942442Y782250D01*
X942275Y781958D01*
X942025Y781708D01*
X941733Y781542D01*
X941400Y781500D01*
G01X943542D02*
Y784000D01*
X945458Y781500D01*
Y784000D01*
G01X947600Y781500D02*
X947267Y781542D01*
X946975Y781708D01*
X946725Y781958D01*
X946558Y782250D01*
X946475Y782583D01*
Y782917D01*
X946558Y783250D01*
X946725Y783542D01*
X946975Y783792D01*
X947267Y783958D01*
X947600Y784000D01*
X947933Y783958D01*
X948225Y783792D01*
X948475Y783542D01*
X948642Y783250D01*
X948725Y782917D01*
Y782583D01*
X948642Y782250D01*
X948475Y781958D01*
X948225Y781708D01*
X947933Y781542D01*
X947600Y781500D01*
G01X949908Y783583D02*
X950158Y783833D01*
X950450Y783958D01*
X950783Y784000D01*
X951200Y783917D01*
X951492Y783708D01*
X951575Y783458D01*
X951533Y783208D01*
X951367Y783000D01*
X950533Y782583D01*
X950158Y782292D01*
X949908Y781875D01*
X949825Y781500D01*
X951575D01*
G01X937217Y786500D02*
Y789000D01*
X938300Y786917D01*
X939383Y789000D01*
Y786500D01*
G01X941400D02*
X941067Y786542D01*
X940775Y786708D01*
X940525Y786958D01*
X940358Y787250D01*
X940275Y787583D01*
Y787917D01*
X940358Y788250D01*
X940525Y788542D01*
X940775Y788792D01*
X941067Y788958D01*
X941400Y789000D01*
X941733Y788958D01*
X942025Y788792D01*
X942275Y788542D01*
X942442Y788250D01*
X942525Y787917D01*
Y787583D01*
X942442Y787250D01*
X942275Y786958D01*
X942025Y786708D01*
X941733Y786542D01*
X941400Y786500D01*
G01X943542D02*
Y789000D01*
X945458Y786500D01*
Y789000D01*
G01X947600Y786500D02*
X947267Y786542D01*
X946975Y786708D01*
X946725Y786958D01*
X946558Y787250D01*
X946475Y787583D01*
Y787917D01*
X946558Y788250D01*
X946725Y788542D01*
X946975Y788792D01*
X947267Y788958D01*
X947600Y789000D01*
X947933Y788958D01*
X948225Y788792D01*
X948475Y788542D01*
X948642Y788250D01*
X948725Y787917D01*
Y787583D01*
X948642Y787250D01*
X948475Y786958D01*
X948225Y786708D01*
X947933Y786542D01*
X947600Y786500D01*
G01X950700D02*
Y789000D01*
X950200Y788500D01*
G01Y786500D02*
X951200D01*
G01X925100Y889767D02*
X922600D01*
Y890808D01*
X922725Y891142D01*
X922892Y891350D01*
X923225Y891433D01*
X923558Y891350D01*
X923767Y891100D01*
X923892Y890808D01*
Y889767D01*
G01Y890808D02*
X925100Y891433D01*
G01X924058Y892908D02*
X923767Y893200D01*
X923600Y893450D01*
X923517Y893783D01*
X923600Y894075D01*
X923767Y894283D01*
X924017Y894450D01*
X924308Y894492D01*
X924558Y894450D01*
X924808Y894283D01*
X925017Y894033D01*
X925100Y893742D01*
X925017Y893408D01*
X924767Y893117D01*
X924392Y892950D01*
X923975Y892908D01*
X923433Y892992D01*
X923142Y893117D01*
X922850Y893325D01*
X922642Y893617D01*
X922600Y893908D01*
X922683Y894200D01*
X922892Y894408D01*
G01X924725Y895883D02*
X924933Y896133D01*
X925058Y896425D01*
X925100Y896800D01*
X925017Y897175D01*
X924850Y897467D01*
X924558Y897675D01*
X924225Y897717D01*
X923892Y897633D01*
X923683Y897425D01*
X923517Y897133D01*
X923475Y896842D01*
X923517Y896550D01*
X923683Y896175D01*
X922600Y896300D01*
Y897425D01*
G01X929600Y889767D02*
X927100D01*
Y890808D01*
X927225Y891142D01*
X927392Y891350D01*
X927725Y891433D01*
X928058Y891350D01*
X928267Y891100D01*
X928392Y890808D01*
Y889767D01*
G01Y890808D02*
X929600Y891433D01*
G01Y893617D02*
X929058Y893700D01*
X928600Y893825D01*
X928183Y893992D01*
X927725Y894200D01*
X927100Y894533D01*
Y892867D01*
G01X929600Y896800D02*
X927100D01*
X927600Y896300D01*
G01X929600D02*
Y897300D01*
G01X916100Y889767D02*
X913600D01*
Y890808D01*
X913725Y891142D01*
X913892Y891350D01*
X914225Y891433D01*
X914558Y891350D01*
X914767Y891100D01*
X914892Y890808D01*
Y889767D01*
G01Y890808D02*
X916100Y891433D01*
G01X915058Y892908D02*
X914767Y893200D01*
X914600Y893450D01*
X914517Y893783D01*
X914600Y894075D01*
X914767Y894283D01*
X915017Y894450D01*
X915308Y894492D01*
X915558Y894450D01*
X915808Y894283D01*
X916017Y894033D01*
X916100Y893742D01*
X916017Y893408D01*
X915767Y893117D01*
X915392Y892950D01*
X914975Y892908D01*
X914433Y892992D01*
X914142Y893117D01*
X913850Y893325D01*
X913642Y893617D01*
X913600Y893908D01*
X913683Y894200D01*
X913892Y894408D01*
G01X916100Y896717D02*
X915558Y896800D01*
X915100Y896925D01*
X914683Y897092D01*
X914225Y897300D01*
X913600Y897633D01*
Y895967D01*
G01X920600Y889767D02*
X918100D01*
Y890808D01*
X918225Y891142D01*
X918392Y891350D01*
X918725Y891433D01*
X919058Y891350D01*
X919267Y891100D01*
X919392Y890808D01*
Y889767D01*
G01Y890808D02*
X920600Y891433D01*
G01Y893617D02*
X920058Y893700D01*
X919600Y893825D01*
X919183Y893992D01*
X918725Y894200D01*
X918100Y894533D01*
Y892867D01*
G01X918517Y896008D02*
X918267Y896258D01*
X918142Y896550D01*
X918100Y896883D01*
X918183Y897300D01*
X918392Y897592D01*
X918642Y897675D01*
X918892Y897633D01*
X919100Y897467D01*
X919517Y896633D01*
X919808Y896258D01*
X920225Y896008D01*
X920600Y895925D01*
Y897675D01*
G01X934265Y888826D02*
X933932Y888868D01*
X933640Y889034D01*
X933390Y889284D01*
X933223Y889576D01*
X933140Y889909D01*
Y890243D01*
X933223Y890576D01*
X933390Y890868D01*
X933640Y891118D01*
X933932Y891284D01*
X934265Y891326D01*
X934598Y891284D01*
X934890Y891118D01*
X935140Y890868D01*
X935307Y890576D01*
X935390Y890243D01*
Y889909D01*
X935307Y889576D01*
X935140Y889284D01*
X934890Y889034D01*
X934598Y888868D01*
X934265Y888826D01*
G01X934598Y889493D02*
X935098Y888826D01*
G01X937365D02*
Y891326D01*
X936865Y890826D01*
G01Y888826D02*
X937865D01*
G01X939548Y889201D02*
X939798Y888993D01*
X940090Y888868D01*
X940465Y888826D01*
X940840Y888909D01*
X941132Y889076D01*
X941340Y889368D01*
X941382Y889701D01*
X941298Y890034D01*
X941090Y890243D01*
X940798Y890409D01*
X940507Y890451D01*
X940215Y890409D01*
X939840Y890243D01*
X939965Y891326D01*
X941090D01*
G01X925600Y914400D02*
X921600D01*
Y907000D01*
G01X930100Y914400D02*
X926100D01*
Y907000D01*
G01X912600D02*
X916600D01*
Y914400D01*
G01X921100D02*
X917100D01*
Y907000D01*
G01X940515Y910852D02*
Y913352D01*
X941556D01*
X941890Y913227D01*
X942098Y913060D01*
X942181Y912727D01*
X942098Y912394D01*
X941848Y912185D01*
X941556Y912060D01*
X940515D01*
G01X941556D02*
X942181Y910852D01*
G01X944448D02*
Y913352D01*
X943948Y912852D01*
G01Y910852D02*
X944948D01*
G01X947465D02*
X947548Y911394D01*
X947673Y911852D01*
X947840Y912269D01*
X948048Y912727D01*
X948381Y913352D01*
X946715D01*
G01X931581Y914047D02*
Y910047D01*
X938981D01*
G01X933564Y934134D02*
X933231Y934176D01*
X932939Y934342D01*
X932689Y934592D01*
X932522Y934884D01*
X932439Y935217D01*
Y935551D01*
X932522Y935884D01*
X932689Y936176D01*
X932939Y936426D01*
X933231Y936592D01*
X933564Y936634D01*
X933897Y936592D01*
X934189Y936426D01*
X934439Y936176D01*
X934606Y935884D01*
X934689Y935551D01*
Y935217D01*
X934606Y934884D01*
X934439Y934592D01*
X934189Y934342D01*
X933897Y934176D01*
X933564Y934134D01*
G01X933897Y934801D02*
X934397Y934134D01*
G01X936664D02*
Y936634D01*
X936164Y936134D01*
G01Y934134D02*
X937164D01*
G01X938972Y935176D02*
X939264Y935467D01*
X939514Y935634D01*
X939847Y935717D01*
X940139Y935634D01*
X940347Y935467D01*
X940514Y935217D01*
X940556Y934926D01*
X940514Y934676D01*
X940347Y934426D01*
X940097Y934217D01*
X939806Y934134D01*
X939472Y934217D01*
X939181Y934467D01*
X939014Y934842D01*
X938972Y935259D01*
X939056Y935801D01*
X939181Y936092D01*
X939389Y936384D01*
X939681Y936592D01*
X939972Y936634D01*
X940264Y936551D01*
X940472Y936342D01*
G01X930899Y894445D02*
X943899D01*
G01X930899Y908445D02*
Y894445D01*
G01X943899Y908445D02*
X930899D01*
G01X927150Y948500D02*
Y927500D01*
X895500D01*
Y938500D01*
X927150D01*
G01Y929850D02*
X924000Y933000D01*
X927150Y936150D01*
G01X940474Y917026D02*
X940349Y916776D01*
X940266Y916484D01*
Y916151D01*
X940391Y915776D01*
X940599Y915484D01*
X940849Y915276D01*
X941266Y915109D01*
X941641Y915067D01*
X942016Y915151D01*
X942266Y915276D01*
X942516Y915526D01*
X942683Y915817D01*
X942766Y916109D01*
Y916401D01*
X942683Y916692D01*
X942558Y916942D01*
X942391Y917151D01*
G01X940683Y918417D02*
X940433Y918667D01*
X940308Y918959D01*
X940266Y919292D01*
X940349Y919709D01*
X940558Y920001D01*
X940808Y920084D01*
X941058Y920042D01*
X941266Y919876D01*
X941683Y919042D01*
X941974Y918667D01*
X942391Y918417D01*
X942766Y918334D01*
Y920084D01*
G01Y922309D02*
X940266D01*
X940766Y921809D01*
G01X942766D02*
Y922809D01*
G01X936774Y917026D02*
X936649Y916776D01*
X936566Y916484D01*
Y916151D01*
X936691Y915776D01*
X936899Y915484D01*
X937149Y915276D01*
X937566Y915109D01*
X937941Y915067D01*
X938316Y915151D01*
X938566Y915276D01*
X938816Y915526D01*
X938983Y915817D01*
X939066Y916109D01*
Y916401D01*
X938983Y916692D01*
X938858Y916942D01*
X938691Y917151D01*
G01X936983Y918417D02*
X936733Y918667D01*
X936608Y918959D01*
X936566Y919292D01*
X936649Y919709D01*
X936858Y920001D01*
X937108Y920084D01*
X937358Y920042D01*
X937566Y919876D01*
X937983Y919042D01*
X938274Y918667D01*
X938691Y918417D01*
X939066Y918334D01*
Y920084D01*
G01X936983Y921517D02*
X936733Y921767D01*
X936608Y922059D01*
X936566Y922392D01*
X936649Y922809D01*
X936858Y923101D01*
X937108Y923184D01*
X937358Y923142D01*
X937566Y922976D01*
X937983Y922142D01*
X938274Y921767D01*
X938691Y921517D01*
X939066Y921434D01*
Y923184D01*
G01X925861Y957507D02*
X929861D01*
Y964907D01*
G01X934361D02*
X930361D01*
Y957507D01*
G01X922607Y964782D02*
X918607D01*
Y957382D01*
G01X898079Y956521D02*
X895579D01*
Y957562D01*
X895704Y957896D01*
X895871Y958104D01*
X896204Y958187D01*
X896537Y958104D01*
X896746Y957854D01*
X896871Y957562D01*
Y956521D01*
G01Y957562D02*
X898079Y958187D01*
G01Y960371D02*
X897537Y960454D01*
X897079Y960579D01*
X896662Y960746D01*
X896204Y960954D01*
X895579Y961287D01*
Y959621D01*
G01X897037Y962762D02*
X896746Y963054D01*
X896579Y963304D01*
X896496Y963637D01*
X896579Y963929D01*
X896746Y964137D01*
X896996Y964304D01*
X897287Y964346D01*
X897537Y964304D01*
X897787Y964137D01*
X897996Y963887D01*
X898079Y963596D01*
X897996Y963262D01*
X897746Y962971D01*
X897371Y962804D01*
X896954Y962762D01*
X896412Y962846D01*
X896121Y962971D01*
X895829Y963179D01*
X895621Y963471D01*
X895579Y963762D01*
X895662Y964054D01*
X895871Y964262D01*
G01X938861Y964907D02*
X934861D01*
Y957507D01*
G01X928100Y983900D02*
X924100D01*
Y976500D01*
G01X932600Y983900D02*
X928600D01*
Y976500D01*
G01X919600D02*
X923600D01*
Y983900D01*
G01X919100D02*
X915100D01*
Y976500D01*
G01X914500Y957400D02*
X918500D01*
Y964800D01*
G01X928460Y952445D02*
Y938445D01*
G01X941460Y952445D02*
X928460D01*
G01X941460Y938445D02*
Y952445D01*
G01X928460Y938445D02*
X941460D01*
G01X933008Y988095D02*
X932758Y988220D01*
X932466Y988303D01*
X932133D01*
X931758Y988178D01*
X931466Y987970D01*
X931258Y987720D01*
X931091Y987303D01*
X931049Y986928D01*
X931133Y986553D01*
X931258Y986303D01*
X931508Y986053D01*
X931799Y985886D01*
X932091Y985803D01*
X932383D01*
X932674Y985886D01*
X932924Y986011D01*
X933133Y986178D01*
G01X934483Y986095D02*
X934774Y985886D01*
X935108Y985803D01*
X935441Y985886D01*
X935733Y986136D01*
X935941Y986511D01*
X936024Y986886D01*
Y987345D01*
X935941Y987720D01*
X935733Y988053D01*
X935483Y988220D01*
X935191Y988303D01*
X934858Y988220D01*
X934608Y988053D01*
X934441Y987803D01*
X934358Y987470D01*
X934441Y987178D01*
X934649Y986886D01*
X934899Y986720D01*
X935191Y986678D01*
X935524Y986761D01*
X935774Y986970D01*
X936024Y987345D01*
G01X913140Y1026422D02*
X910640D01*
Y1027463D01*
X910765Y1027797D01*
X910932Y1028005D01*
X911265Y1028088D01*
X911598Y1028005D01*
X911807Y1027755D01*
X911932Y1027463D01*
Y1026422D01*
G01Y1027463D02*
X913140Y1028088D01*
G01X912640Y1029438D02*
X912932Y1029688D01*
X913098Y1030022D01*
X913140Y1030397D01*
X913098Y1030730D01*
X912890Y1031063D01*
X912640Y1031272D01*
X912390Y1031313D01*
X912098Y1031230D01*
X911890Y1030938D01*
X911807Y1030647D01*
Y1030272D01*
G01Y1030647D02*
X911682Y1030897D01*
X911473Y1031105D01*
X911223Y1031188D01*
X910973Y1031105D01*
X910765Y1030897D01*
X910640Y1030522D01*
X910682Y1030147D01*
X910848Y1029772D01*
G01X911057Y1032663D02*
X910807Y1032913D01*
X910682Y1033205D01*
X910640Y1033538D01*
X910723Y1033955D01*
X910932Y1034247D01*
X911182Y1034330D01*
X911432Y1034288D01*
X911640Y1034122D01*
X912057Y1033288D01*
X912348Y1032913D01*
X912765Y1032663D01*
X913140Y1032580D01*
Y1034330D01*
G01X931105Y1033960D02*
X927105D01*
Y1026560D01*
G01X909788Y1026647D02*
X907288D01*
Y1027688D01*
X907413Y1028022D01*
X907580Y1028230D01*
X907913Y1028313D01*
X908246Y1028230D01*
X908455Y1027980D01*
X908580Y1027688D01*
Y1026647D01*
G01Y1027688D02*
X909788Y1028313D01*
G01X909288Y1029663D02*
X909580Y1029913D01*
X909746Y1030247D01*
X909788Y1030622D01*
X909746Y1030955D01*
X909538Y1031288D01*
X909288Y1031497D01*
X909038Y1031538D01*
X908746Y1031455D01*
X908538Y1031163D01*
X908455Y1030872D01*
Y1030497D01*
G01Y1030872D02*
X908330Y1031122D01*
X908121Y1031330D01*
X907871Y1031413D01*
X907621Y1031330D01*
X907413Y1031122D01*
X907288Y1030747D01*
X907330Y1030372D01*
X907496Y1029997D01*
G01X909788Y1033597D02*
X909246Y1033680D01*
X908788Y1033805D01*
X908371Y1033972D01*
X907913Y1034180D01*
X907288Y1034513D01*
Y1032847D01*
G01X923053Y1026685D02*
X927053D01*
Y1034085D01*
G01X905614Y1026665D02*
X903114D01*
Y1027706D01*
X903239Y1028040D01*
X903406Y1028248D01*
X903739Y1028331D01*
X904072Y1028248D01*
X904281Y1027998D01*
X904406Y1027706D01*
Y1026665D01*
G01Y1027706D02*
X905614Y1028331D01*
G01X905114Y1029681D02*
X905406Y1029931D01*
X905572Y1030265D01*
X905614Y1030640D01*
X905572Y1030973D01*
X905364Y1031306D01*
X905114Y1031515D01*
X904864Y1031556D01*
X904572Y1031473D01*
X904364Y1031181D01*
X904281Y1030890D01*
Y1030515D01*
G01Y1030890D02*
X904156Y1031140D01*
X903947Y1031348D01*
X903697Y1031431D01*
X903447Y1031348D01*
X903239Y1031140D01*
X903114Y1030765D01*
X903156Y1030390D01*
X903322Y1030015D01*
G01X905614Y1033698D02*
X905572Y1033990D01*
X905447Y1034323D01*
X905239Y1034531D01*
X904947Y1034615D01*
X904656Y1034531D01*
X904406Y1034281D01*
X904281Y1033906D01*
Y1033490D01*
X904197Y1033240D01*
X903989Y1033031D01*
X903697Y1032948D01*
X903406Y1033073D01*
X903197Y1033365D01*
X903114Y1033698D01*
X903197Y1034031D01*
X903406Y1034323D01*
X903697Y1034448D01*
X903989Y1034365D01*
X904197Y1034156D01*
X904281Y1033906D01*
Y1033490D01*
X904406Y1033115D01*
X904656Y1032865D01*
X904947Y1032781D01*
X905239Y1032865D01*
X905447Y1033073D01*
X905572Y1033406D01*
X905614Y1033698D01*
G01X922879Y1034103D02*
X918879D01*
Y1026703D01*
G01X931313Y1030083D02*
Y1026083D01*
X938713D01*
G01X931224Y1034390D02*
Y1030390D01*
X938624D01*
G01X901504Y1026701D02*
X899004D01*
Y1027742D01*
X899129Y1028076D01*
X899296Y1028284D01*
X899629Y1028367D01*
X899962Y1028284D01*
X900171Y1028034D01*
X900296Y1027742D01*
Y1026701D01*
G01Y1027742D02*
X901504Y1028367D01*
G01X901004Y1029717D02*
X901296Y1029967D01*
X901462Y1030301D01*
X901504Y1030676D01*
X901462Y1031009D01*
X901254Y1031342D01*
X901004Y1031551D01*
X900754Y1031592D01*
X900462Y1031509D01*
X900254Y1031217D01*
X900171Y1030926D01*
Y1030551D01*
G01Y1030926D02*
X900046Y1031176D01*
X899837Y1031384D01*
X899587Y1031467D01*
X899337Y1031384D01*
X899129Y1031176D01*
X899004Y1030801D01*
X899046Y1030426D01*
X899212Y1030051D01*
G01X901004Y1032817D02*
X901296Y1033067D01*
X901462Y1033401D01*
X901504Y1033776D01*
X901462Y1034109D01*
X901254Y1034442D01*
X901004Y1034651D01*
X900754Y1034692D01*
X900462Y1034609D01*
X900254Y1034317D01*
X900171Y1034026D01*
Y1033651D01*
G01Y1034026D02*
X900046Y1034276D01*
X899837Y1034484D01*
X899587Y1034567D01*
X899337Y1034484D01*
X899129Y1034276D01*
X899004Y1033901D01*
X899046Y1033526D01*
X899212Y1033151D01*
G01X914769Y1026739D02*
X918769D01*
Y1034139D01*
G01X929650Y1018000D02*
Y997000D01*
X898000D01*
Y1008000D01*
X929650D01*
G01Y999350D02*
X926500Y1002500D01*
X929650Y1005650D01*
G01X937208Y1017817D02*
X937083Y1017567D01*
X937000Y1017275D01*
Y1016942D01*
X937125Y1016567D01*
X937333Y1016275D01*
X937583Y1016067D01*
X938000Y1015900D01*
X938375Y1015858D01*
X938750Y1015942D01*
X939000Y1016067D01*
X939250Y1016317D01*
X939417Y1016608D01*
X939500Y1016900D01*
Y1017192D01*
X939417Y1017483D01*
X939292Y1017733D01*
X939125Y1017942D01*
G01X939500Y1020000D02*
X937000D01*
X937500Y1019500D01*
G01X939500D02*
Y1020500D01*
G01X939000Y1022183D02*
X939292Y1022433D01*
X939458Y1022767D01*
X939500Y1023142D01*
X939458Y1023475D01*
X939250Y1023808D01*
X939000Y1024017D01*
X938750Y1024058D01*
X938458Y1023975D01*
X938250Y1023683D01*
X938167Y1023392D01*
Y1023017D01*
G01Y1023392D02*
X938042Y1023642D01*
X937833Y1023850D01*
X937583Y1023933D01*
X937333Y1023850D01*
X937125Y1023642D01*
X937000Y1023267D01*
X937042Y1022892D01*
X937208Y1022517D01*
G01X941208Y1017817D02*
X941083Y1017567D01*
X941000Y1017275D01*
Y1016942D01*
X941125Y1016567D01*
X941333Y1016275D01*
X941583Y1016067D01*
X942000Y1015900D01*
X942375Y1015858D01*
X942750Y1015942D01*
X943000Y1016067D01*
X943250Y1016317D01*
X943417Y1016608D01*
X943500Y1016900D01*
Y1017192D01*
X943417Y1017483D01*
X943292Y1017733D01*
X943125Y1017942D01*
G01X943500Y1020000D02*
X941000D01*
X941500Y1019500D01*
G01X943500D02*
Y1020500D01*
G01Y1023600D02*
X941000D01*
X942792Y1022058D01*
Y1024142D01*
G01X932981Y1001438D02*
X932731Y1001563D01*
X932439Y1001646D01*
X932106D01*
X931731Y1001521D01*
X931439Y1001313D01*
X931231Y1001063D01*
X931064Y1000646D01*
X931022Y1000271D01*
X931106Y999896D01*
X931231Y999646D01*
X931481Y999396D01*
X931772Y999229D01*
X932064Y999146D01*
X932356D01*
X932647Y999229D01*
X932897Y999354D01*
X933106Y999521D01*
G01X935164Y999146D02*
Y1001646D01*
X934664Y1001146D01*
G01Y999146D02*
X935664D01*
G01X938264Y1001646D02*
X937931Y1001563D01*
X937681Y1001354D01*
X937514Y1001104D01*
X937389Y1000771D01*
X937347Y1000396D01*
X937389Y1000021D01*
X937514Y999688D01*
X937681Y999438D01*
X937931Y999229D01*
X938264Y999146D01*
X938597Y999229D01*
X938847Y999438D01*
X939014Y999688D01*
X939139Y1000021D01*
X939181Y1000396D01*
X939139Y1000771D01*
X939014Y1001104D01*
X938847Y1001354D01*
X938597Y1001563D01*
X938264Y1001646D01*
G01X931437Y1037851D02*
Y1040351D01*
X932478D01*
X932812Y1040226D01*
X933020Y1040059D01*
X933103Y1039726D01*
X933020Y1039393D01*
X932770Y1039184D01*
X932478Y1039059D01*
X931437D01*
G01X932478D02*
X933103Y1037851D01*
G01X935870D02*
Y1040351D01*
X934328Y1038559D01*
X936412D01*
G01X938470Y1040351D02*
X938137Y1040268D01*
X937887Y1040059D01*
X937720Y1039809D01*
X937595Y1039476D01*
X937553Y1039101D01*
X937595Y1038726D01*
X937720Y1038393D01*
X937887Y1038143D01*
X938137Y1037934D01*
X938470Y1037851D01*
X938803Y1037934D01*
X939053Y1038143D01*
X939220Y1038393D01*
X939345Y1038726D01*
X939387Y1039101D01*
X939345Y1039476D01*
X939220Y1039809D01*
X939053Y1040059D01*
X938803Y1040268D01*
X938470Y1040351D01*
G01X931752Y1041710D02*
Y1044210D01*
X932793D01*
X933127Y1044085D01*
X933335Y1043918D01*
X933418Y1043585D01*
X933335Y1043252D01*
X933085Y1043043D01*
X932793Y1042918D01*
X931752D01*
G01X932793D02*
X933418Y1041710D01*
G01X936185D02*
Y1044210D01*
X934643Y1042418D01*
X936727D01*
G01X937993Y1043793D02*
X938243Y1044043D01*
X938535Y1044168D01*
X938868Y1044210D01*
X939285Y1044127D01*
X939577Y1043918D01*
X939660Y1043668D01*
X939618Y1043418D01*
X939452Y1043210D01*
X938618Y1042793D01*
X938243Y1042502D01*
X937993Y1042085D01*
X937910Y1041710D01*
X939660D01*
G01X942385D02*
Y1044210D01*
X940843Y1042418D01*
X942927D01*
G01X934559Y1368984D02*
X930559D01*
Y1361584D01*
G01X934959Y1361590D02*
X938959D01*
Y1368990D01*
G01X930294Y1371148D02*
X934294D01*
Y1378548D01*
G01X938994D02*
X934994D01*
Y1371148D01*
G01X918298Y1341769D02*
X915798D01*
Y1342810D01*
X915923Y1343144D01*
X916090Y1343352D01*
X916423Y1343435D01*
X916756Y1343352D01*
X916965Y1343102D01*
X917090Y1342810D01*
Y1341769D01*
G01Y1342810D02*
X918298Y1343435D01*
G01Y1345702D02*
X915798D01*
X916298Y1345202D01*
G01X918298D02*
Y1346202D01*
G01Y1348802D02*
X918256Y1349094D01*
X918131Y1349427D01*
X917923Y1349635D01*
X917631Y1349719D01*
X917340Y1349635D01*
X917090Y1349385D01*
X916965Y1349010D01*
Y1348594D01*
X916881Y1348344D01*
X916673Y1348135D01*
X916381Y1348052D01*
X916090Y1348177D01*
X915881Y1348469D01*
X915798Y1348802D01*
X915881Y1349135D01*
X916090Y1349427D01*
X916381Y1349552D01*
X916673Y1349469D01*
X916881Y1349260D01*
X916965Y1349010D01*
Y1348594D01*
X917090Y1348219D01*
X917340Y1347969D01*
X917631Y1347885D01*
X917923Y1347969D01*
X918131Y1348177D01*
X918256Y1348510D01*
X918298Y1348802D01*
G01X917923Y1350985D02*
X918131Y1351235D01*
X918256Y1351527D01*
X918298Y1351902D01*
X918215Y1352277D01*
X918048Y1352569D01*
X917756Y1352777D01*
X917423Y1352819D01*
X917090Y1352735D01*
X916881Y1352527D01*
X916715Y1352235D01*
X916673Y1351944D01*
X916715Y1351652D01*
X916881Y1351277D01*
X915798Y1351402D01*
Y1352527D01*
G01X934564Y1355312D02*
X930564D01*
Y1347912D01*
G01X921998Y1341769D02*
X919498D01*
Y1342810D01*
X919623Y1343144D01*
X919790Y1343352D01*
X920123Y1343435D01*
X920456Y1343352D01*
X920665Y1343102D01*
X920790Y1342810D01*
Y1341769D01*
G01Y1342810D02*
X921998Y1343435D01*
G01Y1345702D02*
X919498D01*
X919998Y1345202D01*
G01X921998D02*
Y1346202D01*
G01Y1348802D02*
X921956Y1349094D01*
X921831Y1349427D01*
X921623Y1349635D01*
X921331Y1349719D01*
X921040Y1349635D01*
X920790Y1349385D01*
X920665Y1349010D01*
Y1348594D01*
X920581Y1348344D01*
X920373Y1348135D01*
X920081Y1348052D01*
X919790Y1348177D01*
X919581Y1348469D01*
X919498Y1348802D01*
X919581Y1349135D01*
X919790Y1349427D01*
X920081Y1349552D01*
X920373Y1349469D01*
X920581Y1349260D01*
X920665Y1349010D01*
Y1348594D01*
X920790Y1348219D01*
X921040Y1347969D01*
X921331Y1347885D01*
X921623Y1347969D01*
X921831Y1348177D01*
X921956Y1348510D01*
X921998Y1348802D01*
G01X920956Y1351110D02*
X920665Y1351402D01*
X920498Y1351652D01*
X920415Y1351985D01*
X920498Y1352277D01*
X920665Y1352485D01*
X920915Y1352652D01*
X921206Y1352694D01*
X921456Y1352652D01*
X921706Y1352485D01*
X921915Y1352235D01*
X921998Y1351944D01*
X921915Y1351610D01*
X921665Y1351319D01*
X921290Y1351152D01*
X920873Y1351110D01*
X920331Y1351194D01*
X920040Y1351319D01*
X919748Y1351527D01*
X919540Y1351819D01*
X919498Y1352110D01*
X919581Y1352402D01*
X919790Y1352610D01*
G01X934964Y1347912D02*
X938964D01*
Y1355312D01*
G01X899776Y1356483D02*
Y1377283D01*
G01X913776Y1356483D02*
X899776D01*
G01X913776Y1377983D02*
Y1356483D01*
G01X912306Y1343519D02*
X912181Y1343269D01*
X912098Y1342977D01*
Y1342644D01*
X912223Y1342269D01*
X912431Y1341977D01*
X912681Y1341769D01*
X913098Y1341602D01*
X913473Y1341560D01*
X913848Y1341644D01*
X914098Y1341769D01*
X914348Y1342019D01*
X914515Y1342310D01*
X914598Y1342602D01*
Y1342894D01*
X914515Y1343185D01*
X914390Y1343435D01*
X914223Y1343644D01*
G01X913556Y1344910D02*
X913265Y1345202D01*
X913098Y1345452D01*
X913015Y1345785D01*
X913098Y1346077D01*
X913265Y1346285D01*
X913515Y1346452D01*
X913806Y1346494D01*
X914056Y1346452D01*
X914306Y1346285D01*
X914515Y1346035D01*
X914598Y1345744D01*
X914515Y1345410D01*
X914265Y1345119D01*
X913890Y1344952D01*
X913473Y1344910D01*
X912931Y1344994D01*
X912640Y1345119D01*
X912348Y1345327D01*
X912140Y1345619D01*
X912098Y1345910D01*
X912181Y1346202D01*
X912390Y1346410D01*
G01X914098Y1347885D02*
X914390Y1348135D01*
X914556Y1348469D01*
X914598Y1348844D01*
X914556Y1349177D01*
X914348Y1349510D01*
X914098Y1349719D01*
X913848Y1349760D01*
X913556Y1349677D01*
X913348Y1349385D01*
X913265Y1349094D01*
Y1348719D01*
G01Y1349094D02*
X913140Y1349344D01*
X912931Y1349552D01*
X912681Y1349635D01*
X912431Y1349552D01*
X912223Y1349344D01*
X912098Y1348969D01*
X912140Y1348594D01*
X912306Y1348219D01*
G01X932310Y1385233D02*
X929810D01*
Y1386274D01*
X929935Y1386608D01*
X930102Y1386816D01*
X930435Y1386899D01*
X930768Y1386816D01*
X930977Y1386566D01*
X931102Y1386274D01*
Y1385233D01*
G01Y1386274D02*
X932310Y1386899D01*
G01X930227Y1388374D02*
X929977Y1388624D01*
X929852Y1388916D01*
X929810Y1389249D01*
X929893Y1389666D01*
X930102Y1389958D01*
X930352Y1390041D01*
X930602Y1389999D01*
X930810Y1389833D01*
X931227Y1388999D01*
X931518Y1388624D01*
X931935Y1388374D01*
X932310Y1388291D01*
Y1390041D01*
G01X929810Y1392266D02*
X929893Y1391933D01*
X930102Y1391683D01*
X930352Y1391516D01*
X930685Y1391391D01*
X931060Y1391349D01*
X931435Y1391391D01*
X931768Y1391516D01*
X932018Y1391683D01*
X932227Y1391933D01*
X932310Y1392266D01*
X932227Y1392599D01*
X932018Y1392849D01*
X931768Y1393016D01*
X931435Y1393141D01*
X931060Y1393183D01*
X930685Y1393141D01*
X930352Y1393016D01*
X930102Y1392849D01*
X929893Y1392599D01*
X929810Y1392266D01*
G01X937010Y1385233D02*
X934510D01*
Y1386274D01*
X934635Y1386608D01*
X934802Y1386816D01*
X935135Y1386899D01*
X935468Y1386816D01*
X935677Y1386566D01*
X935802Y1386274D01*
Y1385233D01*
G01Y1386274D02*
X937010Y1386899D01*
G01X934927Y1388374D02*
X934677Y1388624D01*
X934552Y1388916D01*
X934510Y1389249D01*
X934593Y1389666D01*
X934802Y1389958D01*
X935052Y1390041D01*
X935302Y1389999D01*
X935510Y1389833D01*
X935927Y1388999D01*
X936218Y1388624D01*
X936635Y1388374D01*
X937010Y1388291D01*
Y1390041D01*
G01Y1392183D02*
X936468Y1392266D01*
X936010Y1392391D01*
X935593Y1392558D01*
X935135Y1392766D01*
X934510Y1393099D01*
Y1391433D01*
G01X902288Y1384518D02*
Y1382726D01*
X902455Y1382351D01*
X902788Y1382101D01*
X903205Y1382018D01*
X903622Y1382101D01*
X903955Y1382351D01*
X904122Y1382726D01*
Y1384518D01*
G01X905388Y1382518D02*
X905638Y1382226D01*
X905972Y1382060D01*
X906347Y1382018D01*
X906680Y1382060D01*
X907013Y1382268D01*
X907222Y1382518D01*
X907263Y1382768D01*
X907180Y1383060D01*
X906888Y1383268D01*
X906597Y1383351D01*
X906222D01*
G01X906597D02*
X906847Y1383476D01*
X907055Y1383685D01*
X907138Y1383935D01*
X907055Y1384185D01*
X906847Y1384393D01*
X906472Y1384518D01*
X906097Y1384476D01*
X905722Y1384310D01*
G01X906776Y1375783D02*
X904576Y1377983D01*
G01X906776Y1375783D02*
X908976Y1377983D01*
G01X913776D02*
X899776D01*
G01X925918Y1388533D02*
X925793Y1388283D01*
X925710Y1387991D01*
Y1387658D01*
X925835Y1387283D01*
X926043Y1386991D01*
X926293Y1386783D01*
X926710Y1386616D01*
X927085Y1386574D01*
X927460Y1386658D01*
X927710Y1386783D01*
X927960Y1387033D01*
X928127Y1387324D01*
X928210Y1387616D01*
Y1387908D01*
X928127Y1388199D01*
X928002Y1388449D01*
X927835Y1388658D01*
G01X928210Y1390716D02*
X928168Y1391008D01*
X928043Y1391341D01*
X927835Y1391549D01*
X927543Y1391633D01*
X927252Y1391549D01*
X927002Y1391299D01*
X926877Y1390924D01*
Y1390508D01*
X926793Y1390258D01*
X926585Y1390049D01*
X926293Y1389966D01*
X926002Y1390091D01*
X925793Y1390383D01*
X925710Y1390716D01*
X925793Y1391049D01*
X926002Y1391341D01*
X926293Y1391466D01*
X926585Y1391383D01*
X926793Y1391174D01*
X926877Y1390924D01*
Y1390508D01*
X927002Y1390133D01*
X927252Y1389883D01*
X927543Y1389799D01*
X927835Y1389883D01*
X928043Y1390091D01*
X928168Y1390424D01*
X928210Y1390716D01*
G01X941400Y1385514D02*
X941275Y1385264D01*
X941192Y1384972D01*
Y1384639D01*
X941317Y1384264D01*
X941525Y1383972D01*
X941775Y1383764D01*
X942192Y1383597D01*
X942567Y1383555D01*
X942942Y1383639D01*
X943192Y1383764D01*
X943442Y1384014D01*
X943609Y1384305D01*
X943692Y1384597D01*
Y1384889D01*
X943609Y1385180D01*
X943484Y1385430D01*
X943317Y1385639D01*
G01X943692Y1387614D02*
X943150Y1387697D01*
X942692Y1387822D01*
X942275Y1387989D01*
X941817Y1388197D01*
X941192Y1388530D01*
Y1386864D01*
G01X897058Y1432148D02*
X894558D01*
Y1433189D01*
X894683Y1433523D01*
X894850Y1433731D01*
X895183Y1433814D01*
X895516Y1433731D01*
X895725Y1433481D01*
X895850Y1433189D01*
Y1432148D01*
G01Y1433189D02*
X897058Y1433814D01*
G01Y1436081D02*
X894558D01*
X895058Y1435581D01*
G01X897058D02*
Y1436581D01*
G01Y1439098D02*
X896516Y1439181D01*
X896058Y1439306D01*
X895641Y1439473D01*
X895183Y1439681D01*
X894558Y1440014D01*
Y1438348D01*
G01X897058Y1442281D02*
X894558D01*
X895058Y1441781D01*
G01X897058D02*
Y1442781D01*
G01X901558Y1432148D02*
X899058D01*
Y1433189D01*
X899183Y1433523D01*
X899350Y1433731D01*
X899683Y1433814D01*
X900016Y1433731D01*
X900225Y1433481D01*
X900350Y1433189D01*
Y1432148D01*
G01Y1433189D02*
X901558Y1433814D01*
G01Y1436081D02*
X899058D01*
X899558Y1435581D01*
G01X901558D02*
Y1436581D01*
G01X901266Y1438473D02*
X901475Y1438764D01*
X901558Y1439098D01*
X901475Y1439431D01*
X901225Y1439723D01*
X900850Y1439931D01*
X900475Y1440014D01*
X900016D01*
X899641Y1439931D01*
X899308Y1439723D01*
X899141Y1439473D01*
X899058Y1439181D01*
X899141Y1438848D01*
X899308Y1438598D01*
X899558Y1438431D01*
X899891Y1438348D01*
X900183Y1438431D01*
X900475Y1438639D01*
X900641Y1438889D01*
X900683Y1439181D01*
X900600Y1439514D01*
X900391Y1439764D01*
X900016Y1440014D01*
G01X901558Y1442781D02*
X899058D01*
X900850Y1441239D01*
Y1443323D01*
G01X894967Y1502500D02*
Y1505000D01*
X896008D01*
X896342Y1504875D01*
X896550Y1504708D01*
X896633Y1504375D01*
X896550Y1504042D01*
X896300Y1503833D01*
X896008Y1503708D01*
X894967D01*
G01X896008D02*
X896633Y1502500D01*
G01X898900D02*
Y1505000D01*
X898400Y1504500D01*
G01Y1502500D02*
X899400D01*
G01X902000D02*
Y1505000D01*
X901500Y1504500D01*
G01Y1502500D02*
X902500D01*
G01X905600D02*
Y1505000D01*
X904058Y1503208D01*
X906142D01*
G01X907283Y1502875D02*
X907533Y1502667D01*
X907825Y1502542D01*
X908200Y1502500D01*
X908575Y1502583D01*
X908867Y1502750D01*
X909075Y1503042D01*
X909117Y1503375D01*
X909033Y1503708D01*
X908825Y1503917D01*
X908533Y1504083D01*
X908242Y1504125D01*
X907950Y1504083D01*
X907575Y1503917D01*
X907700Y1505000D01*
X908825D01*
G01X912300Y1510600D02*
Y1514600D01*
X904900D01*
G01X927500Y1478667D02*
X925000D01*
Y1479708D01*
X925125Y1480042D01*
X925292Y1480250D01*
X925625Y1480333D01*
X925958Y1480250D01*
X926167Y1480000D01*
X926292Y1479708D01*
Y1478667D01*
G01Y1479708D02*
X927500Y1480333D01*
G01Y1482600D02*
X925000D01*
X925500Y1482100D01*
G01X927500D02*
Y1483100D01*
G01Y1485700D02*
X925000D01*
X925500Y1485200D01*
G01X927500D02*
Y1486200D01*
G01X927125Y1487883D02*
X927333Y1488133D01*
X927458Y1488425D01*
X927500Y1488800D01*
X927417Y1489175D01*
X927250Y1489467D01*
X926958Y1489675D01*
X926625Y1489717D01*
X926292Y1489633D01*
X926083Y1489425D01*
X925917Y1489133D01*
X925875Y1488842D01*
X925917Y1488550D01*
X926083Y1488175D01*
X925000Y1488300D01*
Y1489425D01*
G01X927208Y1491192D02*
X927417Y1491483D01*
X927500Y1491817D01*
X927417Y1492150D01*
X927167Y1492442D01*
X926792Y1492650D01*
X926417Y1492733D01*
X925958D01*
X925583Y1492650D01*
X925250Y1492442D01*
X925083Y1492192D01*
X925000Y1491900D01*
X925083Y1491567D01*
X925250Y1491317D01*
X925500Y1491150D01*
X925833Y1491067D01*
X926125Y1491150D01*
X926417Y1491358D01*
X926583Y1491608D01*
X926625Y1491900D01*
X926542Y1492233D01*
X926333Y1492483D01*
X925958Y1492733D01*
G01X928500Y1508400D02*
X924500D01*
Y1501000D01*
G01X923500Y1478667D02*
X921000D01*
Y1479708D01*
X921125Y1480042D01*
X921292Y1480250D01*
X921625Y1480333D01*
X921958Y1480250D01*
X922167Y1480000D01*
X922292Y1479708D01*
Y1478667D01*
G01Y1479708D02*
X923500Y1480333D01*
G01Y1482600D02*
X921000D01*
X921500Y1482100D01*
G01X923500D02*
Y1483100D01*
G01Y1485700D02*
X921000D01*
X921500Y1485200D01*
G01X923500D02*
Y1486200D01*
G01X923125Y1487883D02*
X923333Y1488133D01*
X923458Y1488425D01*
X923500Y1488800D01*
X923417Y1489175D01*
X923250Y1489467D01*
X922958Y1489675D01*
X922625Y1489717D01*
X922292Y1489633D01*
X922083Y1489425D01*
X921917Y1489133D01*
X921875Y1488842D01*
X921917Y1488550D01*
X922083Y1488175D01*
X921000Y1488300D01*
Y1489425D01*
G01X923000Y1490983D02*
X923292Y1491233D01*
X923458Y1491567D01*
X923500Y1491942D01*
X923458Y1492275D01*
X923250Y1492608D01*
X923000Y1492817D01*
X922750Y1492858D01*
X922458Y1492775D01*
X922250Y1492483D01*
X922167Y1492192D01*
Y1491817D01*
G01Y1492192D02*
X922042Y1492442D01*
X921833Y1492650D01*
X921583Y1492733D01*
X921333Y1492650D01*
X921125Y1492442D01*
X921000Y1492067D01*
X921042Y1491692D01*
X921208Y1491317D01*
G01X920500Y1501000D02*
X924500D01*
Y1508400D01*
G01X919500Y1478667D02*
X917000D01*
Y1479708D01*
X917125Y1480042D01*
X917292Y1480250D01*
X917625Y1480333D01*
X917958Y1480250D01*
X918167Y1480000D01*
X918292Y1479708D01*
Y1478667D01*
G01Y1479708D02*
X919500Y1480333D01*
G01Y1482600D02*
X917000D01*
X917500Y1482100D01*
G01X919500D02*
Y1483100D01*
G01Y1485700D02*
X917000D01*
X917500Y1485200D01*
G01X919500D02*
Y1486200D01*
G01Y1489300D02*
X917000D01*
X918792Y1487758D01*
Y1489842D01*
G01X919500Y1491817D02*
X918958Y1491900D01*
X918500Y1492025D01*
X918083Y1492192D01*
X917625Y1492400D01*
X917000Y1492733D01*
Y1491067D01*
G01X916500Y1501000D02*
X920500D01*
Y1508400D01*
G01X894967Y1498500D02*
Y1501000D01*
X896008D01*
X896342Y1500875D01*
X896550Y1500708D01*
X896633Y1500375D01*
X896550Y1500042D01*
X896300Y1499833D01*
X896008Y1499708D01*
X894967D01*
G01X896008D02*
X896633Y1498500D01*
G01X898900D02*
Y1501000D01*
X898400Y1500500D01*
G01Y1498500D02*
X899400D01*
G01X902000D02*
Y1501000D01*
X901500Y1500500D01*
G01Y1498500D02*
X902500D01*
G01X905600D02*
Y1501000D01*
X904058Y1499208D01*
X906142D01*
G01X908700Y1498500D02*
Y1501000D01*
X907158Y1499208D01*
X909242D01*
G01X912300Y1506100D02*
Y1510100D01*
X904900D01*
G01X941834Y1478467D02*
X939334D01*
Y1479508D01*
X939459Y1479842D01*
X939626Y1480050D01*
X939959Y1480133D01*
X940292Y1480050D01*
X940501Y1479800D01*
X940626Y1479508D01*
Y1478467D01*
G01Y1479508D02*
X941834Y1480133D01*
G01Y1482400D02*
X939334D01*
X939834Y1481900D01*
G01X941834D02*
Y1482900D01*
G01Y1485500D02*
X939334D01*
X939834Y1485000D01*
G01X941834D02*
Y1486000D01*
G01Y1488517D02*
X941292Y1488600D01*
X940834Y1488725D01*
X940417Y1488892D01*
X939959Y1489100D01*
X939334Y1489433D01*
Y1487767D01*
G01X940792Y1490908D02*
X940501Y1491200D01*
X940334Y1491450D01*
X940251Y1491783D01*
X940334Y1492075D01*
X940501Y1492283D01*
X940751Y1492450D01*
X941042Y1492492D01*
X941292Y1492450D01*
X941542Y1492283D01*
X941751Y1492033D01*
X941834Y1491742D01*
X941751Y1491408D01*
X941501Y1491117D01*
X941126Y1490950D01*
X940709Y1490908D01*
X940167Y1490992D01*
X939876Y1491117D01*
X939584Y1491325D01*
X939376Y1491617D01*
X939334Y1491908D01*
X939417Y1492200D01*
X939626Y1492408D01*
G01X944000Y1508400D02*
X940000D01*
Y1501000D01*
G01X894983Y1509667D02*
Y1507875D01*
X895150Y1507500D01*
X895483Y1507250D01*
X895900Y1507167D01*
X896317Y1507250D01*
X896650Y1507500D01*
X896817Y1507875D01*
Y1509667D01*
G01X898083Y1507667D02*
X898333Y1507375D01*
X898667Y1507209D01*
X899042Y1507167D01*
X899375Y1507209D01*
X899708Y1507417D01*
X899917Y1507667D01*
X899958Y1507917D01*
X899875Y1508209D01*
X899583Y1508417D01*
X899292Y1508500D01*
X898917D01*
G01X899292D02*
X899542Y1508625D01*
X899750Y1508834D01*
X899833Y1509084D01*
X899750Y1509334D01*
X899542Y1509542D01*
X899167Y1509667D01*
X898792Y1509625D01*
X898417Y1509459D01*
G01X901308Y1508209D02*
X901600Y1508500D01*
X901850Y1508667D01*
X902183Y1508750D01*
X902475Y1508667D01*
X902683Y1508500D01*
X902850Y1508250D01*
X902892Y1507959D01*
X902850Y1507709D01*
X902683Y1507459D01*
X902433Y1507250D01*
X902142Y1507167D01*
X901808Y1507250D01*
X901517Y1507500D01*
X901350Y1507875D01*
X901308Y1508292D01*
X901392Y1508834D01*
X901517Y1509125D01*
X901725Y1509417D01*
X902017Y1509625D01*
X902308Y1509667D01*
X902600Y1509584D01*
X902808Y1509375D01*
G01X917900Y1517500D02*
X904500D01*
G01X917900Y1527500D02*
Y1517500D01*
G01X904500D02*
Y1527500D01*
G01X919500Y1512983D02*
X921292D01*
X921667Y1513150D01*
X921917Y1513483D01*
X922000Y1513900D01*
X921917Y1514317D01*
X921667Y1514650D01*
X921292Y1514817D01*
X919500D01*
G01X919917Y1516208D02*
X919667Y1516458D01*
X919542Y1516750D01*
X919500Y1517083D01*
X919583Y1517500D01*
X919792Y1517792D01*
X920042Y1517875D01*
X920292Y1517833D01*
X920500Y1517667D01*
X920917Y1516833D01*
X921208Y1516458D01*
X921625Y1516208D01*
X922000Y1516125D01*
Y1517875D01*
G01X920958Y1519308D02*
X920667Y1519600D01*
X920500Y1519850D01*
X920417Y1520183D01*
X920500Y1520475D01*
X920667Y1520683D01*
X920917Y1520850D01*
X921208Y1520892D01*
X921458Y1520850D01*
X921708Y1520683D01*
X921917Y1520433D01*
X922000Y1520142D01*
X921917Y1519808D01*
X921667Y1519517D01*
X921292Y1519350D01*
X920875Y1519308D01*
X920333Y1519392D01*
X920042Y1519517D01*
X919750Y1519725D01*
X919542Y1520017D01*
X919500Y1520308D01*
X919583Y1520600D01*
X919792Y1520808D01*
G01X939013Y1513250D02*
Y1516250D01*
G01X926150Y1520350D02*
Y1515350D01*
X931150D01*
G01X930542Y1480267D02*
X930417Y1480017D01*
X930334Y1479725D01*
Y1479392D01*
X930459Y1479017D01*
X930667Y1478725D01*
X930917Y1478517D01*
X931334Y1478350D01*
X931709Y1478308D01*
X932084Y1478392D01*
X932334Y1478517D01*
X932584Y1478767D01*
X932751Y1479058D01*
X932834Y1479350D01*
Y1479642D01*
X932751Y1479933D01*
X932626Y1480183D01*
X932459Y1480392D01*
G01Y1481533D02*
X932667Y1481783D01*
X932792Y1482075D01*
X932834Y1482450D01*
X932751Y1482825D01*
X932584Y1483117D01*
X932292Y1483325D01*
X931959Y1483367D01*
X931626Y1483283D01*
X931417Y1483075D01*
X931251Y1482783D01*
X931209Y1482492D01*
X931251Y1482200D01*
X931417Y1481825D01*
X930334Y1481950D01*
Y1483075D01*
G01X932834Y1485550D02*
X932792Y1485842D01*
X932667Y1486175D01*
X932459Y1486383D01*
X932167Y1486467D01*
X931876Y1486383D01*
X931626Y1486133D01*
X931501Y1485758D01*
Y1485342D01*
X931417Y1485092D01*
X931209Y1484883D01*
X930917Y1484800D01*
X930626Y1484925D01*
X930417Y1485217D01*
X930334Y1485550D01*
X930417Y1485883D01*
X930626Y1486175D01*
X930917Y1486300D01*
X931209Y1486217D01*
X931417Y1486008D01*
X931501Y1485758D01*
Y1485342D01*
X931626Y1484967D01*
X931876Y1484717D01*
X932167Y1484633D01*
X932459Y1484717D01*
X932667Y1484925D01*
X932792Y1485258D01*
X932834Y1485550D01*
G01Y1488650D02*
X932792Y1488942D01*
X932667Y1489275D01*
X932459Y1489483D01*
X932167Y1489567D01*
X931876Y1489483D01*
X931626Y1489233D01*
X931501Y1488858D01*
Y1488442D01*
X931417Y1488192D01*
X931209Y1487983D01*
X930917Y1487900D01*
X930626Y1488025D01*
X930417Y1488317D01*
X930334Y1488650D01*
X930417Y1488983D01*
X930626Y1489275D01*
X930917Y1489400D01*
X931209Y1489317D01*
X931417Y1489108D01*
X931501Y1488858D01*
Y1488442D01*
X931626Y1488067D01*
X931876Y1487817D01*
X932167Y1487733D01*
X932459Y1487817D01*
X932667Y1488025D01*
X932792Y1488358D01*
X932834Y1488650D01*
G01X935042Y1480267D02*
X934917Y1480017D01*
X934834Y1479725D01*
Y1479392D01*
X934959Y1479017D01*
X935167Y1478725D01*
X935417Y1478517D01*
X935834Y1478350D01*
X936209Y1478308D01*
X936584Y1478392D01*
X936834Y1478517D01*
X937084Y1478767D01*
X937251Y1479058D01*
X937334Y1479350D01*
Y1479642D01*
X937251Y1479933D01*
X937126Y1480183D01*
X936959Y1480392D01*
G01Y1481533D02*
X937167Y1481783D01*
X937292Y1482075D01*
X937334Y1482450D01*
X937251Y1482825D01*
X937084Y1483117D01*
X936792Y1483325D01*
X936459Y1483367D01*
X936126Y1483283D01*
X935917Y1483075D01*
X935751Y1482783D01*
X935709Y1482492D01*
X935751Y1482200D01*
X935917Y1481825D01*
X934834Y1481950D01*
Y1483075D01*
G01X937334Y1485550D02*
X937292Y1485842D01*
X937167Y1486175D01*
X936959Y1486383D01*
X936667Y1486467D01*
X936376Y1486383D01*
X936126Y1486133D01*
X936001Y1485758D01*
Y1485342D01*
X935917Y1485092D01*
X935709Y1484883D01*
X935417Y1484800D01*
X935126Y1484925D01*
X934917Y1485217D01*
X934834Y1485550D01*
X934917Y1485883D01*
X935126Y1486175D01*
X935417Y1486300D01*
X935709Y1486217D01*
X935917Y1486008D01*
X936001Y1485758D01*
Y1485342D01*
X936126Y1484967D01*
X936376Y1484717D01*
X936667Y1484633D01*
X936959Y1484717D01*
X937167Y1484925D01*
X937292Y1485258D01*
X937334Y1485550D01*
G01X936292Y1487858D02*
X936001Y1488150D01*
X935834Y1488400D01*
X935751Y1488733D01*
X935834Y1489025D01*
X936001Y1489233D01*
X936251Y1489400D01*
X936542Y1489442D01*
X936792Y1489400D01*
X937042Y1489233D01*
X937251Y1488983D01*
X937334Y1488692D01*
X937251Y1488358D01*
X937001Y1488067D01*
X936626Y1487900D01*
X936209Y1487858D01*
X935667Y1487942D01*
X935376Y1488067D01*
X935084Y1488275D01*
X934876Y1488567D01*
X934834Y1488858D01*
X934917Y1489150D01*
X935126Y1489358D01*
G01X939000Y1555000D02*
X943000D01*
Y1562400D01*
G01X929901Y1566577D02*
Y1569077D01*
X930942D01*
X931276Y1568952D01*
X931484Y1568785D01*
X931567Y1568452D01*
X931484Y1568119D01*
X931234Y1567910D01*
X930942Y1567785D01*
X929901D01*
G01X930942D02*
X931567Y1566577D01*
G01X933834D02*
Y1569077D01*
X933334Y1568577D01*
G01Y1566577D02*
X934334D01*
G01X936934D02*
Y1569077D01*
X936434Y1568577D01*
G01Y1566577D02*
X937434D01*
G01X939242Y1567619D02*
X939534Y1567910D01*
X939784Y1568077D01*
X940117Y1568160D01*
X940409Y1568077D01*
X940617Y1567910D01*
X940784Y1567660D01*
X940826Y1567369D01*
X940784Y1567119D01*
X940617Y1566869D01*
X940367Y1566660D01*
X940076Y1566577D01*
X939742Y1566660D01*
X939451Y1566910D01*
X939284Y1567285D01*
X939242Y1567702D01*
X939326Y1568244D01*
X939451Y1568535D01*
X939659Y1568827D01*
X939951Y1569035D01*
X940242Y1569077D01*
X940534Y1568994D01*
X940742Y1568785D01*
G01X943634Y1566577D02*
Y1569077D01*
X942092Y1567285D01*
X944176D01*
G01X942700Y1550700D02*
Y1554700D01*
X935300D01*
G01X908107Y1559729D02*
Y1562229D01*
X909148D01*
X909482Y1562104D01*
X909690Y1561937D01*
X909773Y1561604D01*
X909690Y1561271D01*
X909440Y1561062D01*
X909148Y1560937D01*
X908107D01*
G01X909148D02*
X909773Y1559729D01*
G01X912040D02*
Y1562229D01*
X911540Y1561729D01*
G01Y1559729D02*
X912540D01*
G01X915140D02*
Y1562229D01*
X914640Y1561729D01*
G01Y1559729D02*
X915640D01*
G01X917323Y1560104D02*
X917573Y1559896D01*
X917865Y1559771D01*
X918240Y1559729D01*
X918615Y1559812D01*
X918907Y1559979D01*
X919115Y1560271D01*
X919157Y1560604D01*
X919073Y1560937D01*
X918865Y1561146D01*
X918573Y1561312D01*
X918282Y1561354D01*
X917990Y1561312D01*
X917615Y1561146D01*
X917740Y1562229D01*
X918865D01*
G01X921340D02*
X921007Y1562146D01*
X920757Y1561937D01*
X920590Y1561687D01*
X920465Y1561354D01*
X920423Y1560979D01*
X920465Y1560604D01*
X920590Y1560271D01*
X920757Y1560021D01*
X921007Y1559812D01*
X921340Y1559729D01*
X921673Y1559812D01*
X921923Y1560021D01*
X922090Y1560271D01*
X922215Y1560604D01*
X922257Y1560979D01*
X922215Y1561354D01*
X922090Y1561687D01*
X921923Y1561937D01*
X921673Y1562146D01*
X921340Y1562229D01*
G01X921700Y1537200D02*
Y1541200D01*
X914300D01*
G01X927764Y1562180D02*
X925264D01*
Y1563221D01*
X925389Y1563555D01*
X925556Y1563763D01*
X925889Y1563846D01*
X926222Y1563763D01*
X926431Y1563513D01*
X926556Y1563221D01*
Y1562180D01*
G01Y1563221D02*
X927764Y1563846D01*
G01Y1566113D02*
X925264D01*
X925764Y1565613D01*
G01X927764D02*
Y1566613D01*
G01Y1569213D02*
X925264D01*
X925764Y1568713D01*
G01X927764D02*
Y1569713D01*
G01Y1572813D02*
X925264D01*
X927056Y1571271D01*
Y1573355D01*
G01X927264Y1574496D02*
X927556Y1574746D01*
X927722Y1575080D01*
X927764Y1575455D01*
X927722Y1575788D01*
X927514Y1576121D01*
X927264Y1576330D01*
X927014Y1576371D01*
X926722Y1576288D01*
X926514Y1575996D01*
X926431Y1575705D01*
Y1575330D01*
G01Y1575705D02*
X926306Y1575955D01*
X926097Y1576163D01*
X925847Y1576246D01*
X925597Y1576163D01*
X925389Y1575955D01*
X925264Y1575580D01*
X925306Y1575205D01*
X925472Y1574830D01*
G01X924500Y1548000D02*
X928500D01*
Y1555400D01*
G01X908301Y1564372D02*
Y1566872D01*
X909342D01*
X909676Y1566747D01*
X909884Y1566580D01*
X909967Y1566247D01*
X909884Y1565914D01*
X909634Y1565705D01*
X909342Y1565580D01*
X908301D01*
G01X909342D02*
X909967Y1564372D01*
G01X912234D02*
Y1566872D01*
X911734Y1566372D01*
G01Y1564372D02*
X912734D01*
G01X915334D02*
Y1566872D01*
X914834Y1566372D01*
G01Y1564372D02*
X915834D01*
G01X918934D02*
Y1566872D01*
X917392Y1565080D01*
X919476D01*
G01X920742Y1566455D02*
X920992Y1566705D01*
X921284Y1566830D01*
X921617Y1566872D01*
X922034Y1566789D01*
X922326Y1566580D01*
X922409Y1566330D01*
X922367Y1566080D01*
X922201Y1565872D01*
X921367Y1565455D01*
X920992Y1565164D01*
X920742Y1564747D01*
X920659Y1564372D01*
X922409D01*
G01X918700Y1542200D02*
Y1546200D01*
X911300D01*
G01X899734Y1545538D02*
X899692Y1545205D01*
X899526Y1544913D01*
X899276Y1544663D01*
X898984Y1544496D01*
X898651Y1544413D01*
X898317D01*
X897984Y1544496D01*
X897692Y1544663D01*
X897442Y1544913D01*
X897276Y1545205D01*
X897234Y1545538D01*
X897276Y1545871D01*
X897442Y1546163D01*
X897692Y1546413D01*
X897984Y1546580D01*
X898317Y1546663D01*
X898651D01*
X898984Y1546580D01*
X899276Y1546413D01*
X899526Y1546163D01*
X899692Y1545871D01*
X899734Y1545538D01*
G01X899067Y1545871D02*
X899734Y1546371D01*
G01X899442Y1547930D02*
X899651Y1548221D01*
X899734Y1548555D01*
X899651Y1548888D01*
X899401Y1549180D01*
X899026Y1549388D01*
X898651Y1549471D01*
X898192D01*
X897817Y1549388D01*
X897484Y1549180D01*
X897317Y1548930D01*
X897234Y1548638D01*
X897317Y1548305D01*
X897484Y1548055D01*
X897734Y1547888D01*
X898067Y1547805D01*
X898359Y1547888D01*
X898651Y1548096D01*
X898817Y1548346D01*
X898859Y1548638D01*
X898776Y1548971D01*
X898567Y1549221D01*
X898192Y1549471D01*
G01X895488Y1531360D02*
X903088D01*
G01X895488Y1542160D02*
Y1531360D01*
G01X903088Y1542160D02*
X895488D01*
G01X903088Y1531360D02*
Y1542160D01*
G01X904500Y1527500D02*
X917900D01*
G01X939013Y1544150D02*
Y1542150D01*
G01X924050Y1534120D02*
X927050D01*
G01X925050Y1524280D02*
X927050D01*
G01X926150Y1538050D02*
Y1543050D01*
X931150D01*
G01X896453Y1554857D02*
Y1557357D01*
X897494D01*
X897828Y1557232D01*
X898036Y1557065D01*
X898119Y1556732D01*
X898036Y1556399D01*
X897786Y1556190D01*
X897494Y1556065D01*
X896453D01*
G01X897494D02*
X898119Y1554857D01*
G01X900386D02*
Y1557357D01*
X899886Y1556857D01*
G01Y1554857D02*
X900886D01*
G01X903486D02*
Y1557357D01*
X902986Y1556857D01*
G01Y1554857D02*
X903986D01*
G01X907086D02*
Y1557357D01*
X905544Y1555565D01*
X907628D01*
G01X909686Y1554857D02*
X909978Y1554899D01*
X910311Y1555024D01*
X910519Y1555232D01*
X910603Y1555524D01*
X910519Y1555815D01*
X910269Y1556065D01*
X909894Y1556190D01*
X909478D01*
X909228Y1556274D01*
X909019Y1556482D01*
X908936Y1556774D01*
X909061Y1557065D01*
X909353Y1557274D01*
X909686Y1557357D01*
X910019Y1557274D01*
X910311Y1557065D01*
X910436Y1556774D01*
X910353Y1556482D01*
X910144Y1556274D01*
X909894Y1556190D01*
X909478D01*
X909103Y1556065D01*
X908853Y1555815D01*
X908769Y1555524D01*
X908853Y1555232D01*
X909061Y1555024D01*
X909394Y1554899D01*
X909686Y1554857D01*
G01X910455Y1553330D02*
X910205Y1553455D01*
X909913Y1553538D01*
X909580D01*
X909205Y1553413D01*
X908913Y1553205D01*
X908705Y1552955D01*
X908538Y1552538D01*
X908496Y1552163D01*
X908580Y1551788D01*
X908705Y1551538D01*
X908955Y1551288D01*
X909246Y1551121D01*
X909538Y1551038D01*
X909830D01*
X910121Y1551121D01*
X910371Y1551246D01*
X910580Y1551413D01*
G01X911846Y1552080D02*
X912138Y1552371D01*
X912388Y1552538D01*
X912721Y1552621D01*
X913013Y1552538D01*
X913221Y1552371D01*
X913388Y1552121D01*
X913430Y1551830D01*
X913388Y1551580D01*
X913221Y1551330D01*
X912971Y1551121D01*
X912680Y1551038D01*
X912346Y1551121D01*
X912055Y1551371D01*
X911888Y1551746D01*
X911846Y1552163D01*
X911930Y1552705D01*
X912055Y1552996D01*
X912263Y1553288D01*
X912555Y1553496D01*
X912846Y1553538D01*
X913138Y1553455D01*
X913346Y1553246D01*
G01X915030Y1551330D02*
X915321Y1551121D01*
X915655Y1551038D01*
X915988Y1551121D01*
X916280Y1551371D01*
X916488Y1551746D01*
X916571Y1552121D01*
Y1552580D01*
X916488Y1552955D01*
X916280Y1553288D01*
X916030Y1553455D01*
X915738Y1553538D01*
X915405Y1553455D01*
X915155Y1553288D01*
X914988Y1553038D01*
X914905Y1552705D01*
X914988Y1552413D01*
X915196Y1552121D01*
X915446Y1551955D01*
X915738Y1551913D01*
X916071Y1551996D01*
X916321Y1552205D01*
X916571Y1552580D01*
G01X910090Y1549577D02*
X909840Y1549702D01*
X909548Y1549785D01*
X909215D01*
X908840Y1549660D01*
X908548Y1549452D01*
X908340Y1549202D01*
X908173Y1548785D01*
X908131Y1548410D01*
X908215Y1548035D01*
X908340Y1547785D01*
X908590Y1547535D01*
X908881Y1547368D01*
X909173Y1547285D01*
X909465D01*
X909756Y1547368D01*
X910006Y1547493D01*
X910215Y1547660D01*
G01X912273Y1547285D02*
Y1549785D01*
X911773Y1549285D01*
G01Y1547285D02*
X912773D01*
G01X915373Y1549785D02*
X915040Y1549702D01*
X914790Y1549493D01*
X914623Y1549243D01*
X914498Y1548910D01*
X914456Y1548535D01*
X914498Y1548160D01*
X914623Y1547827D01*
X914790Y1547577D01*
X915040Y1547368D01*
X915373Y1547285D01*
X915706Y1547368D01*
X915956Y1547577D01*
X916123Y1547827D01*
X916248Y1548160D01*
X916290Y1548535D01*
X916248Y1548910D01*
X916123Y1549243D01*
X915956Y1549493D01*
X915706Y1549702D01*
X915373Y1549785D01*
G01X917681Y1549368D02*
X917931Y1549618D01*
X918223Y1549743D01*
X918556Y1549785D01*
X918973Y1549702D01*
X919265Y1549493D01*
X919348Y1549243D01*
X919306Y1548993D01*
X919140Y1548785D01*
X918306Y1548368D01*
X917931Y1548077D01*
X917681Y1547660D01*
X917598Y1547285D01*
X919348D01*
G01X942331Y1571361D02*
X939831D01*
Y1572402D01*
X939956Y1572736D01*
X940123Y1572944D01*
X940456Y1573027D01*
X940789Y1572944D01*
X940998Y1572694D01*
X941123Y1572402D01*
Y1571361D01*
G01Y1572402D02*
X942331Y1573027D01*
G01Y1575294D02*
X939831D01*
X940331Y1574794D01*
G01X942331D02*
Y1575794D01*
G01Y1578394D02*
X939831D01*
X940331Y1577894D01*
G01X942331D02*
Y1578894D01*
G01X941289Y1580702D02*
X940998Y1580994D01*
X940831Y1581244D01*
X940748Y1581577D01*
X940831Y1581869D01*
X940998Y1582077D01*
X941248Y1582244D01*
X941539Y1582286D01*
X941789Y1582244D01*
X942039Y1582077D01*
X942248Y1581827D01*
X942331Y1581536D01*
X942248Y1581202D01*
X941998Y1580911D01*
X941623Y1580744D01*
X941206Y1580702D01*
X940664Y1580786D01*
X940373Y1580911D01*
X940081Y1581119D01*
X939873Y1581411D01*
X939831Y1581702D01*
X939914Y1581994D01*
X940123Y1582202D01*
G01X941956Y1583677D02*
X942164Y1583927D01*
X942289Y1584219D01*
X942331Y1584594D01*
X942248Y1584969D01*
X942081Y1585261D01*
X941789Y1585469D01*
X941456Y1585511D01*
X941123Y1585427D01*
X940914Y1585219D01*
X940748Y1584927D01*
X940706Y1584636D01*
X940748Y1584344D01*
X940914Y1583969D01*
X939831Y1584094D01*
Y1585219D01*
G01X930781Y1572591D02*
X930656Y1572341D01*
X930573Y1572049D01*
Y1571716D01*
X930698Y1571341D01*
X930906Y1571049D01*
X931156Y1570841D01*
X931573Y1570674D01*
X931948Y1570632D01*
X932323Y1570716D01*
X932573Y1570841D01*
X932823Y1571091D01*
X932990Y1571382D01*
X933073Y1571674D01*
Y1571966D01*
X932990Y1572257D01*
X932865Y1572507D01*
X932698Y1572716D01*
G01Y1573857D02*
X932906Y1574107D01*
X933031Y1574399D01*
X933073Y1574774D01*
X932990Y1575149D01*
X932823Y1575441D01*
X932531Y1575649D01*
X932198Y1575691D01*
X931865Y1575607D01*
X931656Y1575399D01*
X931490Y1575107D01*
X931448Y1574816D01*
X931490Y1574524D01*
X931656Y1574149D01*
X930573Y1574274D01*
Y1575399D01*
G01X933073Y1577874D02*
X933031Y1578166D01*
X932906Y1578499D01*
X932698Y1578707D01*
X932406Y1578791D01*
X932115Y1578707D01*
X931865Y1578457D01*
X931740Y1578082D01*
Y1577666D01*
X931656Y1577416D01*
X931448Y1577207D01*
X931156Y1577124D01*
X930865Y1577249D01*
X930656Y1577541D01*
X930573Y1577874D01*
X930656Y1578207D01*
X930865Y1578499D01*
X931156Y1578624D01*
X931448Y1578541D01*
X931656Y1578332D01*
X931740Y1578082D01*
Y1577666D01*
X931865Y1577291D01*
X932115Y1577041D01*
X932406Y1576957D01*
X932698Y1577041D01*
X932906Y1577249D01*
X933031Y1577582D01*
X933073Y1577874D01*
G01Y1581474D02*
X930573D01*
X932365Y1579932D01*
Y1582016D01*
G01X935957Y1573213D02*
X935832Y1572963D01*
X935749Y1572671D01*
Y1572338D01*
X935874Y1571963D01*
X936082Y1571671D01*
X936332Y1571463D01*
X936749Y1571296D01*
X937124Y1571254D01*
X937499Y1571338D01*
X937749Y1571463D01*
X937999Y1571713D01*
X938166Y1572004D01*
X938249Y1572296D01*
Y1572588D01*
X938166Y1572879D01*
X938041Y1573129D01*
X937874Y1573338D01*
G01Y1574479D02*
X938082Y1574729D01*
X938207Y1575021D01*
X938249Y1575396D01*
X938166Y1575771D01*
X937999Y1576063D01*
X937707Y1576271D01*
X937374Y1576313D01*
X937041Y1576229D01*
X936832Y1576021D01*
X936666Y1575729D01*
X936624Y1575438D01*
X936666Y1575146D01*
X936832Y1574771D01*
X935749Y1574896D01*
Y1576021D01*
G01X937957Y1577788D02*
X938166Y1578079D01*
X938249Y1578413D01*
X938166Y1578746D01*
X937916Y1579038D01*
X937541Y1579246D01*
X937166Y1579329D01*
X936707D01*
X936332Y1579246D01*
X935999Y1579038D01*
X935832Y1578788D01*
X935749Y1578496D01*
X935832Y1578163D01*
X935999Y1577913D01*
X936249Y1577746D01*
X936582Y1577663D01*
X936874Y1577746D01*
X937166Y1577954D01*
X937332Y1578204D01*
X937374Y1578496D01*
X937291Y1578829D01*
X937082Y1579079D01*
X936707Y1579329D01*
G01X936166Y1580804D02*
X935916Y1581054D01*
X935791Y1581346D01*
X935749Y1581679D01*
X935832Y1582096D01*
X936041Y1582388D01*
X936291Y1582471D01*
X936541Y1582429D01*
X936749Y1582263D01*
X937166Y1581429D01*
X937457Y1581054D01*
X937874Y1580804D01*
X938249Y1580721D01*
Y1582471D01*
G01X962226Y151632D02*
X958226D01*
Y153232D01*
X958426Y153765D01*
X958893Y154165D01*
X959426Y154298D01*
X959959Y154165D01*
X960359Y153832D01*
X960559Y153232D01*
Y151632D01*
G01X962226Y156632D02*
X959559D01*
G01X960093D02*
X959826Y156965D01*
X959626Y157298D01*
X959559Y157765D01*
X959626Y158098D01*
X959826Y158498D01*
G01X960426Y161165D02*
Y163298D01*
X959959Y163098D01*
X959693Y162765D01*
X959559Y162298D01*
X959626Y161832D01*
X959826Y161432D01*
X960293Y161165D01*
X960693Y161032D01*
X961093D01*
X961493Y161165D01*
X961893Y161498D01*
X962159Y161898D01*
X962226Y162365D01*
X962093Y162832D01*
X961693Y163298D01*
G01X961759Y165765D02*
X962026Y166098D01*
X962226Y166565D01*
Y166965D01*
X962093Y167365D01*
X961893Y167632D01*
X961626Y167765D01*
X961226Y167698D01*
X961026Y167432D01*
X960626Y166232D01*
X960159Y165965D01*
X959826Y166098D01*
X959626Y166365D01*
X959559Y166765D01*
X959626Y167165D01*
X959826Y167565D01*
G01X961759Y170365D02*
X962026Y170698D01*
X962226Y171165D01*
Y171565D01*
X962093Y171965D01*
X961893Y172232D01*
X961626Y172365D01*
X961226Y172298D01*
X961026Y172032D01*
X960626Y170832D01*
X960159Y170565D01*
X959826Y170698D01*
X959626Y170965D01*
X959559Y171365D01*
X959626Y171765D01*
X959826Y172165D01*
G01X962226Y179298D02*
X958226D01*
Y181832D01*
G01X960159Y180898D02*
Y179298D01*
G01X959559Y185165D02*
X962226D01*
G01X958493D02*
X958426Y185032D01*
X958293D01*
X958226Y185165D01*
X958293Y185298D01*
X958426D01*
X958493Y185165D01*
G01X958226Y189765D02*
X962226D01*
G01X959559Y188832D02*
Y190698D01*
G01X962226Y530765D02*
X958226D01*
Y532365D01*
X958426Y532898D01*
X958893Y533298D01*
X959426Y533431D01*
X959959Y533298D01*
X960359Y532965D01*
X960559Y532365D01*
Y530765D01*
G01X962226Y535765D02*
X959559D01*
G01X960093D02*
X959826Y536098D01*
X959626Y536431D01*
X959559Y536898D01*
X959626Y537231D01*
X959826Y537631D01*
G01X960426Y540298D02*
Y542431D01*
X959959Y542231D01*
X959693Y541898D01*
X959559Y541431D01*
X959626Y540965D01*
X959826Y540565D01*
X960293Y540298D01*
X960693Y540165D01*
X961093D01*
X961493Y540298D01*
X961893Y540631D01*
X962159Y541031D01*
X962226Y541498D01*
X962093Y541965D01*
X961693Y542431D01*
G01X961759Y544898D02*
X962026Y545231D01*
X962226Y545698D01*
Y546098D01*
X962093Y546498D01*
X961893Y546765D01*
X961626Y546898D01*
X961226Y546831D01*
X961026Y546565D01*
X960626Y545365D01*
X960159Y545098D01*
X959826Y545231D01*
X959626Y545498D01*
X959559Y545898D01*
X959626Y546298D01*
X959826Y546698D01*
G01X961759Y549498D02*
X962026Y549831D01*
X962226Y550298D01*
Y550698D01*
X962093Y551098D01*
X961893Y551365D01*
X961626Y551498D01*
X961226Y551431D01*
X961026Y551165D01*
X960626Y549965D01*
X960159Y549698D01*
X959826Y549831D01*
X959626Y550098D01*
X959559Y550498D01*
X959626Y550898D01*
X959826Y551298D01*
G01X962226Y558431D02*
X958226D01*
Y560965D01*
G01X960159Y560031D02*
Y558431D01*
G01X959559Y564298D02*
X962226D01*
G01X958493D02*
X958426Y564165D01*
X958293D01*
X958226Y564298D01*
X958293Y564431D01*
X958426D01*
X958493Y564298D01*
G01X958226Y568898D02*
X962226D01*
G01X959559Y567965D02*
Y569831D01*
G01X956593Y894736D02*
X954093D01*
Y895777D01*
X954218Y896111D01*
X954385Y896319D01*
X954718Y896402D01*
X955051Y896319D01*
X955260Y896069D01*
X955385Y895777D01*
Y894736D01*
G01Y895777D02*
X956593Y896402D01*
G01Y898586D02*
X956051Y898669D01*
X955593Y898794D01*
X955176Y898961D01*
X954718Y899169D01*
X954093Y899502D01*
Y897836D01*
G01X956593Y901769D02*
X956551Y902061D01*
X956426Y902394D01*
X956218Y902602D01*
X955926Y902686D01*
X955635Y902602D01*
X955385Y902352D01*
X955260Y901977D01*
Y901561D01*
X955176Y901311D01*
X954968Y901102D01*
X954676Y901019D01*
X954385Y901144D01*
X954176Y901436D01*
X954093Y901769D01*
X954176Y902102D01*
X954385Y902394D01*
X954676Y902519D01*
X954968Y902436D01*
X955176Y902227D01*
X955260Y901977D01*
Y901561D01*
X955385Y901186D01*
X955635Y900936D01*
X955926Y900852D01*
X956218Y900936D01*
X956426Y901144D01*
X956551Y901477D01*
X956593Y901769D01*
G01X963500Y913700D02*
X959500D01*
Y906300D01*
G01X960293Y894736D02*
X957793D01*
Y895777D01*
X957918Y896111D01*
X958085Y896319D01*
X958418Y896402D01*
X958751Y896319D01*
X958960Y896069D01*
X959085Y895777D01*
Y894736D01*
G01Y895777D02*
X960293Y896402D01*
G01Y898669D02*
X960251Y898961D01*
X960126Y899294D01*
X959918Y899502D01*
X959626Y899586D01*
X959335Y899502D01*
X959085Y899252D01*
X958960Y898877D01*
Y898461D01*
X958876Y898211D01*
X958668Y898002D01*
X958376Y897919D01*
X958085Y898044D01*
X957876Y898336D01*
X957793Y898669D01*
X957876Y899002D01*
X958085Y899294D01*
X958376Y899419D01*
X958668Y899336D01*
X958876Y899127D01*
X958960Y898877D01*
Y898461D01*
X959085Y898086D01*
X959335Y897836D01*
X959626Y897752D01*
X959918Y897836D01*
X960126Y898044D01*
X960251Y898377D01*
X960293Y898669D01*
G01Y901769D02*
X957793D01*
X958293Y901269D01*
G01X960293D02*
Y902269D01*
G01X968000Y913700D02*
X964000D01*
Y906300D01*
G01X952893Y894736D02*
X950393D01*
Y895777D01*
X950518Y896111D01*
X950685Y896319D01*
X951018Y896402D01*
X951351Y896319D01*
X951560Y896069D01*
X951685Y895777D01*
Y894736D01*
G01Y895777D02*
X952893Y896402D01*
G01Y898669D02*
X952851Y898961D01*
X952726Y899294D01*
X952518Y899502D01*
X952226Y899586D01*
X951935Y899502D01*
X951685Y899252D01*
X951560Y898877D01*
Y898461D01*
X951476Y898211D01*
X951268Y898002D01*
X950976Y897919D01*
X950685Y898044D01*
X950476Y898336D01*
X950393Y898669D01*
X950476Y899002D01*
X950685Y899294D01*
X950976Y899419D01*
X951268Y899336D01*
X951476Y899127D01*
X951560Y898877D01*
Y898461D01*
X951685Y898086D01*
X951935Y897836D01*
X952226Y897752D01*
X952518Y897836D01*
X952726Y898044D01*
X952851Y898377D01*
X952893Y898669D01*
G01X952518Y900852D02*
X952726Y901102D01*
X952851Y901394D01*
X952893Y901769D01*
X952810Y902144D01*
X952643Y902436D01*
X952351Y902644D01*
X952018Y902686D01*
X951685Y902602D01*
X951476Y902394D01*
X951310Y902102D01*
X951268Y901811D01*
X951310Y901519D01*
X951476Y901144D01*
X950393Y901269D01*
Y902394D01*
G01X955000Y906300D02*
X959000D01*
Y913700D01*
G01X963993Y894736D02*
X961493D01*
Y895777D01*
X961618Y896111D01*
X961785Y896319D01*
X962118Y896402D01*
X962451Y896319D01*
X962660Y896069D01*
X962785Y895777D01*
Y894736D01*
G01Y895777D02*
X963993Y896402D01*
G01Y898669D02*
X963951Y898961D01*
X963826Y899294D01*
X963618Y899502D01*
X963326Y899586D01*
X963035Y899502D01*
X962785Y899252D01*
X962660Y898877D01*
Y898461D01*
X962576Y898211D01*
X962368Y898002D01*
X962076Y897919D01*
X961785Y898044D01*
X961576Y898336D01*
X961493Y898669D01*
X961576Y899002D01*
X961785Y899294D01*
X962076Y899419D01*
X962368Y899336D01*
X962576Y899127D01*
X962660Y898877D01*
Y898461D01*
X962785Y898086D01*
X963035Y897836D01*
X963326Y897752D01*
X963618Y897836D01*
X963826Y898044D01*
X963951Y898377D01*
X963993Y898669D01*
G01X962951Y900977D02*
X962660Y901269D01*
X962493Y901519D01*
X962410Y901852D01*
X962493Y902144D01*
X962660Y902352D01*
X962910Y902519D01*
X963201Y902561D01*
X963451Y902519D01*
X963701Y902352D01*
X963910Y902102D01*
X963993Y901811D01*
X963910Y901477D01*
X963660Y901186D01*
X963285Y901019D01*
X962868Y900977D01*
X962326Y901061D01*
X962035Y901186D01*
X961743Y901394D01*
X961535Y901686D01*
X961493Y901977D01*
X961576Y902269D01*
X961785Y902477D01*
G01X968500Y906300D02*
X972500D01*
Y913700D01*
G01X949193Y894736D02*
X946693D01*
Y895777D01*
X946818Y896111D01*
X946985Y896319D01*
X947318Y896402D01*
X947651Y896319D01*
X947860Y896069D01*
X947985Y895777D01*
Y894736D01*
G01Y895777D02*
X949193Y896402D01*
G01Y898669D02*
X949151Y898961D01*
X949026Y899294D01*
X948818Y899502D01*
X948526Y899586D01*
X948235Y899502D01*
X947985Y899252D01*
X947860Y898877D01*
Y898461D01*
X947776Y898211D01*
X947568Y898002D01*
X947276Y897919D01*
X946985Y898044D01*
X946776Y898336D01*
X946693Y898669D01*
X946776Y899002D01*
X946985Y899294D01*
X947276Y899419D01*
X947568Y899336D01*
X947776Y899127D01*
X947860Y898877D01*
Y898461D01*
X947985Y898086D01*
X948235Y897836D01*
X948526Y897752D01*
X948818Y897836D01*
X949026Y898044D01*
X949151Y898377D01*
X949193Y898669D01*
G01Y901769D02*
X949151Y902061D01*
X949026Y902394D01*
X948818Y902602D01*
X948526Y902686D01*
X948235Y902602D01*
X947985Y902352D01*
X947860Y901977D01*
Y901561D01*
X947776Y901311D01*
X947568Y901102D01*
X947276Y901019D01*
X946985Y901144D01*
X946776Y901436D01*
X946693Y901769D01*
X946776Y902102D01*
X946985Y902394D01*
X947276Y902519D01*
X947568Y902436D01*
X947776Y902227D01*
X947860Y901977D01*
Y901561D01*
X947985Y901186D01*
X948235Y900936D01*
X948526Y900852D01*
X948818Y900936D01*
X949026Y901144D01*
X949151Y901477D01*
X949193Y901769D01*
G01X950500Y906300D02*
X954500D01*
Y913700D01*
G01X943899Y894445D02*
Y908445D01*
G01X985363Y929967D02*
X987155D01*
X987530Y930134D01*
X987780Y930467D01*
X987863Y930884D01*
X987780Y931301D01*
X987530Y931634D01*
X987155Y931801D01*
X985363D01*
G01X987863Y933984D02*
X987821Y934276D01*
X987696Y934609D01*
X987488Y934817D01*
X987196Y934901D01*
X986905Y934817D01*
X986655Y934567D01*
X986530Y934192D01*
Y933776D01*
X986446Y933526D01*
X986238Y933317D01*
X985946Y933234D01*
X985655Y933359D01*
X985446Y933651D01*
X985363Y933984D01*
X985446Y934317D01*
X985655Y934609D01*
X985946Y934734D01*
X986238Y934651D01*
X986446Y934442D01*
X986530Y934192D01*
Y933776D01*
X986655Y933401D01*
X986905Y933151D01*
X987196Y933067D01*
X987488Y933151D01*
X987696Y933359D01*
X987821Y933692D01*
X987863Y933984D01*
G01X950850Y917500D02*
Y938500D01*
X982500D01*
Y927500D01*
X950850D01*
G01Y936150D02*
X954000Y933000D01*
X950850Y929850D01*
G01X943148Y925736D02*
X943023Y925486D01*
X942940Y925194D01*
Y924861D01*
X943065Y924486D01*
X943273Y924194D01*
X943523Y923986D01*
X943940Y923819D01*
X944315Y923777D01*
X944690Y923861D01*
X944940Y923986D01*
X945190Y924236D01*
X945357Y924527D01*
X945440Y924819D01*
Y925111D01*
X945357Y925402D01*
X945232Y925652D01*
X945065Y925861D01*
G01X943357Y927127D02*
X943107Y927377D01*
X942982Y927669D01*
X942940Y928002D01*
X943023Y928419D01*
X943232Y928711D01*
X943482Y928794D01*
X943732Y928752D01*
X943940Y928586D01*
X944357Y927752D01*
X944648Y927377D01*
X945065Y927127D01*
X945440Y927044D01*
Y928794D01*
G01X945065Y930102D02*
X945273Y930352D01*
X945398Y930644D01*
X945440Y931019D01*
X945357Y931394D01*
X945190Y931686D01*
X944898Y931894D01*
X944565Y931936D01*
X944232Y931852D01*
X944023Y931644D01*
X943857Y931352D01*
X943815Y931061D01*
X943857Y930769D01*
X944023Y930394D01*
X942940Y930519D01*
Y931644D01*
G01X946848Y925736D02*
X946723Y925486D01*
X946640Y925194D01*
Y924861D01*
X946765Y924486D01*
X946973Y924194D01*
X947223Y923986D01*
X947640Y923819D01*
X948015Y923777D01*
X948390Y923861D01*
X948640Y923986D01*
X948890Y924236D01*
X949057Y924527D01*
X949140Y924819D01*
Y925111D01*
X949057Y925402D01*
X948932Y925652D01*
X948765Y925861D01*
G01X947057Y927127D02*
X946807Y927377D01*
X946682Y927669D01*
X946640Y928002D01*
X946723Y928419D01*
X946932Y928711D01*
X947182Y928794D01*
X947432Y928752D01*
X947640Y928586D01*
X948057Y927752D01*
X948348Y927377D01*
X948765Y927127D01*
X949140Y927044D01*
Y928794D01*
G01X948098Y930227D02*
X947807Y930519D01*
X947640Y930769D01*
X947557Y931102D01*
X947640Y931394D01*
X947807Y931602D01*
X948057Y931769D01*
X948348Y931811D01*
X948598Y931769D01*
X948848Y931602D01*
X949057Y931352D01*
X949140Y931061D01*
X949057Y930727D01*
X948807Y930436D01*
X948432Y930269D01*
X948015Y930227D01*
X947473Y930311D01*
X947182Y930436D01*
X946890Y930644D01*
X946682Y930936D01*
X946640Y931227D01*
X946723Y931519D01*
X946932Y931727D01*
G01X991973Y985737D02*
X989473D01*
Y986778D01*
X989598Y987112D01*
X989765Y987320D01*
X990098Y987403D01*
X990431Y987320D01*
X990640Y987070D01*
X990765Y986778D01*
Y985737D01*
G01Y986778D02*
X991973Y987403D01*
G01X991598Y988753D02*
X991806Y989003D01*
X991931Y989295D01*
X991973Y989670D01*
X991890Y990045D01*
X991723Y990337D01*
X991431Y990545D01*
X991098Y990587D01*
X990765Y990503D01*
X990556Y990295D01*
X990390Y990003D01*
X990348Y989712D01*
X990390Y989420D01*
X990556Y989045D01*
X989473Y989170D01*
Y990295D01*
G01X991973Y993270D02*
X989473D01*
X991265Y991728D01*
Y993812D01*
G01X988254Y985869D02*
X985754D01*
Y986910D01*
X985879Y987244D01*
X986046Y987452D01*
X986379Y987535D01*
X986712Y987452D01*
X986921Y987202D01*
X987046Y986910D01*
Y985869D01*
G01Y986910D02*
X988254Y987535D01*
G01X987879Y988885D02*
X988087Y989135D01*
X988212Y989427D01*
X988254Y989802D01*
X988171Y990177D01*
X988004Y990469D01*
X987712Y990677D01*
X987379Y990719D01*
X987046Y990635D01*
X986837Y990427D01*
X986671Y990135D01*
X986629Y989844D01*
X986671Y989552D01*
X986837Y989177D01*
X985754Y989302D01*
Y990427D01*
G01X988254Y992902D02*
X988212Y993194D01*
X988087Y993527D01*
X987879Y993735D01*
X987587Y993819D01*
X987296Y993735D01*
X987046Y993485D01*
X986921Y993110D01*
Y992694D01*
X986837Y992444D01*
X986629Y992235D01*
X986337Y992152D01*
X986046Y992277D01*
X985837Y992569D01*
X985754Y992902D01*
X985837Y993235D01*
X986046Y993527D01*
X986337Y993652D01*
X986629Y993569D01*
X986837Y993360D01*
X986921Y993110D01*
Y992694D01*
X987046Y992319D01*
X987296Y992069D01*
X987587Y991985D01*
X987879Y992069D01*
X988087Y992277D01*
X988212Y992610D01*
X988254Y992902D01*
G01X995194Y983540D02*
X991194D01*
Y976140D01*
G01X965400Y963967D02*
X962900D01*
Y965008D01*
X963025Y965342D01*
X963192Y965550D01*
X963525Y965633D01*
X963858Y965550D01*
X964067Y965300D01*
X964192Y965008D01*
Y963967D01*
G01Y965008D02*
X965400Y965633D01*
G01Y967817D02*
X964858Y967900D01*
X964400Y968025D01*
X963983Y968192D01*
X963525Y968400D01*
X962900Y968733D01*
Y967067D01*
G01X965400Y970917D02*
X964858Y971000D01*
X964400Y971125D01*
X963983Y971292D01*
X963525Y971500D01*
X962900Y971833D01*
Y970167D01*
G01X965900Y959100D02*
X961900D01*
Y951700D01*
G01X956400Y963967D02*
X953900D01*
Y965008D01*
X954025Y965342D01*
X954192Y965550D01*
X954525Y965633D01*
X954858Y965550D01*
X955067Y965300D01*
X955192Y965008D01*
Y963967D01*
G01Y965008D02*
X956400Y965633D01*
G01Y967900D02*
X956358Y968192D01*
X956233Y968525D01*
X956025Y968733D01*
X955733Y968817D01*
X955442Y968733D01*
X955192Y968483D01*
X955067Y968108D01*
Y967692D01*
X954983Y967442D01*
X954775Y967233D01*
X954483Y967150D01*
X954192Y967275D01*
X953983Y967567D01*
X953900Y967900D01*
X953983Y968233D01*
X954192Y968525D01*
X954483Y968650D01*
X954775Y968567D01*
X954983Y968358D01*
X955067Y968108D01*
Y967692D01*
X955192Y967317D01*
X955442Y967067D01*
X955733Y966983D01*
X956025Y967067D01*
X956233Y967275D01*
X956358Y967608D01*
X956400Y967900D01*
G01X954317Y970208D02*
X954067Y970458D01*
X953942Y970750D01*
X953900Y971083D01*
X953983Y971500D01*
X954192Y971792D01*
X954442Y971875D01*
X954692Y971833D01*
X954900Y971667D01*
X955317Y970833D01*
X955608Y970458D01*
X956025Y970208D01*
X956400Y970125D01*
Y971875D01*
G01X952900Y951700D02*
X956900D01*
Y959100D01*
G01X951900Y963967D02*
X949400D01*
Y965008D01*
X949525Y965342D01*
X949692Y965550D01*
X950025Y965633D01*
X950358Y965550D01*
X950567Y965300D01*
X950692Y965008D01*
Y963967D01*
G01Y965008D02*
X951900Y965633D01*
G01Y967900D02*
X951858Y968192D01*
X951733Y968525D01*
X951525Y968733D01*
X951233Y968817D01*
X950942Y968733D01*
X950692Y968483D01*
X950567Y968108D01*
Y967692D01*
X950483Y967442D01*
X950275Y967233D01*
X949983Y967150D01*
X949692Y967275D01*
X949483Y967567D01*
X949400Y967900D01*
X949483Y968233D01*
X949692Y968525D01*
X949983Y968650D01*
X950275Y968567D01*
X950483Y968358D01*
X950567Y968108D01*
Y967692D01*
X950692Y967317D01*
X950942Y967067D01*
X951233Y966983D01*
X951525Y967067D01*
X951733Y967275D01*
X951858Y967608D01*
X951900Y967900D01*
G01X951400Y970083D02*
X951692Y970333D01*
X951858Y970667D01*
X951900Y971042D01*
X951858Y971375D01*
X951650Y971708D01*
X951400Y971917D01*
X951150Y971958D01*
X950858Y971875D01*
X950650Y971583D01*
X950567Y971292D01*
Y970917D01*
G01Y971292D02*
X950442Y971542D01*
X950233Y971750D01*
X949983Y971833D01*
X949733Y971750D01*
X949525Y971542D01*
X949400Y971167D01*
X949442Y970792D01*
X949608Y970417D01*
G01X948400Y951700D02*
X952400D01*
Y959100D01*
G01X960900Y963967D02*
X958400D01*
Y965008D01*
X958525Y965342D01*
X958692Y965550D01*
X959025Y965633D01*
X959358Y965550D01*
X959567Y965300D01*
X959692Y965008D01*
Y963967D01*
G01Y965008D02*
X960900Y965633D01*
G01Y967900D02*
X960858Y968192D01*
X960733Y968525D01*
X960525Y968733D01*
X960233Y968817D01*
X959942Y968733D01*
X959692Y968483D01*
X959567Y968108D01*
Y967692D01*
X959483Y967442D01*
X959275Y967233D01*
X958983Y967150D01*
X958692Y967275D01*
X958483Y967567D01*
X958400Y967900D01*
X958483Y968233D01*
X958692Y968525D01*
X958983Y968650D01*
X959275Y968567D01*
X959483Y968358D01*
X959567Y968108D01*
Y967692D01*
X959692Y967317D01*
X959942Y967067D01*
X960233Y966983D01*
X960525Y967067D01*
X960733Y967275D01*
X960858Y967608D01*
X960900Y967900D01*
G01Y971500D02*
X958400D01*
X960192Y969958D01*
Y972042D01*
G01X957400Y951700D02*
X961400D01*
Y959100D01*
G01X978000Y976067D02*
X975500D01*
Y977108D01*
X975625Y977442D01*
X975792Y977650D01*
X976125Y977733D01*
X976458Y977650D01*
X976667Y977400D01*
X976792Y977108D01*
Y976067D01*
G01Y977108D02*
X978000Y977733D01*
G01Y980500D02*
X975500D01*
X977292Y978958D01*
Y981042D01*
G01X977625Y982183D02*
X977833Y982433D01*
X977958Y982725D01*
X978000Y983100D01*
X977917Y983475D01*
X977750Y983767D01*
X977458Y983975D01*
X977125Y984017D01*
X976792Y983933D01*
X976583Y983725D01*
X976417Y983433D01*
X976375Y983142D01*
X976417Y982850D01*
X976583Y982475D01*
X975500Y982600D01*
Y983725D01*
G01X953000Y977300D02*
X957000D01*
Y984700D01*
G01X985334Y976067D02*
X982834D01*
Y977108D01*
X982959Y977442D01*
X983126Y977650D01*
X983459Y977733D01*
X983792Y977650D01*
X984001Y977400D01*
X984126Y977108D01*
Y976067D01*
G01Y977108D02*
X985334Y977733D01*
G01Y980500D02*
X982834D01*
X984626Y978958D01*
Y981042D01*
G01X984292Y982308D02*
X984001Y982600D01*
X983834Y982850D01*
X983751Y983183D01*
X983834Y983475D01*
X984001Y983683D01*
X984251Y983850D01*
X984542Y983892D01*
X984792Y983850D01*
X985042Y983683D01*
X985251Y983433D01*
X985334Y983142D01*
X985251Y982808D01*
X985001Y982517D01*
X984626Y982350D01*
X984209Y982308D01*
X983667Y982392D01*
X983376Y982517D01*
X983084Y982725D01*
X982876Y983017D01*
X982834Y983308D01*
X982917Y983600D01*
X983126Y983808D01*
G01X962000Y977300D02*
X966000D01*
Y984700D01*
G01X974000Y976067D02*
X971500D01*
Y977108D01*
X971625Y977442D01*
X971792Y977650D01*
X972125Y977733D01*
X972458Y977650D01*
X972667Y977400D01*
X972792Y977108D01*
Y976067D01*
G01Y977108D02*
X974000Y977733D01*
G01Y980500D02*
X971500D01*
X973292Y978958D01*
Y981042D01*
G01X973708Y982392D02*
X973917Y982683D01*
X974000Y983017D01*
X973917Y983350D01*
X973667Y983642D01*
X973292Y983850D01*
X972917Y983933D01*
X972458D01*
X972083Y983850D01*
X971750Y983642D01*
X971583Y983392D01*
X971500Y983100D01*
X971583Y982767D01*
X971750Y982517D01*
X972000Y982350D01*
X972333Y982267D01*
X972625Y982350D01*
X972917Y982558D01*
X973083Y982808D01*
X973125Y983100D01*
X973042Y983433D01*
X972833Y983683D01*
X972458Y983933D01*
G01X952500Y984700D02*
X948500D01*
Y977300D01*
G01X981500Y976067D02*
X979000D01*
Y977108D01*
X979125Y977442D01*
X979292Y977650D01*
X979625Y977733D01*
X979958Y977650D01*
X980167Y977400D01*
X980292Y977108D01*
Y976067D01*
G01Y977108D02*
X981500Y977733D01*
G01X981125Y979083D02*
X981333Y979333D01*
X981458Y979625D01*
X981500Y980000D01*
X981417Y980375D01*
X981250Y980667D01*
X980958Y980875D01*
X980625Y980917D01*
X980292Y980833D01*
X980083Y980625D01*
X979917Y980333D01*
X979875Y980042D01*
X979917Y979750D01*
X980083Y979375D01*
X979000Y979500D01*
Y980625D01*
G01Y983100D02*
X979083Y982767D01*
X979292Y982517D01*
X979542Y982350D01*
X979875Y982225D01*
X980250Y982183D01*
X980625Y982225D01*
X980958Y982350D01*
X981208Y982517D01*
X981417Y982767D01*
X981500Y983100D01*
X981417Y983433D01*
X981208Y983683D01*
X980958Y983850D01*
X980625Y983975D01*
X980250Y984017D01*
X979875Y983975D01*
X979542Y983850D01*
X979292Y983683D01*
X979083Y983433D01*
X979000Y983100D01*
G01X961500Y984700D02*
X957500D01*
Y977300D01*
G01X970000Y976067D02*
X967500D01*
Y977108D01*
X967625Y977442D01*
X967792Y977650D01*
X968125Y977733D01*
X968458Y977650D01*
X968667Y977400D01*
X968792Y977108D01*
Y976067D01*
G01Y977108D02*
X970000Y977733D01*
G01X969625Y979083D02*
X969833Y979333D01*
X969958Y979625D01*
X970000Y980000D01*
X969917Y980375D01*
X969750Y980667D01*
X969458Y980875D01*
X969125Y980917D01*
X968792Y980833D01*
X968583Y980625D01*
X968417Y980333D01*
X968375Y980042D01*
X968417Y979750D01*
X968583Y979375D01*
X967500Y979500D01*
Y980625D01*
G01X967917Y982308D02*
X967667Y982558D01*
X967542Y982850D01*
X967500Y983183D01*
X967583Y983600D01*
X967792Y983892D01*
X968042Y983975D01*
X968292Y983933D01*
X968500Y983767D01*
X968917Y982933D01*
X969208Y982558D01*
X969625Y982308D01*
X970000Y982225D01*
Y983975D01*
G01X948000Y984700D02*
X944000D01*
Y977300D01*
G01X946219Y958698D02*
X943719D01*
Y959739D01*
X943844Y960073D01*
X944011Y960281D01*
X944344Y960364D01*
X944677Y960281D01*
X944886Y960031D01*
X945011Y959739D01*
Y958698D01*
G01Y959739D02*
X946219Y960364D01*
G01Y962631D02*
X943719D01*
X944219Y962131D01*
G01X946219D02*
Y963131D01*
G01X944136Y964939D02*
X943886Y965189D01*
X943761Y965481D01*
X943719Y965814D01*
X943802Y966231D01*
X944011Y966523D01*
X944261Y966606D01*
X944511Y966564D01*
X944719Y966398D01*
X945136Y965564D01*
X945427Y965189D01*
X945844Y964939D01*
X946219Y964856D01*
Y966606D01*
G01Y968831D02*
X946177Y969123D01*
X946052Y969456D01*
X945844Y969664D01*
X945552Y969748D01*
X945261Y969664D01*
X945011Y969414D01*
X944886Y969039D01*
Y968623D01*
X944802Y968373D01*
X944594Y968164D01*
X944302Y968081D01*
X944011Y968206D01*
X943802Y968498D01*
X943719Y968831D01*
X943802Y969164D01*
X944011Y969456D01*
X944302Y969581D01*
X944594Y969498D01*
X944802Y969289D01*
X944886Y969039D01*
Y968623D01*
X945011Y968248D01*
X945261Y967998D01*
X945552Y967914D01*
X945844Y967998D01*
X946052Y968206D01*
X946177Y968539D01*
X946219Y968831D01*
G01X943790Y948462D02*
X947790D01*
Y955862D01*
G01X959700Y1033367D02*
X957200D01*
Y1034408D01*
X957325Y1034742D01*
X957492Y1034950D01*
X957825Y1035033D01*
X958158Y1034950D01*
X958367Y1034700D01*
X958492Y1034408D01*
Y1033367D01*
G01Y1034408D02*
X959700Y1035033D01*
G01Y1037800D02*
X957200D01*
X958992Y1036258D01*
Y1038342D01*
G01X959700Y1040400D02*
X957200D01*
X957700Y1039900D01*
G01X959700D02*
Y1040900D01*
G01X953700Y1022100D02*
X957700D01*
Y1029500D01*
G01X955200Y1033367D02*
X952700D01*
Y1034408D01*
X952825Y1034742D01*
X952992Y1034950D01*
X953325Y1035033D01*
X953658Y1034950D01*
X953867Y1034700D01*
X953992Y1034408D01*
Y1033367D01*
G01Y1034408D02*
X955200Y1035033D01*
G01Y1037800D02*
X952700D01*
X954492Y1036258D01*
Y1038342D01*
G01X954700Y1039483D02*
X954992Y1039733D01*
X955158Y1040067D01*
X955200Y1040442D01*
X955158Y1040775D01*
X954950Y1041108D01*
X954700Y1041317D01*
X954450Y1041358D01*
X954158Y1041275D01*
X953950Y1040983D01*
X953867Y1040692D01*
Y1040317D01*
G01Y1040692D02*
X953742Y1040942D01*
X953533Y1041150D01*
X953283Y1041233D01*
X953033Y1041150D01*
X952825Y1040942D01*
X952700Y1040567D01*
X952742Y1040192D01*
X952908Y1039817D01*
G01X949200Y1022100D02*
X953200D01*
Y1029500D01*
G01X950700Y1033367D02*
X948200D01*
Y1034408D01*
X948325Y1034742D01*
X948492Y1034950D01*
X948825Y1035033D01*
X949158Y1034950D01*
X949367Y1034700D01*
X949492Y1034408D01*
Y1033367D01*
G01Y1034408D02*
X950700Y1035033D01*
G01Y1037800D02*
X948200D01*
X949992Y1036258D01*
Y1038342D01*
G01X950700Y1040317D02*
X950158Y1040400D01*
X949700Y1040525D01*
X949283Y1040692D01*
X948825Y1040900D01*
X948200Y1041233D01*
Y1039567D01*
G01X944700Y1022100D02*
X948700D01*
Y1029500D01*
G01X964400Y1033367D02*
X961900D01*
Y1034408D01*
X962025Y1034742D01*
X962192Y1034950D01*
X962525Y1035033D01*
X962858Y1034950D01*
X963067Y1034700D01*
X963192Y1034408D01*
Y1033367D01*
G01Y1034408D02*
X964400Y1035033D01*
G01Y1037800D02*
X961900D01*
X963692Y1036258D01*
Y1038342D01*
G01X964400Y1040400D02*
X964358Y1040692D01*
X964233Y1041025D01*
X964025Y1041233D01*
X963733Y1041317D01*
X963442Y1041233D01*
X963192Y1040983D01*
X963067Y1040608D01*
Y1040192D01*
X962983Y1039942D01*
X962775Y1039733D01*
X962483Y1039650D01*
X962192Y1039775D01*
X961983Y1040067D01*
X961900Y1040400D01*
X961983Y1040733D01*
X962192Y1041025D01*
X962483Y1041150D01*
X962775Y1041067D01*
X962983Y1040858D01*
X963067Y1040608D01*
Y1040192D01*
X963192Y1039817D01*
X963442Y1039567D01*
X963733Y1039483D01*
X964025Y1039567D01*
X964233Y1039775D01*
X964358Y1040108D01*
X964400Y1040400D01*
G01X962400Y1029500D02*
X958400D01*
Y1022100D01*
G01X969533Y1030500D02*
Y1028708D01*
X969700Y1028333D01*
X970033Y1028083D01*
X970450Y1028000D01*
X970867Y1028083D01*
X971200Y1028333D01*
X971367Y1028708D01*
Y1030500D01*
G01X972633Y1028375D02*
X972883Y1028167D01*
X973175Y1028042D01*
X973550Y1028000D01*
X973925Y1028083D01*
X974217Y1028250D01*
X974425Y1028542D01*
X974467Y1028875D01*
X974383Y1029208D01*
X974175Y1029417D01*
X973883Y1029583D01*
X973592Y1029625D01*
X973300Y1029583D01*
X972925Y1029417D01*
X973050Y1030500D01*
X974175D01*
G01X945850Y988000D02*
Y1009000D01*
X977500D01*
Y998000D01*
X945850D01*
G01Y1006650D02*
X949000Y1003500D01*
X945850Y1000350D01*
G01X982178Y1020824D02*
X982053Y1020574D01*
X981970Y1020282D01*
Y1019949D01*
X982095Y1019574D01*
X982303Y1019282D01*
X982553Y1019074D01*
X982970Y1018907D01*
X983345Y1018865D01*
X983720Y1018949D01*
X983970Y1019074D01*
X984220Y1019324D01*
X984387Y1019615D01*
X984470Y1019907D01*
Y1020199D01*
X984387Y1020490D01*
X984262Y1020740D01*
X984095Y1020949D01*
G01X984470Y1023007D02*
X981970D01*
X982470Y1022507D01*
G01X984470D02*
Y1023507D01*
G01Y1026024D02*
X983928Y1026107D01*
X983470Y1026232D01*
X983053Y1026399D01*
X982595Y1026607D01*
X981970Y1026940D01*
Y1025274D01*
G01X987202Y1021157D02*
X987077Y1020907D01*
X986994Y1020615D01*
Y1020282D01*
X987119Y1019907D01*
X987327Y1019615D01*
X987577Y1019407D01*
X987994Y1019240D01*
X988369Y1019198D01*
X988744Y1019282D01*
X988994Y1019407D01*
X989244Y1019657D01*
X989411Y1019948D01*
X989494Y1020240D01*
Y1020532D01*
X989411Y1020823D01*
X989286Y1021073D01*
X989119Y1021282D01*
G01X989494Y1023340D02*
X986994D01*
X987494Y1022840D01*
G01X989494D02*
Y1023840D01*
G01Y1026440D02*
X989452Y1026732D01*
X989327Y1027065D01*
X989119Y1027273D01*
X988827Y1027357D01*
X988536Y1027273D01*
X988286Y1027023D01*
X988161Y1026648D01*
Y1026232D01*
X988077Y1025982D01*
X987869Y1025773D01*
X987577Y1025690D01*
X987286Y1025815D01*
X987077Y1026107D01*
X986994Y1026440D01*
X987077Y1026773D01*
X987286Y1027065D01*
X987577Y1027190D01*
X987869Y1027107D01*
X988077Y1026898D01*
X988161Y1026648D01*
Y1026232D01*
X988286Y1025857D01*
X988536Y1025607D01*
X988827Y1025523D01*
X989119Y1025607D01*
X989327Y1025815D01*
X989452Y1026148D01*
X989494Y1026440D01*
G01X975729Y1152094D02*
Y1154594D01*
X976770D01*
X977104Y1154469D01*
X977312Y1154302D01*
X977395Y1153969D01*
X977312Y1153636D01*
X977062Y1153427D01*
X976770Y1153302D01*
X975729D01*
G01X976770D02*
X977395Y1152094D01*
G01X979662D02*
Y1154594D01*
X979162Y1154094D01*
G01Y1152094D02*
X980162D01*
G01X983262D02*
Y1154594D01*
X981720Y1152802D01*
X983804D01*
G01X974090Y1151500D02*
Y1155500D01*
X966690D01*
G01X984000Y1164483D02*
X985792D01*
X986167Y1164650D01*
X986417Y1164983D01*
X986500Y1165400D01*
X986417Y1165817D01*
X986167Y1166150D01*
X985792Y1166317D01*
X984000D01*
G01X986500Y1169000D02*
X984000D01*
X985792Y1167458D01*
Y1169542D01*
G01X986500Y1171517D02*
X985958Y1171600D01*
X985500Y1171725D01*
X985083Y1171892D01*
X984625Y1172100D01*
X984000Y1172433D01*
Y1170767D01*
G01X980555Y1175603D02*
Y1162203D01*
G01X970555Y1175603D02*
X980555D01*
G01X970555Y1162203D02*
Y1175603D01*
G01X980555Y1162203D02*
X970555D01*
G01X966042Y1172767D02*
X965917Y1172517D01*
X965834Y1172225D01*
Y1171892D01*
X965959Y1171517D01*
X966167Y1171225D01*
X966417Y1171017D01*
X966834Y1170850D01*
X967209Y1170808D01*
X967584Y1170892D01*
X967834Y1171017D01*
X968084Y1171267D01*
X968251Y1171558D01*
X968334Y1171850D01*
Y1172142D01*
X968251Y1172433D01*
X968126Y1172683D01*
X967959Y1172892D01*
G01X968334Y1174950D02*
X965834D01*
X966334Y1174450D01*
G01X968334D02*
Y1175450D01*
G01X967959Y1177133D02*
X968167Y1177383D01*
X968292Y1177675D01*
X968334Y1178050D01*
X968251Y1178425D01*
X968084Y1178717D01*
X967792Y1178925D01*
X967459Y1178967D01*
X967126Y1178883D01*
X966917Y1178675D01*
X966751Y1178383D01*
X966709Y1178092D01*
X966751Y1177800D01*
X966917Y1177425D01*
X965834Y1177550D01*
Y1178675D01*
G01X968042Y1180442D02*
X968251Y1180733D01*
X968334Y1181067D01*
X968251Y1181400D01*
X968001Y1181692D01*
X967626Y1181900D01*
X967251Y1181983D01*
X966792D01*
X966417Y1181900D01*
X966084Y1181692D01*
X965917Y1181442D01*
X965834Y1181150D01*
X965917Y1180817D01*
X966084Y1180567D01*
X966334Y1180400D01*
X966667Y1180317D01*
X966959Y1180400D01*
X967251Y1180608D01*
X967417Y1180858D01*
X967459Y1181150D01*
X967376Y1181483D01*
X967167Y1181733D01*
X966792Y1181983D01*
G01X993500Y1182617D02*
X991000D01*
Y1183658D01*
X991125Y1183992D01*
X991292Y1184200D01*
X991625Y1184283D01*
X991958Y1184200D01*
X992167Y1183950D01*
X992292Y1183658D01*
Y1182617D01*
G01Y1183658D02*
X993500Y1184283D01*
G01X993208Y1185842D02*
X993417Y1186133D01*
X993500Y1186467D01*
X993417Y1186800D01*
X993167Y1187092D01*
X992792Y1187300D01*
X992417Y1187383D01*
X991958D01*
X991583Y1187300D01*
X991250Y1187092D01*
X991083Y1186842D01*
X991000Y1186550D01*
X991083Y1186217D01*
X991250Y1185967D01*
X991500Y1185800D01*
X991833Y1185717D01*
X992125Y1185800D01*
X992417Y1186008D01*
X992583Y1186258D01*
X992625Y1186550D01*
X992542Y1186883D01*
X992333Y1187133D01*
X991958Y1187383D01*
G01X986208Y1184367D02*
X986083Y1184117D01*
X986000Y1183825D01*
Y1183492D01*
X986125Y1183117D01*
X986333Y1182825D01*
X986583Y1182617D01*
X987000Y1182450D01*
X987375Y1182408D01*
X987750Y1182492D01*
X988000Y1182617D01*
X988250Y1182867D01*
X988417Y1183158D01*
X988500Y1183450D01*
Y1183742D01*
X988417Y1184033D01*
X988292Y1184283D01*
X988125Y1184492D01*
G01X988500Y1186550D02*
X986000D01*
X986500Y1186050D01*
G01X988500D02*
Y1187050D01*
G01X949125Y1378357D02*
X945125D01*
Y1370957D01*
G01X949525D02*
X953525D01*
Y1378357D01*
G01X976012Y1371441D02*
X973512D01*
Y1372482D01*
X973637Y1372816D01*
X973804Y1373024D01*
X974137Y1373107D01*
X974470Y1373024D01*
X974679Y1372774D01*
X974804Y1372482D01*
Y1371441D01*
G01Y1372482D02*
X976012Y1373107D01*
G01Y1375374D02*
X973512D01*
X974012Y1374874D01*
G01X976012D02*
Y1375874D01*
G01X974970Y1377682D02*
X974679Y1377974D01*
X974512Y1378224D01*
X974429Y1378557D01*
X974512Y1378849D01*
X974679Y1379057D01*
X974929Y1379224D01*
X975220Y1379266D01*
X975470Y1379224D01*
X975720Y1379057D01*
X975929Y1378807D01*
X976012Y1378516D01*
X975929Y1378182D01*
X975679Y1377891D01*
X975304Y1377724D01*
X974887Y1377682D01*
X974345Y1377766D01*
X974054Y1377891D01*
X973762Y1378099D01*
X973554Y1378391D01*
X973512Y1378682D01*
X973595Y1378974D01*
X973804Y1379182D01*
G01X976012Y1381574D02*
X975970Y1381866D01*
X975845Y1382199D01*
X975637Y1382407D01*
X975345Y1382491D01*
X975054Y1382407D01*
X974804Y1382157D01*
X974679Y1381782D01*
Y1381366D01*
X974595Y1381116D01*
X974387Y1380907D01*
X974095Y1380824D01*
X973804Y1380949D01*
X973595Y1381241D01*
X973512Y1381574D01*
X973595Y1381907D01*
X973804Y1382199D01*
X974095Y1382324D01*
X974387Y1382241D01*
X974595Y1382032D01*
X974679Y1381782D01*
Y1381366D01*
X974804Y1380991D01*
X975054Y1380741D01*
X975345Y1380657D01*
X975637Y1380741D01*
X975845Y1380949D01*
X975970Y1381282D01*
X976012Y1381574D01*
G01X945159Y1359887D02*
X949159D01*
Y1367287D01*
G01X980725Y1371456D02*
X978225D01*
Y1372497D01*
X978350Y1372831D01*
X978517Y1373039D01*
X978850Y1373122D01*
X979183Y1373039D01*
X979392Y1372789D01*
X979517Y1372497D01*
Y1371456D01*
G01Y1372497D02*
X980725Y1373122D01*
G01Y1375389D02*
X978225D01*
X978725Y1374889D01*
G01X980725D02*
Y1375889D01*
G01Y1378489D02*
X980683Y1378781D01*
X980558Y1379114D01*
X980350Y1379322D01*
X980058Y1379406D01*
X979767Y1379322D01*
X979517Y1379072D01*
X979392Y1378697D01*
Y1378281D01*
X979308Y1378031D01*
X979100Y1377822D01*
X978808Y1377739D01*
X978517Y1377864D01*
X978308Y1378156D01*
X978225Y1378489D01*
X978308Y1378822D01*
X978517Y1379114D01*
X978808Y1379239D01*
X979100Y1379156D01*
X979308Y1378947D01*
X979392Y1378697D01*
Y1378281D01*
X979517Y1377906D01*
X979767Y1377656D01*
X980058Y1377572D01*
X980350Y1377656D01*
X980558Y1377864D01*
X980683Y1378197D01*
X980725Y1378489D01*
G01X978642Y1380797D02*
X978392Y1381047D01*
X978267Y1381339D01*
X978225Y1381672D01*
X978308Y1382089D01*
X978517Y1382381D01*
X978767Y1382464D01*
X979017Y1382422D01*
X979225Y1382256D01*
X979642Y1381422D01*
X979933Y1381047D01*
X980350Y1380797D01*
X980725Y1380714D01*
Y1382464D01*
G01X953872Y1367302D02*
X949872D01*
Y1359902D01*
G01X962335Y1371517D02*
X959835D01*
Y1372558D01*
X959960Y1372892D01*
X960127Y1373100D01*
X960460Y1373183D01*
X960793Y1373100D01*
X961002Y1372850D01*
X961127Y1372558D01*
Y1371517D01*
G01Y1372558D02*
X962335Y1373183D01*
G01Y1375450D02*
X959835D01*
X960335Y1374950D01*
G01X962335D02*
Y1375950D01*
G01X961293Y1377758D02*
X961002Y1378050D01*
X960835Y1378300D01*
X960752Y1378633D01*
X960835Y1378925D01*
X961002Y1379133D01*
X961252Y1379300D01*
X961543Y1379342D01*
X961793Y1379300D01*
X962043Y1379133D01*
X962252Y1378883D01*
X962335Y1378592D01*
X962252Y1378258D01*
X962002Y1377967D01*
X961627Y1377800D01*
X961210Y1377758D01*
X960668Y1377842D01*
X960377Y1377967D01*
X960085Y1378175D01*
X959877Y1378467D01*
X959835Y1378758D01*
X959918Y1379050D01*
X960127Y1379258D01*
G01X960252Y1380858D02*
X960002Y1381108D01*
X959877Y1381400D01*
X959835Y1381733D01*
X959918Y1382150D01*
X960127Y1382442D01*
X960377Y1382525D01*
X960627Y1382483D01*
X960835Y1382317D01*
X961252Y1381483D01*
X961543Y1381108D01*
X961960Y1380858D01*
X962335Y1380775D01*
Y1382525D01*
G01X966735Y1371523D02*
X964235D01*
Y1372564D01*
X964360Y1372898D01*
X964527Y1373106D01*
X964860Y1373189D01*
X965193Y1373106D01*
X965402Y1372856D01*
X965527Y1372564D01*
Y1371523D01*
G01Y1372564D02*
X966735Y1373189D01*
G01Y1375456D02*
X964235D01*
X964735Y1374956D01*
G01X966735D02*
Y1375956D01*
G01X965693Y1377764D02*
X965402Y1378056D01*
X965235Y1378306D01*
X965152Y1378639D01*
X965235Y1378931D01*
X965402Y1379139D01*
X965652Y1379306D01*
X965943Y1379348D01*
X966193Y1379306D01*
X966443Y1379139D01*
X966652Y1378889D01*
X966735Y1378598D01*
X966652Y1378264D01*
X966402Y1377973D01*
X966027Y1377806D01*
X965610Y1377764D01*
X965068Y1377848D01*
X964777Y1377973D01*
X964485Y1378181D01*
X964277Y1378473D01*
X964235Y1378764D01*
X964318Y1379056D01*
X964527Y1379264D01*
G01X966360Y1380739D02*
X966568Y1380989D01*
X966693Y1381281D01*
X966735Y1381656D01*
X966652Y1382031D01*
X966485Y1382323D01*
X966193Y1382531D01*
X965860Y1382573D01*
X965527Y1382489D01*
X965318Y1382281D01*
X965152Y1381989D01*
X965110Y1381698D01*
X965152Y1381406D01*
X965318Y1381031D01*
X964235Y1381156D01*
Y1382281D01*
G01X955923Y1374847D02*
X955798Y1374597D01*
X955715Y1374305D01*
Y1373972D01*
X955840Y1373597D01*
X956048Y1373305D01*
X956298Y1373097D01*
X956715Y1372930D01*
X957090Y1372888D01*
X957465Y1372972D01*
X957715Y1373097D01*
X957965Y1373347D01*
X958132Y1373638D01*
X958215Y1373930D01*
Y1374222D01*
X958132Y1374513D01*
X958007Y1374763D01*
X957840Y1374972D01*
G01X958215Y1377530D02*
X955715D01*
X957507Y1375988D01*
Y1378072D01*
G01X958215Y1380130D02*
X958173Y1380422D01*
X958048Y1380755D01*
X957840Y1380963D01*
X957548Y1381047D01*
X957257Y1380963D01*
X957007Y1380713D01*
X956882Y1380338D01*
Y1379922D01*
X956798Y1379672D01*
X956590Y1379463D01*
X956298Y1379380D01*
X956007Y1379505D01*
X955798Y1379797D01*
X955715Y1380130D01*
X955798Y1380463D01*
X956007Y1380755D01*
X956298Y1380880D01*
X956590Y1380797D01*
X956798Y1380588D01*
X956882Y1380338D01*
Y1379922D01*
X957007Y1379547D01*
X957257Y1379297D01*
X957548Y1379213D01*
X957840Y1379297D01*
X958048Y1379505D01*
X958173Y1379838D01*
X958215Y1380130D01*
G01X969440Y1374711D02*
X969315Y1374461D01*
X969232Y1374169D01*
Y1373836D01*
X969357Y1373461D01*
X969565Y1373169D01*
X969815Y1372961D01*
X970232Y1372794D01*
X970607Y1372752D01*
X970982Y1372836D01*
X971232Y1372961D01*
X971482Y1373211D01*
X971649Y1373502D01*
X971732Y1373794D01*
Y1374086D01*
X971649Y1374377D01*
X971524Y1374627D01*
X971357Y1374836D01*
G01Y1375977D02*
X971565Y1376227D01*
X971690Y1376519D01*
X971732Y1376894D01*
X971649Y1377269D01*
X971482Y1377561D01*
X971190Y1377769D01*
X970857Y1377811D01*
X970524Y1377727D01*
X970315Y1377519D01*
X970149Y1377227D01*
X970107Y1376936D01*
X970149Y1376644D01*
X970315Y1376269D01*
X969232Y1376394D01*
Y1377519D01*
G01Y1379994D02*
X969315Y1379661D01*
X969524Y1379411D01*
X969774Y1379244D01*
X970107Y1379119D01*
X970482Y1379077D01*
X970857Y1379119D01*
X971190Y1379244D01*
X971440Y1379411D01*
X971649Y1379661D01*
X971732Y1379994D01*
X971649Y1380327D01*
X971440Y1380577D01*
X971190Y1380744D01*
X970857Y1380869D01*
X970482Y1380911D01*
X970107Y1380869D01*
X969774Y1380744D01*
X969524Y1380577D01*
X969315Y1380327D01*
X969232Y1379994D01*
G01X947892Y1382214D02*
X945392D01*
Y1383255D01*
X945517Y1383589D01*
X945684Y1383797D01*
X946017Y1383880D01*
X946350Y1383797D01*
X946559Y1383547D01*
X946684Y1383255D01*
Y1382214D01*
G01Y1383255D02*
X947892Y1383880D01*
G01Y1386147D02*
X945392D01*
X945892Y1385647D01*
G01X947892D02*
Y1386647D01*
G01X947600Y1388539D02*
X947809Y1388830D01*
X947892Y1389164D01*
X947809Y1389497D01*
X947559Y1389789D01*
X947184Y1389997D01*
X946809Y1390080D01*
X946350D01*
X945975Y1389997D01*
X945642Y1389789D01*
X945475Y1389539D01*
X945392Y1389247D01*
X945475Y1388914D01*
X945642Y1388664D01*
X945892Y1388497D01*
X946225Y1388414D01*
X946517Y1388497D01*
X946809Y1388705D01*
X946975Y1388955D01*
X947017Y1389247D01*
X946934Y1389580D01*
X946725Y1389830D01*
X946350Y1390080D01*
G01X952292Y1382214D02*
X949792D01*
Y1383255D01*
X949917Y1383589D01*
X950084Y1383797D01*
X950417Y1383880D01*
X950750Y1383797D01*
X950959Y1383547D01*
X951084Y1383255D01*
Y1382214D01*
G01Y1383255D02*
X952292Y1383880D01*
G01X950209Y1385355D02*
X949959Y1385605D01*
X949834Y1385897D01*
X949792Y1386230D01*
X949875Y1386647D01*
X950084Y1386939D01*
X950334Y1387022D01*
X950584Y1386980D01*
X950792Y1386814D01*
X951209Y1385980D01*
X951500Y1385605D01*
X951917Y1385355D01*
X952292Y1385272D01*
Y1387022D01*
G01X951917Y1388330D02*
X952125Y1388580D01*
X952250Y1388872D01*
X952292Y1389247D01*
X952209Y1389622D01*
X952042Y1389914D01*
X951750Y1390122D01*
X951417Y1390164D01*
X951084Y1390080D01*
X950875Y1389872D01*
X950709Y1389580D01*
X950667Y1389289D01*
X950709Y1388997D01*
X950875Y1388622D01*
X949792Y1388747D01*
Y1389872D01*
G01X945834Y1477967D02*
X943334D01*
Y1479008D01*
X943459Y1479342D01*
X943626Y1479550D01*
X943959Y1479633D01*
X944292Y1479550D01*
X944501Y1479300D01*
X944626Y1479008D01*
Y1477967D01*
G01Y1479008D02*
X945834Y1479633D01*
G01Y1481900D02*
X943334D01*
X943834Y1481400D01*
G01X945834D02*
Y1482400D01*
G01Y1485000D02*
X943334D01*
X943834Y1484500D01*
G01X945834D02*
Y1485500D01*
G01X945459Y1487183D02*
X945667Y1487433D01*
X945792Y1487725D01*
X945834Y1488100D01*
X945751Y1488475D01*
X945584Y1488767D01*
X945292Y1488975D01*
X944959Y1489017D01*
X944626Y1488933D01*
X944417Y1488725D01*
X944251Y1488433D01*
X944209Y1488142D01*
X944251Y1487850D01*
X944417Y1487475D01*
X943334Y1487600D01*
Y1488725D01*
G01X945834Y1491200D02*
X945792Y1491492D01*
X945667Y1491825D01*
X945459Y1492033D01*
X945167Y1492117D01*
X944876Y1492033D01*
X944626Y1491783D01*
X944501Y1491408D01*
Y1490992D01*
X944417Y1490742D01*
X944209Y1490533D01*
X943917Y1490450D01*
X943626Y1490575D01*
X943417Y1490867D01*
X943334Y1491200D01*
X943417Y1491533D01*
X943626Y1491825D01*
X943917Y1491950D01*
X944209Y1491867D01*
X944417Y1491658D01*
X944501Y1491408D01*
Y1490992D01*
X944626Y1490617D01*
X944876Y1490367D01*
X945167Y1490283D01*
X945459Y1490367D01*
X945667Y1490575D01*
X945792Y1490908D01*
X945834Y1491200D01*
G01X948300Y1508400D02*
X944300D01*
Y1501000D01*
G01X950334Y1477967D02*
X947834D01*
Y1479008D01*
X947959Y1479342D01*
X948126Y1479550D01*
X948459Y1479633D01*
X948792Y1479550D01*
X949001Y1479300D01*
X949126Y1479008D01*
Y1477967D01*
G01Y1479008D02*
X950334Y1479633D01*
G01Y1481900D02*
X947834D01*
X948334Y1481400D01*
G01X950334D02*
Y1482400D01*
G01Y1485000D02*
X947834D01*
X948334Y1484500D01*
G01X950334D02*
Y1485500D01*
G01X949959Y1487183D02*
X950167Y1487433D01*
X950292Y1487725D01*
X950334Y1488100D01*
X950251Y1488475D01*
X950084Y1488767D01*
X949792Y1488975D01*
X949459Y1489017D01*
X949126Y1488933D01*
X948917Y1488725D01*
X948751Y1488433D01*
X948709Y1488142D01*
X948751Y1487850D01*
X948917Y1487475D01*
X947834Y1487600D01*
Y1488725D01*
G01X948251Y1490408D02*
X948001Y1490658D01*
X947876Y1490950D01*
X947834Y1491283D01*
X947917Y1491700D01*
X948126Y1491992D01*
X948376Y1492075D01*
X948626Y1492033D01*
X948834Y1491867D01*
X949251Y1491033D01*
X949542Y1490658D01*
X949959Y1490408D01*
X950334Y1490325D01*
Y1492075D01*
G01X948300Y1501000D02*
X952300D01*
Y1508400D01*
G01X965334Y1480517D02*
X962834D01*
Y1481558D01*
X962959Y1481892D01*
X963126Y1482100D01*
X963459Y1482183D01*
X963792Y1482100D01*
X964001Y1481850D01*
X964126Y1481558D01*
Y1480517D01*
G01Y1481558D02*
X965334Y1482183D01*
G01Y1484450D02*
X962834D01*
X963334Y1483950D01*
G01X965334D02*
Y1484950D01*
G01Y1488050D02*
X962834D01*
X964626Y1486508D01*
Y1488592D01*
G01X963251Y1489858D02*
X963001Y1490108D01*
X962876Y1490400D01*
X962834Y1490733D01*
X962917Y1491150D01*
X963126Y1491442D01*
X963376Y1491525D01*
X963626Y1491483D01*
X963834Y1491317D01*
X964251Y1490483D01*
X964542Y1490108D01*
X964959Y1489858D01*
X965334Y1489775D01*
Y1491525D01*
G01X967535Y1506752D02*
Y1501552D01*
G01X960535Y1506752D02*
Y1498952D01*
G01X967535Y1506752D02*
X960535D01*
G01X967535Y1493352D02*
Y1502052D01*
G01X960535Y1493352D02*
X967535D01*
G01X960535Y1499752D02*
Y1493352D01*
G01X956334Y1477467D02*
X953834D01*
Y1478508D01*
X953959Y1478842D01*
X954126Y1479050D01*
X954459Y1479133D01*
X954792Y1479050D01*
X955001Y1478800D01*
X955126Y1478508D01*
Y1477467D01*
G01Y1478508D02*
X956334Y1479133D01*
G01Y1481400D02*
X953834D01*
X954334Y1480900D01*
G01X956334D02*
Y1481900D01*
G01Y1484500D02*
X953834D01*
X954334Y1484000D01*
G01X956334D02*
Y1485000D01*
G01Y1487517D02*
X955792Y1487600D01*
X955334Y1487725D01*
X954917Y1487892D01*
X954459Y1488100D01*
X953834Y1488433D01*
Y1486767D01*
G01X956334Y1490617D02*
X955792Y1490700D01*
X955334Y1490825D01*
X954917Y1490992D01*
X954459Y1491200D01*
X953834Y1491533D01*
Y1489867D01*
G01X959786Y1513425D02*
Y1508225D01*
G01X952786Y1513425D02*
Y1505625D01*
G01X959786Y1513425D02*
X952786D01*
G01X959786Y1500025D02*
Y1508725D01*
G01X952786Y1500025D02*
X959786D01*
G01X952786Y1506425D02*
Y1500025D01*
G01X953850Y1520350D02*
Y1515350D01*
X948850D01*
G01X978350Y1487500D02*
X978017Y1487542D01*
X977725Y1487708D01*
X977475Y1487958D01*
X977308Y1488250D01*
X977225Y1488583D01*
Y1488917D01*
X977308Y1489250D01*
X977475Y1489542D01*
X977725Y1489792D01*
X978017Y1489958D01*
X978350Y1490000D01*
X978683Y1489958D01*
X978975Y1489792D01*
X979225Y1489542D01*
X979392Y1489250D01*
X979475Y1488917D01*
Y1488583D01*
X979392Y1488250D01*
X979225Y1487958D01*
X978975Y1487708D01*
X978683Y1487542D01*
X978350Y1487500D01*
G01X978683Y1488167D02*
X979183Y1487500D01*
G01X980658Y1489583D02*
X980908Y1489833D01*
X981200Y1489958D01*
X981533Y1490000D01*
X981950Y1489917D01*
X982242Y1489708D01*
X982325Y1489458D01*
X982283Y1489208D01*
X982117Y1489000D01*
X981283Y1488583D01*
X980908Y1488292D01*
X980658Y1487875D01*
X980575Y1487500D01*
X982325D01*
G01X983758Y1489583D02*
X984008Y1489833D01*
X984300Y1489958D01*
X984633Y1490000D01*
X985050Y1489917D01*
X985342Y1489708D01*
X985425Y1489458D01*
X985383Y1489208D01*
X985217Y1489000D01*
X984383Y1488583D01*
X984008Y1488292D01*
X983758Y1487875D01*
X983675Y1487500D01*
X985425D01*
G01X986733Y1487875D02*
X986983Y1487667D01*
X987275Y1487542D01*
X987650Y1487500D01*
X988025Y1487583D01*
X988317Y1487750D01*
X988525Y1488042D01*
X988567Y1488375D01*
X988483Y1488708D01*
X988275Y1488917D01*
X987983Y1489083D01*
X987692Y1489125D01*
X987400Y1489083D01*
X987025Y1488917D01*
X987150Y1490000D01*
X988275D01*
G01X971773Y1501712D02*
X985773D01*
G01X971773Y1514712D02*
Y1501712D01*
G01X985773Y1514712D02*
X971773D01*
G01X985773Y1501712D02*
Y1514712D01*
G01X986573Y1504512D02*
X990573D01*
Y1511912D01*
G01X976500Y1483467D02*
X974000D01*
Y1484508D01*
X974125Y1484842D01*
X974292Y1485050D01*
X974625Y1485133D01*
X974958Y1485050D01*
X975167Y1484800D01*
X975292Y1484508D01*
Y1483467D01*
G01Y1484508D02*
X976500Y1485133D01*
G01Y1487400D02*
X974000D01*
X974500Y1486900D01*
G01X976500D02*
Y1487900D01*
G01Y1490500D02*
X974000D01*
X974500Y1490000D01*
G01X976500D02*
Y1491000D01*
G01X976000Y1492683D02*
X976292Y1492933D01*
X976458Y1493267D01*
X976500Y1493642D01*
X976458Y1493975D01*
X976250Y1494308D01*
X976000Y1494517D01*
X975750Y1494558D01*
X975458Y1494475D01*
X975250Y1494183D01*
X975167Y1493892D01*
Y1493517D01*
G01Y1493892D02*
X975042Y1494142D01*
X974833Y1494350D01*
X974583Y1494433D01*
X974333Y1494350D01*
X974125Y1494142D01*
X974000Y1493767D01*
X974042Y1493392D01*
X974208Y1493017D01*
G01X976208Y1495992D02*
X976417Y1496283D01*
X976500Y1496617D01*
X976417Y1496950D01*
X976167Y1497242D01*
X975792Y1497450D01*
X975417Y1497533D01*
X974958D01*
X974583Y1497450D01*
X974250Y1497242D01*
X974083Y1496992D01*
X974000Y1496700D01*
X974083Y1496367D01*
X974250Y1496117D01*
X974500Y1495950D01*
X974833Y1495867D01*
X975125Y1495950D01*
X975417Y1496158D01*
X975583Y1496408D01*
X975625Y1496700D01*
X975542Y1497033D01*
X975333Y1497283D01*
X974958Y1497533D01*
G01X965488Y1522439D02*
X961488D01*
Y1515039D01*
G01X986503Y1516427D02*
Y1518927D01*
X987544D01*
X987878Y1518802D01*
X988086Y1518635D01*
X988169Y1518302D01*
X988086Y1517969D01*
X987836Y1517760D01*
X987544Y1517635D01*
X986503D01*
G01X987544D02*
X988169Y1516427D01*
G01X990436D02*
Y1518927D01*
X989936Y1518427D01*
G01Y1516427D02*
X990936D01*
G01X993536D02*
Y1518927D01*
X993036Y1518427D01*
G01Y1516427D02*
X994036D01*
G01X995719Y1516802D02*
X995969Y1516594D01*
X996261Y1516469D01*
X996636Y1516427D01*
X997011Y1516510D01*
X997303Y1516677D01*
X997511Y1516969D01*
X997553Y1517302D01*
X997469Y1517635D01*
X997261Y1517844D01*
X996969Y1518010D01*
X996678Y1518052D01*
X996386Y1518010D01*
X996011Y1517844D01*
X996136Y1518927D01*
X997261D01*
G01X999653Y1516427D02*
X999736Y1516969D01*
X999861Y1517427D01*
X1000028Y1517844D01*
X1000236Y1518302D01*
X1000569Y1518927D01*
X998903D01*
G01X950767Y1474459D02*
X950517Y1474584D01*
X950225Y1474667D01*
X949892D01*
X949517Y1474542D01*
X949225Y1474334D01*
X949017Y1474084D01*
X948850Y1473667D01*
X948808Y1473292D01*
X948892Y1472917D01*
X949017Y1472667D01*
X949267Y1472417D01*
X949558Y1472250D01*
X949850Y1472167D01*
X950142D01*
X950433Y1472250D01*
X950683Y1472375D01*
X950892Y1472542D01*
G01X952033D02*
X952283Y1472334D01*
X952575Y1472209D01*
X952950Y1472167D01*
X953325Y1472250D01*
X953617Y1472417D01*
X953825Y1472709D01*
X953867Y1473042D01*
X953783Y1473375D01*
X953575Y1473584D01*
X953283Y1473750D01*
X952992Y1473792D01*
X952700Y1473750D01*
X952325Y1473584D01*
X952450Y1474667D01*
X953575D01*
G01X955342Y1472459D02*
X955633Y1472250D01*
X955967Y1472167D01*
X956300Y1472250D01*
X956592Y1472500D01*
X956800Y1472875D01*
X956883Y1473250D01*
Y1473709D01*
X956800Y1474084D01*
X956592Y1474417D01*
X956342Y1474584D01*
X956050Y1474667D01*
X955717Y1474584D01*
X955467Y1474417D01*
X955300Y1474167D01*
X955217Y1473834D01*
X955300Y1473542D01*
X955508Y1473250D01*
X955758Y1473084D01*
X956050Y1473042D01*
X956383Y1473125D01*
X956633Y1473334D01*
X956883Y1473709D01*
G01X958358Y1473209D02*
X958650Y1473500D01*
X958900Y1473667D01*
X959233Y1473750D01*
X959525Y1473667D01*
X959733Y1473500D01*
X959900Y1473250D01*
X959942Y1472959D01*
X959900Y1472709D01*
X959733Y1472459D01*
X959483Y1472250D01*
X959192Y1472167D01*
X958858Y1472250D01*
X958567Y1472500D01*
X958400Y1472875D01*
X958358Y1473292D01*
X958442Y1473834D01*
X958567Y1474125D01*
X958775Y1474417D01*
X959067Y1474625D01*
X959358Y1474667D01*
X959650Y1474584D01*
X959858Y1474375D01*
G01X979767Y1495292D02*
X979517Y1495417D01*
X979225Y1495500D01*
X978892D01*
X978517Y1495375D01*
X978225Y1495167D01*
X978017Y1494917D01*
X977850Y1494500D01*
X977808Y1494125D01*
X977892Y1493750D01*
X978017Y1493500D01*
X978267Y1493250D01*
X978558Y1493083D01*
X978850Y1493000D01*
X979142D01*
X979433Y1493083D01*
X979683Y1493208D01*
X979892Y1493375D01*
G01X981033D02*
X981283Y1493167D01*
X981575Y1493042D01*
X981950Y1493000D01*
X982325Y1493083D01*
X982617Y1493250D01*
X982825Y1493542D01*
X982867Y1493875D01*
X982783Y1494208D01*
X982575Y1494417D01*
X982283Y1494583D01*
X981992Y1494625D01*
X981700Y1494583D01*
X981325Y1494417D01*
X981450Y1495500D01*
X982575D01*
G01X985050Y1493000D02*
X985342Y1493042D01*
X985675Y1493167D01*
X985883Y1493375D01*
X985967Y1493667D01*
X985883Y1493958D01*
X985633Y1494208D01*
X985258Y1494333D01*
X984842D01*
X984592Y1494417D01*
X984383Y1494625D01*
X984300Y1494917D01*
X984425Y1495208D01*
X984717Y1495417D01*
X985050Y1495500D01*
X985383Y1495417D01*
X985675Y1495208D01*
X985800Y1494917D01*
X985717Y1494625D01*
X985508Y1494417D01*
X985258Y1494333D01*
X984842D01*
X984467Y1494208D01*
X984217Y1493958D01*
X984133Y1493667D01*
X984217Y1493375D01*
X984425Y1493167D01*
X984758Y1493042D01*
X985050Y1493000D01*
G01X987233Y1493500D02*
X987483Y1493208D01*
X987817Y1493042D01*
X988192Y1493000D01*
X988525Y1493042D01*
X988858Y1493250D01*
X989067Y1493500D01*
X989108Y1493750D01*
X989025Y1494042D01*
X988733Y1494250D01*
X988442Y1494333D01*
X988067D01*
G01X988442D02*
X988692Y1494458D01*
X988900Y1494667D01*
X988983Y1494917D01*
X988900Y1495167D01*
X988692Y1495375D01*
X988317Y1495500D01*
X987942Y1495458D01*
X987567Y1495292D01*
G01X983280Y1517997D02*
X983155Y1517747D01*
X983072Y1517455D01*
Y1517122D01*
X983197Y1516747D01*
X983405Y1516455D01*
X983655Y1516247D01*
X984072Y1516080D01*
X984447Y1516038D01*
X984822Y1516122D01*
X985072Y1516247D01*
X985322Y1516497D01*
X985489Y1516788D01*
X985572Y1517080D01*
Y1517372D01*
X985489Y1517663D01*
X985364Y1517913D01*
X985197Y1518122D01*
G01X984530Y1519388D02*
X984239Y1519680D01*
X984072Y1519930D01*
X983989Y1520263D01*
X984072Y1520555D01*
X984239Y1520763D01*
X984489Y1520930D01*
X984780Y1520972D01*
X985030Y1520930D01*
X985280Y1520763D01*
X985489Y1520513D01*
X985572Y1520222D01*
X985489Y1519888D01*
X985239Y1519597D01*
X984864Y1519430D01*
X984447Y1519388D01*
X983905Y1519472D01*
X983614Y1519597D01*
X983322Y1519805D01*
X983114Y1520097D01*
X983072Y1520388D01*
X983155Y1520680D01*
X983364Y1520888D01*
G01X985572Y1523280D02*
X983072D01*
X983572Y1522780D01*
G01X985572D02*
Y1523780D01*
G01X983072Y1526380D02*
X983155Y1526047D01*
X983364Y1525797D01*
X983614Y1525630D01*
X983947Y1525505D01*
X984322Y1525463D01*
X984697Y1525505D01*
X985030Y1525630D01*
X985280Y1525797D01*
X985489Y1526047D01*
X985572Y1526380D01*
X985489Y1526713D01*
X985280Y1526963D01*
X985030Y1527130D01*
X984697Y1527255D01*
X984322Y1527297D01*
X983947Y1527255D01*
X983614Y1527130D01*
X983364Y1526963D01*
X983155Y1526713D01*
X983072Y1526380D01*
G01X972880Y1566654D02*
X970380D01*
Y1567695D01*
X970505Y1568029D01*
X970672Y1568237D01*
X971005Y1568320D01*
X971338Y1568237D01*
X971547Y1567987D01*
X971672Y1567695D01*
Y1566654D01*
G01Y1567695D02*
X972880Y1568320D01*
G01Y1570587D02*
X970380D01*
X970880Y1570087D01*
G01X972880D02*
Y1571087D01*
G01Y1573687D02*
X970380D01*
X970880Y1573187D01*
G01X972880D02*
Y1574187D01*
G01X971838Y1575995D02*
X971547Y1576287D01*
X971380Y1576537D01*
X971297Y1576870D01*
X971380Y1577162D01*
X971547Y1577370D01*
X971797Y1577537D01*
X972088Y1577579D01*
X972338Y1577537D01*
X972588Y1577370D01*
X972797Y1577120D01*
X972880Y1576829D01*
X972797Y1576495D01*
X972547Y1576204D01*
X972172Y1576037D01*
X971755Y1575995D01*
X971213Y1576079D01*
X970922Y1576204D01*
X970630Y1576412D01*
X970422Y1576704D01*
X970380Y1576995D01*
X970463Y1577287D01*
X970672Y1577495D01*
G01X972880Y1579887D02*
X970380D01*
X970880Y1579387D01*
G01X972880D02*
Y1580387D01*
G01X960000Y1555000D02*
X964000D01*
Y1562400D01*
G01X965485Y1562725D02*
Y1565225D01*
X966526D01*
X966860Y1565100D01*
X967068Y1564933D01*
X967151Y1564600D01*
X967068Y1564267D01*
X966818Y1564058D01*
X966526Y1563933D01*
X965485D01*
G01X966526D02*
X967151Y1562725D01*
G01X969418D02*
Y1565225D01*
X968918Y1564725D01*
G01Y1562725D02*
X969918D01*
G01X972518D02*
Y1565225D01*
X972018Y1564725D01*
G01Y1562725D02*
X973018D01*
G01X974826Y1563767D02*
X975118Y1564058D01*
X975368Y1564225D01*
X975701Y1564308D01*
X975993Y1564225D01*
X976201Y1564058D01*
X976368Y1563808D01*
X976410Y1563517D01*
X976368Y1563267D01*
X976201Y1563017D01*
X975951Y1562808D01*
X975660Y1562725D01*
X975326Y1562808D01*
X975035Y1563058D01*
X974868Y1563433D01*
X974826Y1563850D01*
X974910Y1564392D01*
X975035Y1564683D01*
X975243Y1564975D01*
X975535Y1565183D01*
X975826Y1565225D01*
X976118Y1565142D01*
X976326Y1564933D01*
G01X978718Y1565225D02*
X978385Y1565142D01*
X978135Y1564933D01*
X977968Y1564683D01*
X977843Y1564350D01*
X977801Y1563975D01*
X977843Y1563600D01*
X977968Y1563267D01*
X978135Y1563017D01*
X978385Y1562808D01*
X978718Y1562725D01*
X979051Y1562808D01*
X979301Y1563017D01*
X979468Y1563267D01*
X979593Y1563600D01*
X979635Y1563975D01*
X979593Y1564350D01*
X979468Y1564683D01*
X979301Y1564933D01*
X979051Y1565142D01*
X978718Y1565225D01*
G01X956300Y1554700D02*
Y1550700D01*
X963700D01*
G01X947000Y1555000D02*
X951000D01*
Y1562400D01*
G01X950700Y1550700D02*
Y1554700D01*
X943300D01*
G01X983324Y1551197D02*
Y1553697D01*
X984365D01*
X984699Y1553572D01*
X984907Y1553405D01*
X984990Y1553072D01*
X984907Y1552739D01*
X984657Y1552530D01*
X984365Y1552405D01*
X983324D01*
G01X984365D02*
X984990Y1551197D01*
G01X987257D02*
Y1553697D01*
X986757Y1553197D01*
G01Y1551197D02*
X987757D01*
G01X990357D02*
Y1553697D01*
X989857Y1553197D01*
G01Y1551197D02*
X990857D01*
G01X992665Y1552239D02*
X992957Y1552530D01*
X993207Y1552697D01*
X993540Y1552780D01*
X993832Y1552697D01*
X994040Y1552530D01*
X994207Y1552280D01*
X994249Y1551989D01*
X994207Y1551739D01*
X994040Y1551489D01*
X993790Y1551280D01*
X993499Y1551197D01*
X993165Y1551280D01*
X992874Y1551530D01*
X992707Y1551905D01*
X992665Y1552322D01*
X992749Y1552864D01*
X992874Y1553155D01*
X993082Y1553447D01*
X993374Y1553655D01*
X993665Y1553697D01*
X993957Y1553614D01*
X994165Y1553405D01*
G01X996474Y1551197D02*
X996557Y1551739D01*
X996682Y1552197D01*
X996849Y1552614D01*
X997057Y1553072D01*
X997390Y1553697D01*
X995724D01*
G01X981913Y1551466D02*
Y1555466D01*
X974513D01*
G01X988220Y1555100D02*
X985720D01*
Y1556141D01*
X985845Y1556475D01*
X986012Y1556683D01*
X986345Y1556766D01*
X986678Y1556683D01*
X986887Y1556433D01*
X987012Y1556141D01*
Y1555100D01*
G01Y1556141D02*
X988220Y1556766D01*
G01Y1559033D02*
X985720D01*
X986220Y1558533D01*
G01X988220D02*
Y1559533D01*
G01Y1562133D02*
X985720D01*
X986220Y1561633D01*
G01X988220D02*
Y1562633D01*
G01Y1565150D02*
X987678Y1565233D01*
X987220Y1565358D01*
X986803Y1565525D01*
X986345Y1565733D01*
X985720Y1566066D01*
Y1564400D01*
G01Y1568333D02*
X985803Y1568000D01*
X986012Y1567750D01*
X986262Y1567583D01*
X986595Y1567458D01*
X986970Y1567416D01*
X987345Y1567458D01*
X987678Y1567583D01*
X987928Y1567750D01*
X988137Y1568000D01*
X988220Y1568333D01*
X988137Y1568666D01*
X987928Y1568916D01*
X987678Y1569083D01*
X987345Y1569208D01*
X986970Y1569250D01*
X986595Y1569208D01*
X986262Y1569083D01*
X986012Y1568916D01*
X985803Y1568666D01*
X985720Y1568333D01*
G01X970413Y1551466D02*
X974413D01*
Y1558866D01*
G01X983324Y1547197D02*
Y1549697D01*
X984365D01*
X984699Y1549572D01*
X984907Y1549405D01*
X984990Y1549072D01*
X984907Y1548739D01*
X984657Y1548530D01*
X984365Y1548405D01*
X983324D01*
G01X984365D02*
X984990Y1547197D01*
G01X987257D02*
Y1549697D01*
X986757Y1549197D01*
G01Y1547197D02*
X987757D01*
G01X990357D02*
Y1549697D01*
X989857Y1549197D01*
G01Y1547197D02*
X990857D01*
G01X992665Y1548239D02*
X992957Y1548530D01*
X993207Y1548697D01*
X993540Y1548780D01*
X993832Y1548697D01*
X994040Y1548530D01*
X994207Y1548280D01*
X994249Y1547989D01*
X994207Y1547739D01*
X994040Y1547489D01*
X993790Y1547280D01*
X993499Y1547197D01*
X993165Y1547280D01*
X992874Y1547530D01*
X992707Y1547905D01*
X992665Y1548322D01*
X992749Y1548864D01*
X992874Y1549155D01*
X993082Y1549447D01*
X993374Y1549655D01*
X993665Y1549697D01*
X993957Y1549614D01*
X994165Y1549405D01*
G01X996557Y1547197D02*
X996849Y1547239D01*
X997182Y1547364D01*
X997390Y1547572D01*
X997474Y1547864D01*
X997390Y1548155D01*
X997140Y1548405D01*
X996765Y1548530D01*
X996349D01*
X996099Y1548614D01*
X995890Y1548822D01*
X995807Y1549114D01*
X995932Y1549405D01*
X996224Y1549614D01*
X996557Y1549697D01*
X996890Y1549614D01*
X997182Y1549405D01*
X997307Y1549114D01*
X997224Y1548822D01*
X997015Y1548614D01*
X996765Y1548530D01*
X996349D01*
X995974Y1548405D01*
X995724Y1548155D01*
X995640Y1547864D01*
X995724Y1547572D01*
X995932Y1547364D01*
X996265Y1547239D01*
X996557Y1547197D01*
G01X981913Y1547366D02*
Y1551366D01*
X974513D01*
G01X982104Y1532878D02*
X979604D01*
Y1533919D01*
X979729Y1534253D01*
X979896Y1534461D01*
X980229Y1534544D01*
X980562Y1534461D01*
X980771Y1534211D01*
X980896Y1533919D01*
Y1532878D01*
G01Y1533919D02*
X982104Y1534544D01*
G01Y1536811D02*
X979604D01*
X980104Y1536311D01*
G01X982104D02*
Y1537311D01*
G01Y1539911D02*
X979604D01*
X980104Y1539411D01*
G01X982104D02*
Y1540411D01*
G01Y1542928D02*
X981562Y1543011D01*
X981104Y1543136D01*
X980687Y1543303D01*
X980229Y1543511D01*
X979604Y1543844D01*
Y1542178D01*
G01X982104Y1546111D02*
X979604D01*
X980104Y1545611D01*
G01X982104D02*
Y1546611D01*
G01X974413Y1551366D02*
X970413D01*
Y1543966D01*
G01X955950Y1532152D02*
X952950D01*
G01X954950Y1522312D02*
X952950D01*
G01X986703Y1527827D02*
Y1530327D01*
X987744D01*
X988078Y1530202D01*
X988286Y1530035D01*
X988369Y1529702D01*
X988286Y1529369D01*
X988036Y1529160D01*
X987744Y1529035D01*
X986703D01*
G01X987744D02*
X988369Y1527827D01*
G01X990636D02*
Y1530327D01*
X990136Y1529827D01*
G01Y1527827D02*
X991136D01*
G01X993736D02*
Y1530327D01*
X993236Y1529827D01*
G01Y1527827D02*
X994236D01*
G01X997336D02*
Y1530327D01*
X995794Y1528535D01*
X997878D01*
G01X999936Y1527827D02*
Y1530327D01*
X999436Y1529827D01*
G01Y1527827D02*
X1000436D01*
G01X970232Y1536282D02*
Y1540282D01*
X962832D01*
G01X986786Y1520397D02*
Y1522897D01*
X987827D01*
X988161Y1522772D01*
X988369Y1522605D01*
X988452Y1522272D01*
X988369Y1521939D01*
X988119Y1521730D01*
X987827Y1521605D01*
X986786D01*
G01X987827D02*
X988452Y1520397D01*
G01X990719D02*
Y1522897D01*
X990219Y1522397D01*
G01Y1520397D02*
X991219D01*
G01X993819D02*
Y1522897D01*
X993319Y1522397D01*
G01Y1520397D02*
X994319D01*
G01X996002Y1520772D02*
X996252Y1520564D01*
X996544Y1520439D01*
X996919Y1520397D01*
X997294Y1520480D01*
X997586Y1520647D01*
X997794Y1520939D01*
X997836Y1521272D01*
X997752Y1521605D01*
X997544Y1521814D01*
X997252Y1521980D01*
X996961Y1522022D01*
X996669Y1521980D01*
X996294Y1521814D01*
X996419Y1522897D01*
X997544D01*
G01X999102Y1520772D02*
X999352Y1520564D01*
X999644Y1520439D01*
X1000019Y1520397D01*
X1000394Y1520480D01*
X1000686Y1520647D01*
X1000894Y1520939D01*
X1000936Y1521272D01*
X1000852Y1521605D01*
X1000644Y1521814D01*
X1000352Y1521980D01*
X1000061Y1522022D01*
X999769Y1521980D01*
X999394Y1521814D01*
X999519Y1522897D01*
X1000644D01*
G01X973200Y1527200D02*
Y1531200D01*
X965800D01*
G01X973200Y1523200D02*
Y1527200D01*
X965800D01*
G01X975691Y1534607D02*
X975566Y1534357D01*
X975483Y1534065D01*
Y1533732D01*
X975608Y1533357D01*
X975816Y1533065D01*
X976066Y1532857D01*
X976483Y1532690D01*
X976858Y1532648D01*
X977233Y1532732D01*
X977483Y1532857D01*
X977733Y1533107D01*
X977900Y1533398D01*
X977983Y1533690D01*
Y1533982D01*
X977900Y1534273D01*
X977775Y1534523D01*
X977608Y1534732D01*
G01Y1535873D02*
X977816Y1536123D01*
X977941Y1536415D01*
X977983Y1536790D01*
X977900Y1537165D01*
X977733Y1537457D01*
X977441Y1537665D01*
X977108Y1537707D01*
X976775Y1537623D01*
X976566Y1537415D01*
X976400Y1537123D01*
X976358Y1536832D01*
X976400Y1536540D01*
X976566Y1536165D01*
X975483Y1536290D01*
Y1537415D01*
G01X977691Y1539182D02*
X977900Y1539473D01*
X977983Y1539807D01*
X977900Y1540140D01*
X977650Y1540432D01*
X977275Y1540640D01*
X976900Y1540723D01*
X976441D01*
X976066Y1540640D01*
X975733Y1540432D01*
X975566Y1540182D01*
X975483Y1539890D01*
X975566Y1539557D01*
X975733Y1539307D01*
X975983Y1539140D01*
X976316Y1539057D01*
X976608Y1539140D01*
X976900Y1539348D01*
X977066Y1539598D01*
X977108Y1539890D01*
X977025Y1540223D01*
X976816Y1540473D01*
X976441Y1540723D01*
G01X977608Y1542073D02*
X977816Y1542323D01*
X977941Y1542615D01*
X977983Y1542990D01*
X977900Y1543365D01*
X977733Y1543657D01*
X977441Y1543865D01*
X977108Y1543907D01*
X976775Y1543823D01*
X976566Y1543615D01*
X976400Y1543323D01*
X976358Y1543032D01*
X976400Y1542740D01*
X976566Y1542365D01*
X975483Y1542490D01*
Y1543615D01*
G01X981913Y1558761D02*
X981788Y1558511D01*
X981705Y1558219D01*
Y1557886D01*
X981830Y1557511D01*
X982038Y1557219D01*
X982288Y1557011D01*
X982705Y1556844D01*
X983080Y1556802D01*
X983455Y1556886D01*
X983705Y1557011D01*
X983955Y1557261D01*
X984122Y1557552D01*
X984205Y1557844D01*
Y1558136D01*
X984122Y1558427D01*
X983997Y1558677D01*
X983830Y1558886D01*
G01Y1560027D02*
X984038Y1560277D01*
X984163Y1560569D01*
X984205Y1560944D01*
X984122Y1561319D01*
X983955Y1561611D01*
X983663Y1561819D01*
X983330Y1561861D01*
X982997Y1561777D01*
X982788Y1561569D01*
X982622Y1561277D01*
X982580Y1560986D01*
X982622Y1560694D01*
X982788Y1560319D01*
X981705Y1560444D01*
Y1561569D01*
G01X983913Y1563336D02*
X984122Y1563627D01*
X984205Y1563961D01*
X984122Y1564294D01*
X983872Y1564586D01*
X983497Y1564794D01*
X983122Y1564877D01*
X982663D01*
X982288Y1564794D01*
X981955Y1564586D01*
X981788Y1564336D01*
X981705Y1564044D01*
X981788Y1563711D01*
X981955Y1563461D01*
X982205Y1563294D01*
X982538Y1563211D01*
X982830Y1563294D01*
X983122Y1563502D01*
X983288Y1563752D01*
X983330Y1564044D01*
X983247Y1564377D01*
X983038Y1564627D01*
X982663Y1564877D01*
G01X984205Y1567644D02*
X981705D01*
X983497Y1566102D01*
Y1568186D01*
G01X988503Y1526619D02*
X988253Y1526744D01*
X987961Y1526827D01*
X987628D01*
X987253Y1526702D01*
X986961Y1526494D01*
X986753Y1526244D01*
X986586Y1525827D01*
X986544Y1525452D01*
X986628Y1525077D01*
X986753Y1524827D01*
X987003Y1524577D01*
X987294Y1524410D01*
X987586Y1524327D01*
X987878D01*
X988169Y1524410D01*
X988419Y1524535D01*
X988628Y1524702D01*
G01X989769D02*
X990019Y1524494D01*
X990311Y1524369D01*
X990686Y1524327D01*
X991061Y1524410D01*
X991353Y1524577D01*
X991561Y1524869D01*
X991603Y1525202D01*
X991519Y1525535D01*
X991311Y1525744D01*
X991019Y1525910D01*
X990728Y1525952D01*
X990436Y1525910D01*
X990061Y1525744D01*
X990186Y1526827D01*
X991311D01*
G01X993786Y1524327D02*
X994078Y1524369D01*
X994411Y1524494D01*
X994619Y1524702D01*
X994703Y1524994D01*
X994619Y1525285D01*
X994369Y1525535D01*
X993994Y1525660D01*
X993578D01*
X993328Y1525744D01*
X993119Y1525952D01*
X993036Y1526244D01*
X993161Y1526535D01*
X993453Y1526744D01*
X993786Y1526827D01*
X994119Y1526744D01*
X994411Y1526535D01*
X994536Y1526244D01*
X994453Y1525952D01*
X994244Y1525744D01*
X993994Y1525660D01*
X993578D01*
X993203Y1525535D01*
X992953Y1525285D01*
X992869Y1524994D01*
X992953Y1524702D01*
X993161Y1524494D01*
X993494Y1524369D01*
X993786Y1524327D01*
G01X995969Y1524702D02*
X996219Y1524494D01*
X996511Y1524369D01*
X996886Y1524327D01*
X997261Y1524410D01*
X997553Y1524577D01*
X997761Y1524869D01*
X997803Y1525202D01*
X997719Y1525535D01*
X997511Y1525744D01*
X997219Y1525910D01*
X996928Y1525952D01*
X996636Y1525910D01*
X996261Y1525744D01*
X996386Y1526827D01*
X997511D01*
G01X952141Y1575048D02*
X949641D01*
Y1576089D01*
X949766Y1576423D01*
X949933Y1576631D01*
X950266Y1576714D01*
X950599Y1576631D01*
X950808Y1576381D01*
X950933Y1576089D01*
Y1575048D01*
G01Y1576089D02*
X952141Y1576714D01*
G01Y1578981D02*
X949641D01*
X950141Y1578481D01*
G01X952141D02*
Y1579481D01*
G01Y1582081D02*
X949641D01*
X950141Y1581581D01*
G01X952141D02*
Y1582581D01*
G01X951099Y1584389D02*
X950808Y1584681D01*
X950641Y1584931D01*
X950558Y1585264D01*
X950641Y1585556D01*
X950808Y1585764D01*
X951058Y1585931D01*
X951349Y1585973D01*
X951599Y1585931D01*
X951849Y1585764D01*
X952058Y1585514D01*
X952141Y1585223D01*
X952058Y1584889D01*
X951808Y1584598D01*
X951433Y1584431D01*
X951016Y1584389D01*
X950474Y1584473D01*
X950183Y1584598D01*
X949891Y1584806D01*
X949683Y1585098D01*
X949641Y1585389D01*
X949724Y1585681D01*
X949933Y1585889D01*
G01X951641Y1587364D02*
X951933Y1587614D01*
X952099Y1587948D01*
X952141Y1588323D01*
X952099Y1588656D01*
X951891Y1588989D01*
X951641Y1589198D01*
X951391Y1589239D01*
X951099Y1589156D01*
X950891Y1588864D01*
X950808Y1588573D01*
Y1588198D01*
G01Y1588573D02*
X950683Y1588823D01*
X950474Y1589031D01*
X950224Y1589114D01*
X949974Y1589031D01*
X949766Y1588823D01*
X949641Y1588448D01*
X949683Y1588073D01*
X949849Y1587698D01*
G01X944911Y1570757D02*
Y1573257D01*
X945952D01*
X946286Y1573132D01*
X946494Y1572965D01*
X946577Y1572632D01*
X946494Y1572299D01*
X946244Y1572090D01*
X945952Y1571965D01*
X944911D01*
G01X945952D02*
X946577Y1570757D01*
G01X948844D02*
Y1573257D01*
X948344Y1572757D01*
G01Y1570757D02*
X949344D01*
G01X951944D02*
Y1573257D01*
X951444Y1572757D01*
G01Y1570757D02*
X952444D01*
G01X954252Y1571799D02*
X954544Y1572090D01*
X954794Y1572257D01*
X955127Y1572340D01*
X955419Y1572257D01*
X955627Y1572090D01*
X955794Y1571840D01*
X955836Y1571549D01*
X955794Y1571299D01*
X955627Y1571049D01*
X955377Y1570840D01*
X955086Y1570757D01*
X954752Y1570840D01*
X954461Y1571090D01*
X954294Y1571465D01*
X954252Y1571882D01*
X954336Y1572424D01*
X954461Y1572715D01*
X954669Y1573007D01*
X954961Y1573215D01*
X955252Y1573257D01*
X955544Y1573174D01*
X955752Y1572965D01*
G01X957352Y1572840D02*
X957602Y1573090D01*
X957894Y1573215D01*
X958227Y1573257D01*
X958644Y1573174D01*
X958936Y1572965D01*
X959019Y1572715D01*
X958977Y1572465D01*
X958811Y1572257D01*
X957977Y1571840D01*
X957602Y1571549D01*
X957352Y1571132D01*
X957269Y1570757D01*
X959019D01*
G01X960910Y1569559D02*
X960785Y1569309D01*
X960702Y1569017D01*
Y1568684D01*
X960827Y1568309D01*
X961035Y1568017D01*
X961285Y1567809D01*
X961702Y1567642D01*
X962077Y1567600D01*
X962452Y1567684D01*
X962702Y1567809D01*
X962952Y1568059D01*
X963119Y1568350D01*
X963202Y1568642D01*
Y1568934D01*
X963119Y1569225D01*
X962994Y1569475D01*
X962827Y1569684D01*
G01Y1570825D02*
X963035Y1571075D01*
X963160Y1571367D01*
X963202Y1571742D01*
X963119Y1572117D01*
X962952Y1572409D01*
X962660Y1572617D01*
X962327Y1572659D01*
X961994Y1572575D01*
X961785Y1572367D01*
X961619Y1572075D01*
X961577Y1571784D01*
X961619Y1571492D01*
X961785Y1571117D01*
X960702Y1571242D01*
Y1572367D01*
G01X962910Y1574134D02*
X963119Y1574425D01*
X963202Y1574759D01*
X963119Y1575092D01*
X962869Y1575384D01*
X962494Y1575592D01*
X962119Y1575675D01*
X961660D01*
X961285Y1575592D01*
X960952Y1575384D01*
X960785Y1575134D01*
X960702Y1574842D01*
X960785Y1574509D01*
X960952Y1574259D01*
X961202Y1574092D01*
X961535Y1574009D01*
X961827Y1574092D01*
X962119Y1574300D01*
X962285Y1574550D01*
X962327Y1574842D01*
X962244Y1575175D01*
X962035Y1575425D01*
X961660Y1575675D01*
G01X963202Y1577942D02*
X960702D01*
X961202Y1577442D01*
G01X963202D02*
Y1578442D01*
G01X945372Y1576900D02*
X945247Y1576650D01*
X945164Y1576358D01*
Y1576025D01*
X945289Y1575650D01*
X945497Y1575358D01*
X945747Y1575150D01*
X946164Y1574983D01*
X946539Y1574941D01*
X946914Y1575025D01*
X947164Y1575150D01*
X947414Y1575400D01*
X947581Y1575691D01*
X947664Y1575983D01*
Y1576275D01*
X947581Y1576566D01*
X947456Y1576816D01*
X947289Y1577025D01*
G01Y1578166D02*
X947497Y1578416D01*
X947622Y1578708D01*
X947664Y1579083D01*
X947581Y1579458D01*
X947414Y1579750D01*
X947122Y1579958D01*
X946789Y1580000D01*
X946456Y1579916D01*
X946247Y1579708D01*
X946081Y1579416D01*
X946039Y1579125D01*
X946081Y1578833D01*
X946247Y1578458D01*
X945164Y1578583D01*
Y1579708D01*
G01X947372Y1581475D02*
X947581Y1581766D01*
X947664Y1582100D01*
X947581Y1582433D01*
X947331Y1582725D01*
X946956Y1582933D01*
X946581Y1583016D01*
X946122D01*
X945747Y1582933D01*
X945414Y1582725D01*
X945247Y1582475D01*
X945164Y1582183D01*
X945247Y1581850D01*
X945414Y1581600D01*
X945664Y1581433D01*
X945997Y1581350D01*
X946289Y1581433D01*
X946581Y1581641D01*
X946747Y1581891D01*
X946789Y1582183D01*
X946706Y1582516D01*
X946497Y1582766D01*
X946122Y1583016D01*
G01X945164Y1585283D02*
X945247Y1584950D01*
X945456Y1584700D01*
X945706Y1584533D01*
X946039Y1584408D01*
X946414Y1584366D01*
X946789Y1584408D01*
X947122Y1584533D01*
X947372Y1584700D01*
X947581Y1584950D01*
X947664Y1585283D01*
X947581Y1585616D01*
X947372Y1585866D01*
X947122Y1586033D01*
X946789Y1586158D01*
X946414Y1586200D01*
X946039Y1586158D01*
X945706Y1586033D01*
X945456Y1585866D01*
X945247Y1585616D01*
X945164Y1585283D01*
G01X965979Y1570283D02*
X965854Y1570033D01*
X965771Y1569741D01*
Y1569408D01*
X965896Y1569033D01*
X966104Y1568741D01*
X966354Y1568533D01*
X966771Y1568366D01*
X967146Y1568324D01*
X967521Y1568408D01*
X967771Y1568533D01*
X968021Y1568783D01*
X968188Y1569074D01*
X968271Y1569366D01*
Y1569658D01*
X968188Y1569949D01*
X968063Y1570199D01*
X967896Y1570408D01*
G01Y1571549D02*
X968104Y1571799D01*
X968229Y1572091D01*
X968271Y1572466D01*
X968188Y1572841D01*
X968021Y1573133D01*
X967729Y1573341D01*
X967396Y1573383D01*
X967063Y1573299D01*
X966854Y1573091D01*
X966688Y1572799D01*
X966646Y1572508D01*
X966688Y1572216D01*
X966854Y1571841D01*
X965771Y1571966D01*
Y1573091D01*
G01X968271Y1575566D02*
X968229Y1575858D01*
X968104Y1576191D01*
X967896Y1576399D01*
X967604Y1576483D01*
X967313Y1576399D01*
X967063Y1576149D01*
X966938Y1575774D01*
Y1575358D01*
X966854Y1575108D01*
X966646Y1574899D01*
X966354Y1574816D01*
X966063Y1574941D01*
X965854Y1575233D01*
X965771Y1575566D01*
X965854Y1575899D01*
X966063Y1576191D01*
X966354Y1576316D01*
X966646Y1576233D01*
X966854Y1576024D01*
X966938Y1575774D01*
Y1575358D01*
X967063Y1574983D01*
X967313Y1574733D01*
X967604Y1574649D01*
X967896Y1574733D01*
X968104Y1574941D01*
X968229Y1575274D01*
X968271Y1575566D01*
G01X967979Y1577958D02*
X968188Y1578249D01*
X968271Y1578583D01*
X968188Y1578916D01*
X967938Y1579208D01*
X967563Y1579416D01*
X967188Y1579499D01*
X966729D01*
X966354Y1579416D01*
X966021Y1579208D01*
X965854Y1578958D01*
X965771Y1578666D01*
X965854Y1578333D01*
X966021Y1578083D01*
X966271Y1577916D01*
X966604Y1577833D01*
X966896Y1577916D01*
X967188Y1578124D01*
X967354Y1578374D01*
X967396Y1578666D01*
X967313Y1578999D01*
X967104Y1579249D01*
X966729Y1579499D01*
G01X1028990Y1587057D02*
Y1583057D01*
X1027390D01*
X1026857Y1583257D01*
X1026457Y1583724D01*
X1026324Y1584257D01*
X1026457Y1584790D01*
X1026790Y1585190D01*
X1027390Y1585390D01*
X1028990D01*
G01X1023990Y1587057D02*
Y1584390D01*
G01Y1584924D02*
X1023657Y1584657D01*
X1023324Y1584457D01*
X1022857Y1584390D01*
X1022524Y1584457D01*
X1022124Y1584657D01*
G01X1019457Y1585257D02*
X1017324D01*
X1017524Y1584790D01*
X1017857Y1584524D01*
X1018324Y1584390D01*
X1018790Y1584457D01*
X1019190Y1584657D01*
X1019457Y1585124D01*
X1019590Y1585524D01*
Y1585924D01*
X1019457Y1586324D01*
X1019124Y1586724D01*
X1018724Y1586990D01*
X1018257Y1587057D01*
X1017790Y1586924D01*
X1017324Y1586524D01*
G01X1014857Y1586590D02*
X1014524Y1586857D01*
X1014057Y1587057D01*
X1013657D01*
X1013257Y1586924D01*
X1012990Y1586724D01*
X1012857Y1586457D01*
X1012924Y1586057D01*
X1013190Y1585857D01*
X1014390Y1585457D01*
X1014657Y1584990D01*
X1014524Y1584657D01*
X1014257Y1584457D01*
X1013857Y1584390D01*
X1013457Y1584457D01*
X1013057Y1584657D01*
G01X1010257Y1586590D02*
X1009924Y1586857D01*
X1009457Y1587057D01*
X1009057D01*
X1008657Y1586924D01*
X1008390Y1586724D01*
X1008257Y1586457D01*
X1008324Y1586057D01*
X1008590Y1585857D01*
X1009790Y1585457D01*
X1010057Y1584990D01*
X1009924Y1584657D01*
X1009657Y1584457D01*
X1009257Y1584390D01*
X1008857Y1584457D01*
X1008457Y1584657D01*
G01X1001324Y1587057D02*
Y1583057D01*
X998790D01*
G01X999724Y1584990D02*
X1001324D01*
G01X995457Y1584390D02*
Y1587057D01*
G01Y1583324D02*
X995590Y1583257D01*
Y1583124D01*
X995457Y1583057D01*
X995324Y1583124D01*
Y1583257D01*
X995457Y1583324D01*
G01X990857Y1583057D02*
Y1587057D01*
G01X991790Y1584390D02*
X989924D01*
G01X965307Y1658268D02*
X1052207D01*
Y1581307D01*
X965307D01*
Y1658268D01*
G01X1018400Y-140500D02*
X1019400D01*
G01X1018900D02*
Y-143000D01*
G01X1018400D02*
X1019400D01*
G01X1022000D02*
X1021667Y-142958D01*
X1021375Y-142792D01*
X1021125Y-142542D01*
X1020958Y-142250D01*
X1020875Y-141917D01*
Y-141583D01*
X1020958Y-141250D01*
X1021125Y-140958D01*
X1021375Y-140708D01*
X1021667Y-140542D01*
X1022000Y-140500D01*
X1022333Y-140542D01*
X1022625Y-140708D01*
X1022875Y-140958D01*
X1023042Y-141250D01*
X1023125Y-141583D01*
Y-141917D01*
X1023042Y-142250D01*
X1022875Y-142542D01*
X1022625Y-142792D01*
X1022333Y-142958D01*
X1022000Y-143000D01*
G01X1024183Y-142500D02*
X1024433Y-142792D01*
X1024767Y-142958D01*
X1025142Y-143000D01*
X1025475Y-142958D01*
X1025808Y-142750D01*
X1026017Y-142500D01*
X1026058Y-142250D01*
X1025975Y-141958D01*
X1025683Y-141750D01*
X1025392Y-141667D01*
X1025017D01*
G01X1025392D02*
X1025642Y-141542D01*
X1025850Y-141333D01*
X1025933Y-141083D01*
X1025850Y-140833D01*
X1025642Y-140625D01*
X1025267Y-140500D01*
X1024892Y-140542D01*
X1024517Y-140708D01*
G01X1036075Y-95036D02*
Y-92536D01*
X1037116D01*
X1037450Y-92661D01*
X1037658Y-92828D01*
X1037741Y-93161D01*
X1037658Y-93494D01*
X1037408Y-93703D01*
X1037116Y-93828D01*
X1036075D01*
G01X1037116D02*
X1037741Y-95036D01*
G01X1040008D02*
Y-92536D01*
X1039508Y-93036D01*
G01Y-95036D02*
X1040508D01*
G01X1042191Y-94536D02*
X1042441Y-94828D01*
X1042775Y-94994D01*
X1043150Y-95036D01*
X1043483Y-94994D01*
X1043816Y-94786D01*
X1044025Y-94536D01*
X1044066Y-94286D01*
X1043983Y-93994D01*
X1043691Y-93786D01*
X1043400Y-93703D01*
X1043025D01*
G01X1043400D02*
X1043650Y-93578D01*
X1043858Y-93369D01*
X1043941Y-93119D01*
X1043858Y-92869D01*
X1043650Y-92661D01*
X1043275Y-92536D01*
X1042900Y-92578D01*
X1042525Y-92744D01*
G01X1045416Y-93994D02*
X1045708Y-93703D01*
X1045958Y-93536D01*
X1046291Y-93453D01*
X1046583Y-93536D01*
X1046791Y-93703D01*
X1046958Y-93953D01*
X1047000Y-94244D01*
X1046958Y-94494D01*
X1046791Y-94744D01*
X1046541Y-94953D01*
X1046250Y-95036D01*
X1045916Y-94953D01*
X1045625Y-94703D01*
X1045458Y-94328D01*
X1045416Y-93911D01*
X1045500Y-93369D01*
X1045625Y-93078D01*
X1045833Y-92786D01*
X1046125Y-92578D01*
X1046416Y-92536D01*
X1046708Y-92619D01*
X1046916Y-92828D01*
G01X1036017Y-98700D02*
Y-96200D01*
X1037058D01*
X1037392Y-96325D01*
X1037600Y-96492D01*
X1037683Y-96825D01*
X1037600Y-97158D01*
X1037350Y-97367D01*
X1037058Y-97492D01*
X1036017D01*
G01X1037058D02*
X1037683Y-98700D01*
G01X1039950D02*
Y-96200D01*
X1039450Y-96700D01*
G01Y-98700D02*
X1040450D01*
G01X1042133Y-98200D02*
X1042383Y-98492D01*
X1042717Y-98658D01*
X1043092Y-98700D01*
X1043425Y-98658D01*
X1043758Y-98450D01*
X1043967Y-98200D01*
X1044008Y-97950D01*
X1043925Y-97658D01*
X1043633Y-97450D01*
X1043342Y-97367D01*
X1042967D01*
G01X1043342D02*
X1043592Y-97242D01*
X1043800Y-97033D01*
X1043883Y-96783D01*
X1043800Y-96533D01*
X1043592Y-96325D01*
X1043217Y-96200D01*
X1042842Y-96242D01*
X1042467Y-96408D01*
G01X1046067Y-98700D02*
X1046150Y-98158D01*
X1046275Y-97700D01*
X1046442Y-97283D01*
X1046650Y-96825D01*
X1046983Y-96200D01*
X1045317D01*
G01X1036858Y-73936D02*
Y-77936D01*
X1044258D01*
G01X1027317Y-92942D02*
X1027067Y-92817D01*
X1026775Y-92734D01*
X1026442D01*
X1026067Y-92859D01*
X1025775Y-93067D01*
X1025567Y-93317D01*
X1025400Y-93734D01*
X1025358Y-94109D01*
X1025442Y-94484D01*
X1025567Y-94734D01*
X1025817Y-94984D01*
X1026108Y-95151D01*
X1026400Y-95234D01*
X1026692D01*
X1026983Y-95151D01*
X1027233Y-95026D01*
X1027442Y-94859D01*
G01X1030000Y-95234D02*
Y-92734D01*
X1028458Y-94526D01*
X1030542D01*
G01X1032517Y-95234D02*
X1032600Y-94692D01*
X1032725Y-94234D01*
X1032892Y-93817D01*
X1033100Y-93359D01*
X1033433Y-92734D01*
X1031767D01*
G01X1027417Y-97742D02*
X1027167Y-97617D01*
X1026875Y-97534D01*
X1026542D01*
X1026167Y-97659D01*
X1025875Y-97867D01*
X1025667Y-98117D01*
X1025500Y-98534D01*
X1025458Y-98909D01*
X1025542Y-99284D01*
X1025667Y-99534D01*
X1025917Y-99784D01*
X1026208Y-99951D01*
X1026500Y-100034D01*
X1026792D01*
X1027083Y-99951D01*
X1027333Y-99826D01*
X1027542Y-99659D01*
G01X1030100Y-100034D02*
Y-97534D01*
X1028558Y-99326D01*
X1030642D01*
G01X1031783Y-99659D02*
X1032033Y-99867D01*
X1032325Y-99992D01*
X1032700Y-100034D01*
X1033075Y-99951D01*
X1033367Y-99784D01*
X1033575Y-99492D01*
X1033617Y-99159D01*
X1033533Y-98826D01*
X1033325Y-98617D01*
X1033033Y-98451D01*
X1032742Y-98409D01*
X1032450Y-98451D01*
X1032075Y-98617D01*
X1032200Y-97534D01*
X1033325D01*
G01X1026495Y-91625D02*
X1032695D01*
Y-79225D01*
X1026495D01*
G01X1020495D02*
X1014295D01*
Y-91625D01*
X1020495D01*
G01X1043197Y-78667D02*
X1036997D01*
Y-91067D01*
X1043197D01*
G01X1044258Y-73536D02*
Y-69536D01*
X1036858D01*
G01X1014962Y-31822D02*
Y-29322D01*
X1016003D01*
X1016337Y-29447D01*
X1016545Y-29614D01*
X1016628Y-29947D01*
X1016545Y-30280D01*
X1016295Y-30489D01*
X1016003Y-30614D01*
X1014962D01*
G01X1016003D02*
X1016628Y-31822D01*
G01X1018103Y-30780D02*
X1018395Y-30489D01*
X1018645Y-30322D01*
X1018978Y-30239D01*
X1019270Y-30322D01*
X1019478Y-30489D01*
X1019645Y-30739D01*
X1019687Y-31030D01*
X1019645Y-31280D01*
X1019478Y-31530D01*
X1019228Y-31739D01*
X1018937Y-31822D01*
X1018603Y-31739D01*
X1018312Y-31489D01*
X1018145Y-31114D01*
X1018103Y-30697D01*
X1018187Y-30155D01*
X1018312Y-29864D01*
X1018520Y-29572D01*
X1018812Y-29364D01*
X1019103Y-29322D01*
X1019395Y-29405D01*
X1019603Y-29614D01*
G01X1021995Y-31822D02*
Y-29322D01*
X1021495Y-29822D01*
G01Y-31822D02*
X1022495D01*
G01X1025095Y-29322D02*
X1024762Y-29405D01*
X1024512Y-29614D01*
X1024345Y-29864D01*
X1024220Y-30197D01*
X1024178Y-30572D01*
X1024220Y-30947D01*
X1024345Y-31280D01*
X1024512Y-31530D01*
X1024762Y-31739D01*
X1025095Y-31822D01*
X1025428Y-31739D01*
X1025678Y-31530D01*
X1025845Y-31280D01*
X1025970Y-30947D01*
X1026012Y-30572D01*
X1025970Y-30197D01*
X1025845Y-29864D01*
X1025678Y-29614D01*
X1025428Y-29405D01*
X1025095Y-29322D01*
G01X1017168Y-38100D02*
Y-42100D01*
X1024568D01*
G01X1041421Y-30971D02*
X1038921D01*
Y-29930D01*
X1039046Y-29596D01*
X1039213Y-29388D01*
X1039546Y-29305D01*
X1039879Y-29388D01*
X1040088Y-29638D01*
X1040213Y-29930D01*
Y-30971D01*
G01Y-29930D02*
X1041421Y-29305D01*
G01Y-27038D02*
X1038921D01*
X1039421Y-27538D01*
G01X1041421D02*
Y-26538D01*
G01X1040921Y-24855D02*
X1041213Y-24605D01*
X1041379Y-24271D01*
X1041421Y-23896D01*
X1041379Y-23563D01*
X1041171Y-23230D01*
X1040921Y-23021D01*
X1040671Y-22980D01*
X1040379Y-23063D01*
X1040171Y-23355D01*
X1040088Y-23646D01*
Y-24021D01*
G01Y-23646D02*
X1039963Y-23396D01*
X1039754Y-23188D01*
X1039504Y-23105D01*
X1039254Y-23188D01*
X1039046Y-23396D01*
X1038921Y-23771D01*
X1038963Y-24146D01*
X1039129Y-24521D01*
G01X1041421Y-20338D02*
X1038921D01*
X1040713Y-21880D01*
Y-19796D01*
G01X1037721Y-30971D02*
X1035221D01*
Y-29930D01*
X1035346Y-29596D01*
X1035513Y-29388D01*
X1035846Y-29305D01*
X1036179Y-29388D01*
X1036388Y-29638D01*
X1036513Y-29930D01*
Y-30971D01*
G01Y-29930D02*
X1037721Y-29305D01*
G01Y-27038D02*
X1035221D01*
X1035721Y-27538D01*
G01X1037721D02*
Y-26538D01*
G01X1037221Y-24855D02*
X1037513Y-24605D01*
X1037679Y-24271D01*
X1037721Y-23896D01*
X1037679Y-23563D01*
X1037471Y-23230D01*
X1037221Y-23021D01*
X1036971Y-22980D01*
X1036679Y-23063D01*
X1036471Y-23355D01*
X1036388Y-23646D01*
Y-24021D01*
G01Y-23646D02*
X1036263Y-23396D01*
X1036054Y-23188D01*
X1035804Y-23105D01*
X1035554Y-23188D01*
X1035346Y-23396D01*
X1035221Y-23771D01*
X1035263Y-24146D01*
X1035429Y-24521D01*
G01X1037346Y-21755D02*
X1037554Y-21505D01*
X1037679Y-21213D01*
X1037721Y-20838D01*
X1037638Y-20463D01*
X1037471Y-20171D01*
X1037179Y-19963D01*
X1036846Y-19921D01*
X1036513Y-20005D01*
X1036304Y-20213D01*
X1036138Y-20505D01*
X1036096Y-20796D01*
X1036138Y-21088D01*
X1036304Y-21463D01*
X1035221Y-21338D01*
Y-20213D01*
G01X1036712Y-43958D02*
X1040712D01*
Y-36558D01*
G01X1014917Y-76334D02*
Y-73834D01*
X1015958D01*
X1016292Y-73959D01*
X1016500Y-74126D01*
X1016583Y-74459D01*
X1016500Y-74792D01*
X1016250Y-75001D01*
X1015958Y-75126D01*
X1014917D01*
G01X1015958D02*
X1016583Y-76334D01*
G01X1018058Y-75292D02*
X1018350Y-75001D01*
X1018600Y-74834D01*
X1018933Y-74751D01*
X1019225Y-74834D01*
X1019433Y-75001D01*
X1019600Y-75251D01*
X1019642Y-75542D01*
X1019600Y-75792D01*
X1019433Y-76042D01*
X1019183Y-76251D01*
X1018892Y-76334D01*
X1018558Y-76251D01*
X1018267Y-76001D01*
X1018100Y-75626D01*
X1018058Y-75209D01*
X1018142Y-74667D01*
X1018267Y-74376D01*
X1018475Y-74084D01*
X1018767Y-73876D01*
X1019058Y-73834D01*
X1019350Y-73917D01*
X1019558Y-74126D01*
G01X1021950Y-76334D02*
Y-73834D01*
X1021450Y-74334D01*
G01Y-76334D02*
X1022450D01*
G01X1025050D02*
Y-73834D01*
X1024550Y-74334D01*
G01Y-76334D02*
X1025550D01*
G01X1021032Y-68200D02*
Y-64200D01*
X1013632D01*
G01X998557Y-76935D02*
X996057D01*
Y-75894D01*
X996182Y-75560D01*
X996349Y-75352D01*
X996682Y-75269D01*
X997015Y-75352D01*
X997224Y-75602D01*
X997349Y-75894D01*
Y-76935D01*
G01Y-75894D02*
X998557Y-75269D01*
G01X997515Y-73794D02*
X997224Y-73502D01*
X997057Y-73252D01*
X996974Y-72919D01*
X997057Y-72627D01*
X997224Y-72419D01*
X997474Y-72252D01*
X997765Y-72210D01*
X998015Y-72252D01*
X998265Y-72419D01*
X998474Y-72669D01*
X998557Y-72960D01*
X998474Y-73294D01*
X998224Y-73585D01*
X997849Y-73752D01*
X997432Y-73794D01*
X996890Y-73710D01*
X996599Y-73585D01*
X996307Y-73377D01*
X996099Y-73085D01*
X996057Y-72794D01*
X996140Y-72502D01*
X996349Y-72294D01*
G01X998057Y-70819D02*
X998349Y-70569D01*
X998515Y-70235D01*
X998557Y-69860D01*
X998515Y-69527D01*
X998307Y-69194D01*
X998057Y-68985D01*
X997807Y-68944D01*
X997515Y-69027D01*
X997307Y-69319D01*
X997224Y-69610D01*
Y-69985D01*
G01Y-69610D02*
X997099Y-69360D01*
X996890Y-69152D01*
X996640Y-69069D01*
X996390Y-69152D01*
X996182Y-69360D01*
X996057Y-69735D01*
X996099Y-70110D01*
X996265Y-70485D01*
G01X998557Y-66802D02*
X998515Y-66510D01*
X998390Y-66177D01*
X998182Y-65969D01*
X997890Y-65885D01*
X997599Y-65969D01*
X997349Y-66219D01*
X997224Y-66594D01*
Y-67010D01*
X997140Y-67260D01*
X996932Y-67469D01*
X996640Y-67552D01*
X996349Y-67427D01*
X996140Y-67135D01*
X996057Y-66802D01*
X996140Y-66469D01*
X996349Y-66177D01*
X996640Y-66052D01*
X996932Y-66135D01*
X997140Y-66344D01*
X997224Y-66594D01*
Y-67010D01*
X997349Y-67385D01*
X997599Y-67635D01*
X997890Y-67719D01*
X998182Y-67635D01*
X998390Y-67427D01*
X998515Y-67094D01*
X998557Y-66802D01*
G01X1002100Y-75432D02*
X1006100D01*
Y-68032D01*
G01X1002705Y-36962D02*
Y-34462D01*
X1003746D01*
X1004080Y-34587D01*
X1004288Y-34754D01*
X1004371Y-35087D01*
X1004288Y-35420D01*
X1004038Y-35629D01*
X1003746Y-35754D01*
X1002705D01*
G01X1003746D02*
X1004371Y-36962D01*
G01X1005846Y-35920D02*
X1006138Y-35629D01*
X1006388Y-35462D01*
X1006721Y-35379D01*
X1007013Y-35462D01*
X1007221Y-35629D01*
X1007388Y-35879D01*
X1007430Y-36170D01*
X1007388Y-36420D01*
X1007221Y-36670D01*
X1006971Y-36879D01*
X1006680Y-36962D01*
X1006346Y-36879D01*
X1006055Y-36629D01*
X1005888Y-36254D01*
X1005846Y-35837D01*
X1005930Y-35295D01*
X1006055Y-35004D01*
X1006263Y-34712D01*
X1006555Y-34504D01*
X1006846Y-34462D01*
X1007138Y-34545D01*
X1007346Y-34754D01*
G01X1008821Y-36462D02*
X1009071Y-36754D01*
X1009405Y-36920D01*
X1009780Y-36962D01*
X1010113Y-36920D01*
X1010446Y-36712D01*
X1010655Y-36462D01*
X1010696Y-36212D01*
X1010613Y-35920D01*
X1010321Y-35712D01*
X1010030Y-35629D01*
X1009655D01*
G01X1010030D02*
X1010280Y-35504D01*
X1010488Y-35295D01*
X1010571Y-35045D01*
X1010488Y-34795D01*
X1010280Y-34587D01*
X1009905Y-34462D01*
X1009530Y-34504D01*
X1009155Y-34670D01*
G01X1013338Y-36962D02*
Y-34462D01*
X1011796Y-36254D01*
X1013880D01*
G01X1009532Y-45500D02*
Y-41500D01*
X1002132D01*
G01X1011950Y-44232D02*
X1011617Y-44190D01*
X1011325Y-44024D01*
X1011075Y-43774D01*
X1010908Y-43482D01*
X1010825Y-43149D01*
Y-42815D01*
X1010908Y-42482D01*
X1011075Y-42190D01*
X1011325Y-41940D01*
X1011617Y-41774D01*
X1011950Y-41732D01*
X1012283Y-41774D01*
X1012575Y-41940D01*
X1012825Y-42190D01*
X1012992Y-42482D01*
X1013075Y-42815D01*
Y-43149D01*
X1012992Y-43482D01*
X1012825Y-43774D01*
X1012575Y-44024D01*
X1012283Y-44190D01*
X1011950Y-44232D01*
G01X1012283Y-43565D02*
X1012783Y-44232D01*
G01X1014258Y-42149D02*
X1014508Y-41899D01*
X1014800Y-41774D01*
X1015133Y-41732D01*
X1015550Y-41815D01*
X1015842Y-42024D01*
X1015925Y-42274D01*
X1015883Y-42524D01*
X1015717Y-42732D01*
X1014883Y-43149D01*
X1014508Y-43440D01*
X1014258Y-43857D01*
X1014175Y-44232D01*
X1015925D01*
G01X1013400Y-59732D02*
X1024800D01*
G01X1013400Y-46332D02*
Y-59732D01*
G01X1024800Y-46332D02*
X1013400D01*
G01X1024800Y-59732D02*
Y-46332D01*
G01X996150Y-48068D02*
X995817Y-48026D01*
X995525Y-47860D01*
X995275Y-47610D01*
X995108Y-47318D01*
X995025Y-46985D01*
Y-46651D01*
X995108Y-46318D01*
X995275Y-46026D01*
X995525Y-45776D01*
X995817Y-45610D01*
X996150Y-45568D01*
X996483Y-45610D01*
X996775Y-45776D01*
X997025Y-46026D01*
X997192Y-46318D01*
X997275Y-46651D01*
Y-46985D01*
X997192Y-47318D01*
X997025Y-47610D01*
X996775Y-47860D01*
X996483Y-48026D01*
X996150Y-48068D01*
G01X996483Y-47401D02*
X996983Y-48068D01*
G01X999250D02*
Y-45568D01*
X998750Y-46068D01*
G01Y-48068D02*
X999750D01*
G01X998400Y-62968D02*
X1009800D01*
G01X998400Y-49568D02*
Y-62968D01*
G01X1009800Y-49568D02*
X998400D01*
G01X1009800Y-62968D02*
Y-49568D01*
G01X1034820Y-65855D02*
X1042820D01*
G01X1028820D02*
X1034820D01*
G01X1028820D02*
X1042820D01*
G01X1028820Y-47855D02*
Y-65855D01*
G01X1042820Y-47855D02*
X1028820D01*
G01X1030761Y-29458D02*
X1030636Y-29708D01*
X1030553Y-30000D01*
Y-30333D01*
X1030678Y-30708D01*
X1030886Y-31000D01*
X1031136Y-31208D01*
X1031553Y-31375D01*
X1031928Y-31417D01*
X1032303Y-31333D01*
X1032553Y-31208D01*
X1032803Y-30958D01*
X1032970Y-30667D01*
X1033053Y-30375D01*
Y-30083D01*
X1032970Y-29792D01*
X1032845Y-29542D01*
X1032678Y-29333D01*
G01X1033053Y-26775D02*
X1030553D01*
X1032345Y-28317D01*
Y-26233D01*
G01X1032553Y-25092D02*
X1032845Y-24842D01*
X1033011Y-24508D01*
X1033053Y-24133D01*
X1033011Y-23800D01*
X1032803Y-23467D01*
X1032553Y-23258D01*
X1032303Y-23217D01*
X1032011Y-23300D01*
X1031803Y-23592D01*
X1031720Y-23883D01*
Y-24258D01*
G01Y-23883D02*
X1031595Y-23633D01*
X1031386Y-23425D01*
X1031136Y-23342D01*
X1030886Y-23425D01*
X1030678Y-23633D01*
X1030553Y-24008D01*
X1030595Y-24383D01*
X1030761Y-24758D01*
G01X1013371Y19943D02*
Y17443D01*
G01X1012413Y19943D02*
X1014329D01*
G01X1015638Y17443D02*
Y19943D01*
X1016638D01*
X1016971Y19818D01*
X1017221Y19526D01*
X1017304Y19193D01*
X1017221Y18860D01*
X1017013Y18610D01*
X1016638Y18485D01*
X1015638D01*
G01X1018779Y19526D02*
X1019029Y19776D01*
X1019321Y19901D01*
X1019654Y19943D01*
X1020071Y19860D01*
X1020363Y19651D01*
X1020446Y19401D01*
X1020404Y19151D01*
X1020238Y18943D01*
X1019404Y18526D01*
X1019029Y18235D01*
X1018779Y17818D01*
X1018696Y17443D01*
X1020446D01*
G01X1022671D02*
Y19943D01*
X1022171Y19443D01*
G01Y17443D02*
X1023171D01*
G01X1024979Y19526D02*
X1025229Y19776D01*
X1025521Y19901D01*
X1025854Y19943D01*
X1026271Y19860D01*
X1026563Y19651D01*
X1026646Y19401D01*
X1026604Y19151D01*
X1026438Y18943D01*
X1025604Y18526D01*
X1025229Y18235D01*
X1024979Y17818D01*
X1024896Y17443D01*
X1026646D01*
G01X1013271Y13743D02*
Y11243D01*
G01X1012313Y13743D02*
X1014229D01*
G01X1015538Y11243D02*
Y13743D01*
X1016538D01*
X1016871Y13618D01*
X1017121Y13326D01*
X1017204Y12993D01*
X1017121Y12660D01*
X1016913Y12410D01*
X1016538Y12285D01*
X1015538D01*
G01X1018679Y13326D02*
X1018929Y13576D01*
X1019221Y13701D01*
X1019554Y13743D01*
X1019971Y13660D01*
X1020263Y13451D01*
X1020346Y13201D01*
X1020304Y12951D01*
X1020138Y12743D01*
X1019304Y12326D01*
X1018929Y12035D01*
X1018679Y11618D01*
X1018596Y11243D01*
X1020346D01*
G01X1022571D02*
Y13743D01*
X1022071Y13243D01*
G01Y11243D02*
X1023071D01*
G01X1024754Y11743D02*
X1025004Y11451D01*
X1025338Y11285D01*
X1025713Y11243D01*
X1026046Y11285D01*
X1026379Y11493D01*
X1026588Y11743D01*
X1026629Y11993D01*
X1026546Y12285D01*
X1026254Y12493D01*
X1025963Y12576D01*
X1025588D01*
G01X1025963D02*
X1026213Y12701D01*
X1026421Y12910D01*
X1026504Y13160D01*
X1026421Y13410D01*
X1026213Y13618D01*
X1025838Y13743D01*
X1025463Y13701D01*
X1025088Y13535D01*
G01X1013371Y7443D02*
Y4943D01*
G01X1012413Y7443D02*
X1014329D01*
G01X1015638Y4943D02*
Y7443D01*
X1016638D01*
X1016971Y7318D01*
X1017221Y7026D01*
X1017304Y6693D01*
X1017221Y6360D01*
X1017013Y6110D01*
X1016638Y5985D01*
X1015638D01*
G01X1018779Y7026D02*
X1019029Y7276D01*
X1019321Y7401D01*
X1019654Y7443D01*
X1020071Y7360D01*
X1020363Y7151D01*
X1020446Y6901D01*
X1020404Y6651D01*
X1020238Y6443D01*
X1019404Y6026D01*
X1019029Y5735D01*
X1018779Y5318D01*
X1018696Y4943D01*
X1020446D01*
G01X1022671D02*
Y7443D01*
X1022171Y6943D01*
G01Y4943D02*
X1023171D01*
G01X1024854Y5318D02*
X1025104Y5110D01*
X1025396Y4985D01*
X1025771Y4943D01*
X1026146Y5026D01*
X1026438Y5193D01*
X1026646Y5485D01*
X1026688Y5818D01*
X1026604Y6151D01*
X1026396Y6360D01*
X1026104Y6526D01*
X1025813Y6568D01*
X1025521Y6526D01*
X1025146Y6360D01*
X1025271Y7443D01*
X1026396D01*
G01X1024867Y57400D02*
Y59900D01*
X1025908D01*
X1026242Y59775D01*
X1026450Y59608D01*
X1026533Y59275D01*
X1026450Y58942D01*
X1026200Y58733D01*
X1025908Y58608D01*
X1024867D01*
G01X1025908D02*
X1026533Y57400D01*
G01X1028800D02*
Y59900D01*
X1028300Y59400D01*
G01Y57400D02*
X1029300D01*
G01X1031900Y59900D02*
X1031567Y59817D01*
X1031317Y59608D01*
X1031150Y59358D01*
X1031025Y59025D01*
X1030983Y58650D01*
X1031025Y58275D01*
X1031150Y57942D01*
X1031317Y57692D01*
X1031567Y57483D01*
X1031900Y57400D01*
X1032233Y57483D01*
X1032483Y57692D01*
X1032650Y57942D01*
X1032775Y58275D01*
X1032817Y58650D01*
X1032775Y59025D01*
X1032650Y59358D01*
X1032483Y59608D01*
X1032233Y59817D01*
X1031900Y59900D01*
G01X1035500Y57400D02*
Y59900D01*
X1033958Y58108D01*
X1036042D01*
G01X1037392Y57692D02*
X1037683Y57483D01*
X1038017Y57400D01*
X1038350Y57483D01*
X1038642Y57733D01*
X1038850Y58108D01*
X1038933Y58483D01*
Y58942D01*
X1038850Y59317D01*
X1038642Y59650D01*
X1038392Y59817D01*
X1038100Y59900D01*
X1037767Y59817D01*
X1037517Y59650D01*
X1037350Y59400D01*
X1037267Y59067D01*
X1037350Y58775D01*
X1037558Y58483D01*
X1037808Y58317D01*
X1038100Y58275D01*
X1038433Y58358D01*
X1038683Y58567D01*
X1038933Y58942D01*
G01X1008700Y60900D02*
Y56900D01*
X1016100D01*
G01X1024867Y62100D02*
Y64600D01*
X1025908D01*
X1026242Y64475D01*
X1026450Y64308D01*
X1026533Y63975D01*
X1026450Y63642D01*
X1026200Y63433D01*
X1025908Y63308D01*
X1024867D01*
G01X1025908D02*
X1026533Y62100D01*
G01X1028800D02*
Y64600D01*
X1028300Y64100D01*
G01Y62100D02*
X1029300D01*
G01X1031900Y64600D02*
X1031567Y64517D01*
X1031317Y64308D01*
X1031150Y64058D01*
X1031025Y63725D01*
X1030983Y63350D01*
X1031025Y62975D01*
X1031150Y62642D01*
X1031317Y62392D01*
X1031567Y62183D01*
X1031900Y62100D01*
X1032233Y62183D01*
X1032483Y62392D01*
X1032650Y62642D01*
X1032775Y62975D01*
X1032817Y63350D01*
X1032775Y63725D01*
X1032650Y64058D01*
X1032483Y64308D01*
X1032233Y64517D01*
X1031900Y64600D01*
G01X1035500Y62100D02*
Y64600D01*
X1033958Y62808D01*
X1036042D01*
G01X1038600Y62100D02*
Y64600D01*
X1037058Y62808D01*
X1039142D01*
G01X1008700Y65600D02*
Y61600D01*
X1016100D01*
G01X1024867Y52700D02*
Y55200D01*
X1025908D01*
X1026242Y55075D01*
X1026450Y54908D01*
X1026533Y54575D01*
X1026450Y54242D01*
X1026200Y54033D01*
X1025908Y53908D01*
X1024867D01*
G01X1025908D02*
X1026533Y52700D01*
G01X1028800D02*
Y55200D01*
X1028300Y54700D01*
G01Y52700D02*
X1029300D01*
G01X1031900Y55200D02*
X1031567Y55117D01*
X1031317Y54908D01*
X1031150Y54658D01*
X1031025Y54325D01*
X1030983Y53950D01*
X1031025Y53575D01*
X1031150Y53242D01*
X1031317Y52992D01*
X1031567Y52783D01*
X1031900Y52700D01*
X1032233Y52783D01*
X1032483Y52992D01*
X1032650Y53242D01*
X1032775Y53575D01*
X1032817Y53950D01*
X1032775Y54325D01*
X1032650Y54658D01*
X1032483Y54908D01*
X1032233Y55117D01*
X1031900Y55200D01*
G01X1035000D02*
X1034667Y55117D01*
X1034417Y54908D01*
X1034250Y54658D01*
X1034125Y54325D01*
X1034083Y53950D01*
X1034125Y53575D01*
X1034250Y53242D01*
X1034417Y52992D01*
X1034667Y52783D01*
X1035000Y52700D01*
X1035333Y52783D01*
X1035583Y52992D01*
X1035750Y53242D01*
X1035875Y53575D01*
X1035917Y53950D01*
X1035875Y54325D01*
X1035750Y54658D01*
X1035583Y54908D01*
X1035333Y55117D01*
X1035000Y55200D01*
G01X1038017Y52700D02*
X1038100Y53242D01*
X1038225Y53700D01*
X1038392Y54117D01*
X1038600Y54575D01*
X1038933Y55200D01*
X1037267D01*
G01X1008700Y56200D02*
Y52200D01*
X1016100D01*
G01X1013271Y26043D02*
Y23543D01*
G01X1012313Y26043D02*
X1014229D01*
G01X1015538Y23543D02*
Y26043D01*
X1016538D01*
X1016871Y25918D01*
X1017121Y25626D01*
X1017204Y25293D01*
X1017121Y24960D01*
X1016913Y24710D01*
X1016538Y24585D01*
X1015538D01*
G01X1018679Y25626D02*
X1018929Y25876D01*
X1019221Y26001D01*
X1019554Y26043D01*
X1019971Y25960D01*
X1020263Y25751D01*
X1020346Y25501D01*
X1020304Y25251D01*
X1020138Y25043D01*
X1019304Y24626D01*
X1018929Y24335D01*
X1018679Y23918D01*
X1018596Y23543D01*
X1020346D01*
G01X1022571D02*
Y26043D01*
X1022071Y25543D01*
G01Y23543D02*
X1023071D01*
G01X1026171D02*
Y26043D01*
X1024629Y24251D01*
X1026713D01*
G01X1013271Y31843D02*
Y29343D01*
G01X1012313Y31843D02*
X1014229D01*
G01X1015538Y29343D02*
Y31843D01*
X1016538D01*
X1016871Y31718D01*
X1017121Y31426D01*
X1017204Y31093D01*
X1017121Y30760D01*
X1016913Y30510D01*
X1016538Y30385D01*
X1015538D01*
G01X1018679Y31426D02*
X1018929Y31676D01*
X1019221Y31801D01*
X1019554Y31843D01*
X1019971Y31760D01*
X1020263Y31551D01*
X1020346Y31301D01*
X1020304Y31051D01*
X1020138Y30843D01*
X1019304Y30426D01*
X1018929Y30135D01*
X1018679Y29718D01*
X1018596Y29343D01*
X1020346D01*
G01X1022571D02*
Y31843D01*
X1022071Y31343D01*
G01Y29343D02*
X1023071D01*
G01X1024879Y30385D02*
X1025171Y30676D01*
X1025421Y30843D01*
X1025754Y30926D01*
X1026046Y30843D01*
X1026254Y30676D01*
X1026421Y30426D01*
X1026463Y30135D01*
X1026421Y29885D01*
X1026254Y29635D01*
X1026004Y29426D01*
X1025713Y29343D01*
X1025379Y29426D01*
X1025088Y29676D01*
X1024921Y30051D01*
X1024879Y30468D01*
X1024963Y31010D01*
X1025088Y31301D01*
X1025296Y31593D01*
X1025588Y31801D01*
X1025879Y31843D01*
X1026171Y31760D01*
X1026379Y31551D01*
G01X1013171Y43543D02*
Y41043D01*
G01X1012213Y43543D02*
X1014129D01*
G01X1015438Y41043D02*
Y43543D01*
X1016438D01*
X1016771Y43418D01*
X1017021Y43126D01*
X1017104Y42793D01*
X1017021Y42460D01*
X1016813Y42210D01*
X1016438Y42085D01*
X1015438D01*
G01X1018579Y43126D02*
X1018829Y43376D01*
X1019121Y43501D01*
X1019454Y43543D01*
X1019871Y43460D01*
X1020163Y43251D01*
X1020246Y43001D01*
X1020204Y42751D01*
X1020038Y42543D01*
X1019204Y42126D01*
X1018829Y41835D01*
X1018579Y41418D01*
X1018496Y41043D01*
X1020246D01*
G01X1022471D02*
Y43543D01*
X1021971Y43043D01*
G01Y41043D02*
X1022971D01*
G01X1025488D02*
X1025571Y41585D01*
X1025696Y42043D01*
X1025863Y42460D01*
X1026071Y42918D01*
X1026404Y43543D01*
X1024738D01*
G01X1013257Y37771D02*
Y35271D01*
G01X1012299Y37771D02*
X1014215D01*
G01X1015524Y35271D02*
Y37771D01*
X1016524D01*
X1016857Y37646D01*
X1017107Y37354D01*
X1017190Y37021D01*
X1017107Y36688D01*
X1016899Y36438D01*
X1016524Y36313D01*
X1015524D01*
G01X1018665Y37354D02*
X1018915Y37604D01*
X1019207Y37729D01*
X1019540Y37771D01*
X1019957Y37688D01*
X1020249Y37479D01*
X1020332Y37229D01*
X1020290Y36979D01*
X1020124Y36771D01*
X1019290Y36354D01*
X1018915Y36063D01*
X1018665Y35646D01*
X1018582Y35271D01*
X1020332D01*
G01X1022557D02*
Y37771D01*
X1022057Y37271D01*
G01Y35271D02*
X1023057D01*
G01X1025657D02*
X1025949Y35313D01*
X1026282Y35438D01*
X1026490Y35646D01*
X1026574Y35938D01*
X1026490Y36229D01*
X1026240Y36479D01*
X1025865Y36604D01*
X1025449D01*
X1025199Y36688D01*
X1024990Y36896D01*
X1024907Y37188D01*
X1025032Y37479D01*
X1025324Y37688D01*
X1025657Y37771D01*
X1025990Y37688D01*
X1026282Y37479D01*
X1026407Y37188D01*
X1026324Y36896D01*
X1026115Y36688D01*
X1025865Y36604D01*
X1025449D01*
X1025074Y36479D01*
X1024824Y36229D01*
X1024740Y35938D01*
X1024824Y35646D01*
X1025032Y35438D01*
X1025365Y35313D01*
X1025657Y35271D01*
G01X1013357Y49371D02*
Y46871D01*
G01X1012399Y49371D02*
X1014315D01*
G01X1015624Y46871D02*
Y49371D01*
X1016624D01*
X1016957Y49246D01*
X1017207Y48954D01*
X1017290Y48621D01*
X1017207Y48288D01*
X1016999Y48038D01*
X1016624Y47913D01*
X1015624D01*
G01X1018765Y48954D02*
X1019015Y49204D01*
X1019307Y49329D01*
X1019640Y49371D01*
X1020057Y49288D01*
X1020349Y49079D01*
X1020432Y48829D01*
X1020390Y48579D01*
X1020224Y48371D01*
X1019390Y47954D01*
X1019015Y47663D01*
X1018765Y47246D01*
X1018682Y46871D01*
X1020432D01*
G01X1022657D02*
Y49371D01*
X1022157Y48871D01*
G01Y46871D02*
X1023157D01*
G01X1025049Y47163D02*
X1025340Y46954D01*
X1025674Y46871D01*
X1026007Y46954D01*
X1026299Y47204D01*
X1026507Y47579D01*
X1026590Y47954D01*
Y48413D01*
X1026507Y48788D01*
X1026299Y49121D01*
X1026049Y49288D01*
X1025757Y49371D01*
X1025424Y49288D01*
X1025174Y49121D01*
X1025007Y48871D01*
X1024924Y48538D01*
X1025007Y48246D01*
X1025215Y47954D01*
X1025465Y47788D01*
X1025757Y47746D01*
X1026090Y47829D01*
X1026340Y48038D01*
X1026590Y48413D01*
G01X1035071Y78765D02*
Y81265D01*
X1036112D01*
X1036446Y81140D01*
X1036654Y80973D01*
X1036737Y80640D01*
X1036654Y80307D01*
X1036404Y80098D01*
X1036112Y79973D01*
X1035071D01*
G01X1036112D02*
X1036737Y78765D01*
G01X1039004D02*
Y81265D01*
X1038504Y80765D01*
G01Y78765D02*
X1039504D01*
G01X1042104D02*
Y81265D01*
X1041604Y80765D01*
G01Y78765D02*
X1042604D01*
G01X1044287Y79265D02*
X1044537Y78973D01*
X1044871Y78807D01*
X1045246Y78765D01*
X1045579Y78807D01*
X1045912Y79015D01*
X1046121Y79265D01*
X1046162Y79515D01*
X1046079Y79807D01*
X1045787Y80015D01*
X1045496Y80098D01*
X1045121D01*
G01X1045496D02*
X1045746Y80223D01*
X1045954Y80432D01*
X1046037Y80682D01*
X1045954Y80932D01*
X1045746Y81140D01*
X1045371Y81265D01*
X1044996Y81223D01*
X1044621Y81057D01*
G01X1048304Y81265D02*
X1047971Y81182D01*
X1047721Y80973D01*
X1047554Y80723D01*
X1047429Y80390D01*
X1047387Y80015D01*
X1047429Y79640D01*
X1047554Y79307D01*
X1047721Y79057D01*
X1047971Y78848D01*
X1048304Y78765D01*
X1048637Y78848D01*
X1048887Y79057D01*
X1049054Y79307D01*
X1049179Y79640D01*
X1049221Y80015D01*
X1049179Y80390D01*
X1049054Y80723D01*
X1048887Y80973D01*
X1048637Y81182D01*
X1048304Y81265D01*
G01X1024655Y99219D02*
Y130819D01*
X1029355Y135519D01*
X1047955D01*
X1052655Y130819D01*
Y99219D01*
X1024655D01*
G01X1010698Y73514D02*
Y71014D01*
G01X1009740Y73514D02*
X1011656D01*
G01X1012965Y71014D02*
Y73514D01*
X1013965D01*
X1014298Y73389D01*
X1014548Y73097D01*
X1014631Y72764D01*
X1014548Y72431D01*
X1014340Y72181D01*
X1013965Y72056D01*
X1012965D01*
G01X1016106Y73097D02*
X1016356Y73347D01*
X1016648Y73472D01*
X1016981Y73514D01*
X1017398Y73431D01*
X1017690Y73222D01*
X1017773Y72972D01*
X1017731Y72722D01*
X1017565Y72514D01*
X1016731Y72097D01*
X1016356Y71806D01*
X1016106Y71389D01*
X1016023Y71014D01*
X1017773D01*
G01X1020498D02*
Y73514D01*
X1018956Y71722D01*
X1021040D01*
G01X1022181Y71389D02*
X1022431Y71181D01*
X1022723Y71056D01*
X1023098Y71014D01*
X1023473Y71097D01*
X1023765Y71264D01*
X1023973Y71556D01*
X1024015Y71889D01*
X1023931Y72222D01*
X1023723Y72431D01*
X1023431Y72597D01*
X1023140Y72639D01*
X1022848Y72597D01*
X1022473Y72431D01*
X1022598Y73514D01*
X1023723D01*
G01X1010698Y80114D02*
Y77614D01*
G01X1009740Y80114D02*
X1011656D01*
G01X1012965Y77614D02*
Y80114D01*
X1013965D01*
X1014298Y79989D01*
X1014548Y79697D01*
X1014631Y79364D01*
X1014548Y79031D01*
X1014340Y78781D01*
X1013965Y78656D01*
X1012965D01*
G01X1016106Y79697D02*
X1016356Y79947D01*
X1016648Y80072D01*
X1016981Y80114D01*
X1017398Y80031D01*
X1017690Y79822D01*
X1017773Y79572D01*
X1017731Y79322D01*
X1017565Y79114D01*
X1016731Y78697D01*
X1016356Y78406D01*
X1016106Y77989D01*
X1016023Y77614D01*
X1017773D01*
G01X1020498D02*
Y80114D01*
X1018956Y78322D01*
X1021040D01*
G01X1022306Y78656D02*
X1022598Y78947D01*
X1022848Y79114D01*
X1023181Y79197D01*
X1023473Y79114D01*
X1023681Y78947D01*
X1023848Y78697D01*
X1023890Y78406D01*
X1023848Y78156D01*
X1023681Y77906D01*
X1023431Y77697D01*
X1023140Y77614D01*
X1022806Y77697D01*
X1022515Y77947D01*
X1022348Y78322D01*
X1022306Y78739D01*
X1022390Y79281D01*
X1022515Y79572D01*
X1022723Y79864D01*
X1023015Y80072D01*
X1023306Y80114D01*
X1023598Y80031D01*
X1023806Y79822D01*
G01X1033350Y145000D02*
Y142500D01*
G01X1032392Y145000D02*
X1034308D01*
G01X1037367Y144792D02*
X1037117Y144917D01*
X1036825Y145000D01*
X1036492D01*
X1036117Y144875D01*
X1035825Y144667D01*
X1035617Y144417D01*
X1035450Y144000D01*
X1035408Y143625D01*
X1035492Y143250D01*
X1035617Y143000D01*
X1035867Y142750D01*
X1036158Y142583D01*
X1036450Y142500D01*
X1036742D01*
X1037033Y142583D01*
X1037283Y142708D01*
X1037492Y142875D01*
G01X1039550Y142500D02*
Y145000D01*
X1039050Y144500D01*
G01Y142500D02*
X1040050D01*
G01X1042650D02*
X1042942Y142542D01*
X1043275Y142667D01*
X1043483Y142875D01*
X1043567Y143167D01*
X1043483Y143458D01*
X1043233Y143708D01*
X1042858Y143833D01*
X1042442D01*
X1042192Y143917D01*
X1041983Y144125D01*
X1041900Y144417D01*
X1042025Y144708D01*
X1042317Y144917D01*
X1042650Y145000D01*
X1042983Y144917D01*
X1043275Y144708D01*
X1043400Y144417D01*
X1043317Y144125D01*
X1043108Y143917D01*
X1042858Y143833D01*
X1042442D01*
X1042067Y143708D01*
X1041817Y143458D01*
X1041733Y143167D01*
X1041817Y142875D01*
X1042025Y142667D01*
X1042358Y142542D01*
X1042650Y142500D01*
G01X1028417Y441567D02*
Y444067D01*
X1029458D01*
X1029792Y443942D01*
X1030000Y443775D01*
X1030083Y443442D01*
X1030000Y443109D01*
X1029750Y442900D01*
X1029458Y442775D01*
X1028417D01*
G01X1029458D02*
X1030083Y441567D01*
G01X1031558Y442609D02*
X1031850Y442900D01*
X1032100Y443067D01*
X1032433Y443150D01*
X1032725Y443067D01*
X1032933Y442900D01*
X1033100Y442650D01*
X1033142Y442359D01*
X1033100Y442109D01*
X1032933Y441859D01*
X1032683Y441650D01*
X1032392Y441567D01*
X1032058Y441650D01*
X1031767Y441900D01*
X1031600Y442275D01*
X1031558Y442692D01*
X1031642Y443234D01*
X1031767Y443525D01*
X1031975Y443817D01*
X1032267Y444025D01*
X1032558Y444067D01*
X1032850Y443984D01*
X1033058Y443775D01*
G01X1034658Y443650D02*
X1034908Y443900D01*
X1035200Y444025D01*
X1035533Y444067D01*
X1035950Y443984D01*
X1036242Y443775D01*
X1036325Y443525D01*
X1036283Y443275D01*
X1036117Y443067D01*
X1035283Y442650D01*
X1034908Y442359D01*
X1034658Y441942D01*
X1034575Y441567D01*
X1036325D01*
G01X1037633Y442067D02*
X1037883Y441775D01*
X1038217Y441609D01*
X1038592Y441567D01*
X1038925Y441609D01*
X1039258Y441817D01*
X1039467Y442067D01*
X1039508Y442317D01*
X1039425Y442609D01*
X1039133Y442817D01*
X1038842Y442900D01*
X1038467D01*
G01X1038842D02*
X1039092Y443025D01*
X1039300Y443234D01*
X1039383Y443484D01*
X1039300Y443734D01*
X1039092Y443942D01*
X1038717Y444067D01*
X1038342Y444025D01*
X1037967Y443859D01*
G01X1027754Y427120D02*
Y429620D01*
X1028795D01*
X1029129Y429495D01*
X1029337Y429328D01*
X1029420Y428995D01*
X1029337Y428662D01*
X1029087Y428453D01*
X1028795Y428328D01*
X1027754D01*
G01X1028795D02*
X1029420Y427120D01*
G01X1030770Y427620D02*
X1031020Y427328D01*
X1031354Y427162D01*
X1031729Y427120D01*
X1032062Y427162D01*
X1032395Y427370D01*
X1032604Y427620D01*
X1032645Y427870D01*
X1032562Y428162D01*
X1032270Y428370D01*
X1031979Y428453D01*
X1031604D01*
G01X1031979D02*
X1032229Y428578D01*
X1032437Y428787D01*
X1032520Y429037D01*
X1032437Y429287D01*
X1032229Y429495D01*
X1031854Y429620D01*
X1031479Y429578D01*
X1031104Y429412D01*
G01X1033995Y428162D02*
X1034287Y428453D01*
X1034537Y428620D01*
X1034870Y428703D01*
X1035162Y428620D01*
X1035370Y428453D01*
X1035537Y428203D01*
X1035579Y427912D01*
X1035537Y427662D01*
X1035370Y427412D01*
X1035120Y427203D01*
X1034829Y427120D01*
X1034495Y427203D01*
X1034204Y427453D01*
X1034037Y427828D01*
X1033995Y428245D01*
X1034079Y428787D01*
X1034204Y429078D01*
X1034412Y429370D01*
X1034704Y429578D01*
X1034995Y429620D01*
X1035287Y429537D01*
X1035495Y429328D01*
G01X1037887Y427120D02*
Y429620D01*
X1037387Y429120D01*
G01Y427120D02*
X1038387D01*
G01X1028403Y433723D02*
Y436223D01*
X1029444D01*
X1029778Y436098D01*
X1029986Y435931D01*
X1030069Y435598D01*
X1029986Y435265D01*
X1029736Y435056D01*
X1029444Y434931D01*
X1028403D01*
G01X1029444D02*
X1030069Y433723D01*
G01X1031628Y434015D02*
X1031919Y433806D01*
X1032253Y433723D01*
X1032586Y433806D01*
X1032878Y434056D01*
X1033086Y434431D01*
X1033169Y434806D01*
Y435265D01*
X1033086Y435640D01*
X1032878Y435973D01*
X1032628Y436140D01*
X1032336Y436223D01*
X1032003Y436140D01*
X1031753Y435973D01*
X1031586Y435723D01*
X1031503Y435390D01*
X1031586Y435098D01*
X1031794Y434806D01*
X1032044Y434640D01*
X1032336Y434598D01*
X1032669Y434681D01*
X1032919Y434890D01*
X1033169Y435265D01*
G01X1034728Y434015D02*
X1035019Y433806D01*
X1035353Y433723D01*
X1035686Y433806D01*
X1035978Y434056D01*
X1036186Y434431D01*
X1036269Y434806D01*
Y435265D01*
X1036186Y435640D01*
X1035978Y435973D01*
X1035728Y436140D01*
X1035436Y436223D01*
X1035103Y436140D01*
X1034853Y435973D01*
X1034686Y435723D01*
X1034603Y435390D01*
X1034686Y435098D01*
X1034894Y434806D01*
X1035144Y434640D01*
X1035436Y434598D01*
X1035769Y434681D01*
X1036019Y434890D01*
X1036269Y435265D01*
G01X1037744Y435806D02*
X1037994Y436056D01*
X1038286Y436181D01*
X1038619Y436223D01*
X1039036Y436140D01*
X1039328Y435931D01*
X1039411Y435681D01*
X1039369Y435431D01*
X1039203Y435223D01*
X1038369Y434806D01*
X1037994Y434515D01*
X1037744Y434098D01*
X1037661Y433723D01*
X1039411D01*
G01X1009173Y538532D02*
Y541032D01*
X1010214D01*
X1010548Y540907D01*
X1010756Y540740D01*
X1010839Y540407D01*
X1010756Y540074D01*
X1010506Y539865D01*
X1010214Y539740D01*
X1009173D01*
G01X1010214D02*
X1010839Y538532D01*
G01X1013106D02*
Y541032D01*
X1012606Y540532D01*
G01Y538532D02*
X1013606D01*
G01X1016206D02*
X1016498Y538574D01*
X1016831Y538699D01*
X1017039Y538907D01*
X1017123Y539199D01*
X1017039Y539490D01*
X1016789Y539740D01*
X1016414Y539865D01*
X1015998D01*
X1015748Y539949D01*
X1015539Y540157D01*
X1015456Y540449D01*
X1015581Y540740D01*
X1015873Y540949D01*
X1016206Y541032D01*
X1016539Y540949D01*
X1016831Y540740D01*
X1016956Y540449D01*
X1016873Y540157D01*
X1016664Y539949D01*
X1016414Y539865D01*
X1015998D01*
X1015623Y539740D01*
X1015373Y539490D01*
X1015289Y539199D01*
X1015373Y538907D01*
X1015581Y538699D01*
X1015914Y538574D01*
X1016206Y538532D01*
G01X1006139Y529207D02*
Y531707D01*
X1007180D01*
X1007514Y531582D01*
X1007722Y531415D01*
X1007805Y531082D01*
X1007722Y530749D01*
X1007472Y530540D01*
X1007180Y530415D01*
X1006139D01*
G01X1007180D02*
X1007805Y529207D01*
G01X1010072D02*
Y531707D01*
X1009572Y531207D01*
G01Y529207D02*
X1010572D01*
G01X1013172Y531707D02*
X1012839Y531624D01*
X1012589Y531415D01*
X1012422Y531165D01*
X1012297Y530832D01*
X1012255Y530457D01*
X1012297Y530082D01*
X1012422Y529749D01*
X1012589Y529499D01*
X1012839Y529290D01*
X1013172Y529207D01*
X1013505Y529290D01*
X1013755Y529499D01*
X1013922Y529749D01*
X1014047Y530082D01*
X1014089Y530457D01*
X1014047Y530832D01*
X1013922Y531165D01*
X1013755Y531415D01*
X1013505Y531624D01*
X1013172Y531707D01*
G01X1016272D02*
X1015939Y531624D01*
X1015689Y531415D01*
X1015522Y531165D01*
X1015397Y530832D01*
X1015355Y530457D01*
X1015397Y530082D01*
X1015522Y529749D01*
X1015689Y529499D01*
X1015939Y529290D01*
X1016272Y529207D01*
X1016605Y529290D01*
X1016855Y529499D01*
X1017022Y529749D01*
X1017147Y530082D01*
X1017189Y530457D01*
X1017147Y530832D01*
X1017022Y531165D01*
X1016855Y531415D01*
X1016605Y531624D01*
X1016272Y531707D01*
G01X1018455Y529707D02*
X1018705Y529415D01*
X1019039Y529249D01*
X1019414Y529207D01*
X1019747Y529249D01*
X1020080Y529457D01*
X1020289Y529707D01*
X1020330Y529957D01*
X1020247Y530249D01*
X1019955Y530457D01*
X1019664Y530540D01*
X1019289D01*
G01X1019664D02*
X1019914Y530665D01*
X1020122Y530874D01*
X1020205Y531124D01*
X1020122Y531374D01*
X1019914Y531582D01*
X1019539Y531707D01*
X1019164Y531665D01*
X1018789Y531499D01*
G01X1009472Y547207D02*
Y543207D01*
X1016872D01*
G01X1007667Y534000D02*
Y536500D01*
X1008708D01*
X1009042Y536375D01*
X1009250Y536208D01*
X1009333Y535875D01*
X1009250Y535542D01*
X1009000Y535333D01*
X1008708Y535208D01*
X1007667D01*
G01X1008708D02*
X1009333Y534000D01*
G01X1012100D02*
Y536500D01*
X1010558Y534708D01*
X1012642D01*
G01X1013783Y534375D02*
X1014033Y534167D01*
X1014325Y534042D01*
X1014700Y534000D01*
X1015075Y534083D01*
X1015367Y534250D01*
X1015575Y534542D01*
X1015617Y534875D01*
X1015533Y535208D01*
X1015325Y535417D01*
X1015033Y535583D01*
X1014742Y535625D01*
X1014450Y535583D01*
X1014075Y535417D01*
X1014200Y536500D01*
X1015325D01*
G01X1018300Y534000D02*
Y536500D01*
X1016758Y534708D01*
X1018842D01*
G01X1016850Y548000D02*
Y552000D01*
X1009450D01*
G01X1033715Y519253D02*
Y516753D01*
G01X1032757Y519253D02*
X1034673D01*
G01X1035982Y516753D02*
Y519253D01*
X1036982D01*
X1037315Y519128D01*
X1037565Y518836D01*
X1037648Y518503D01*
X1037565Y518170D01*
X1037357Y517920D01*
X1036982Y517795D01*
X1035982D01*
G01X1039915Y516753D02*
Y519253D01*
X1039415Y518753D01*
G01Y516753D02*
X1040415D01*
G01X1043015D02*
X1043307Y516795D01*
X1043640Y516920D01*
X1043848Y517128D01*
X1043932Y517420D01*
X1043848Y517711D01*
X1043598Y517961D01*
X1043223Y518086D01*
X1042807D01*
X1042557Y518170D01*
X1042348Y518378D01*
X1042265Y518670D01*
X1042390Y518961D01*
X1042682Y519170D01*
X1043015Y519253D01*
X1043348Y519170D01*
X1043640Y518961D01*
X1043765Y518670D01*
X1043682Y518378D01*
X1043473Y518170D01*
X1043223Y518086D01*
X1042807D01*
X1042432Y517961D01*
X1042182Y517711D01*
X1042098Y517420D01*
X1042182Y517128D01*
X1042390Y516920D01*
X1042723Y516795D01*
X1043015Y516753D01*
G01X1045198Y517128D02*
X1045448Y516920D01*
X1045740Y516795D01*
X1046115Y516753D01*
X1046490Y516836D01*
X1046782Y517003D01*
X1046990Y517295D01*
X1047032Y517628D01*
X1046948Y517961D01*
X1046740Y518170D01*
X1046448Y518336D01*
X1046157Y518378D01*
X1045865Y518336D01*
X1045490Y518170D01*
X1045615Y519253D01*
X1046740D01*
G01X1033715Y525853D02*
Y523353D01*
G01X1032757Y525853D02*
X1034673D01*
G01X1035982Y523353D02*
Y525853D01*
X1036982D01*
X1037315Y525728D01*
X1037565Y525436D01*
X1037648Y525103D01*
X1037565Y524770D01*
X1037357Y524520D01*
X1036982Y524395D01*
X1035982D01*
G01X1039915Y523353D02*
Y525853D01*
X1039415Y525353D01*
G01Y523353D02*
X1040415D01*
G01X1043015D02*
X1043307Y523395D01*
X1043640Y523520D01*
X1043848Y523728D01*
X1043932Y524020D01*
X1043848Y524311D01*
X1043598Y524561D01*
X1043223Y524686D01*
X1042807D01*
X1042557Y524770D01*
X1042348Y524978D01*
X1042265Y525270D01*
X1042390Y525561D01*
X1042682Y525770D01*
X1043015Y525853D01*
X1043348Y525770D01*
X1043640Y525561D01*
X1043765Y525270D01*
X1043682Y524978D01*
X1043473Y524770D01*
X1043223Y524686D01*
X1042807D01*
X1042432Y524561D01*
X1042182Y524311D01*
X1042098Y524020D01*
X1042182Y523728D01*
X1042390Y523520D01*
X1042723Y523395D01*
X1043015Y523353D01*
G01X1045323Y524395D02*
X1045615Y524686D01*
X1045865Y524853D01*
X1046198Y524936D01*
X1046490Y524853D01*
X1046698Y524686D01*
X1046865Y524436D01*
X1046907Y524145D01*
X1046865Y523895D01*
X1046698Y523645D01*
X1046448Y523436D01*
X1046157Y523353D01*
X1045823Y523436D01*
X1045532Y523686D01*
X1045365Y524061D01*
X1045323Y524478D01*
X1045407Y525020D01*
X1045532Y525311D01*
X1045740Y525603D01*
X1046032Y525811D01*
X1046323Y525853D01*
X1046615Y525770D01*
X1046823Y525561D01*
G01X1033669Y539079D02*
Y536579D01*
G01X1032711Y539079D02*
X1034627D01*
G01X1035936Y536579D02*
Y539079D01*
X1036936D01*
X1037269Y538954D01*
X1037519Y538662D01*
X1037602Y538329D01*
X1037519Y537996D01*
X1037311Y537746D01*
X1036936Y537621D01*
X1035936D01*
G01X1039869Y536579D02*
Y539079D01*
X1039369Y538579D01*
G01Y536579D02*
X1040369D01*
G01X1042261Y536871D02*
X1042552Y536662D01*
X1042886Y536579D01*
X1043219Y536662D01*
X1043511Y536912D01*
X1043719Y537287D01*
X1043802Y537662D01*
Y538121D01*
X1043719Y538496D01*
X1043511Y538829D01*
X1043261Y538996D01*
X1042969Y539079D01*
X1042636Y538996D01*
X1042386Y538829D01*
X1042219Y538579D01*
X1042136Y538246D01*
X1042219Y537954D01*
X1042427Y537662D01*
X1042677Y537496D01*
X1042969Y537454D01*
X1043302Y537537D01*
X1043552Y537746D01*
X1043802Y538121D01*
G01X1046069Y536579D02*
X1046361Y536621D01*
X1046694Y536746D01*
X1046902Y536954D01*
X1046986Y537246D01*
X1046902Y537537D01*
X1046652Y537787D01*
X1046277Y537912D01*
X1045861D01*
X1045611Y537996D01*
X1045402Y538204D01*
X1045319Y538496D01*
X1045444Y538787D01*
X1045736Y538996D01*
X1046069Y539079D01*
X1046402Y538996D01*
X1046694Y538787D01*
X1046819Y538496D01*
X1046736Y538204D01*
X1046527Y537996D01*
X1046277Y537912D01*
X1045861D01*
X1045486Y537787D01*
X1045236Y537537D01*
X1045152Y537246D01*
X1045236Y536954D01*
X1045444Y536746D01*
X1045777Y536621D01*
X1046069Y536579D01*
G01X1033669Y532479D02*
Y529979D01*
G01X1032711Y532479D02*
X1034627D01*
G01X1035936Y529979D02*
Y532479D01*
X1036936D01*
X1037269Y532354D01*
X1037519Y532062D01*
X1037602Y531729D01*
X1037519Y531396D01*
X1037311Y531146D01*
X1036936Y531021D01*
X1035936D01*
G01X1039077Y532062D02*
X1039327Y532312D01*
X1039619Y532437D01*
X1039952Y532479D01*
X1040369Y532396D01*
X1040661Y532187D01*
X1040744Y531937D01*
X1040702Y531687D01*
X1040536Y531479D01*
X1039702Y531062D01*
X1039327Y530771D01*
X1039077Y530354D01*
X1038994Y529979D01*
X1040744D01*
G01X1042969Y532479D02*
X1042636Y532396D01*
X1042386Y532187D01*
X1042219Y531937D01*
X1042094Y531604D01*
X1042052Y531229D01*
X1042094Y530854D01*
X1042219Y530521D01*
X1042386Y530271D01*
X1042636Y530062D01*
X1042969Y529979D01*
X1043302Y530062D01*
X1043552Y530271D01*
X1043719Y530521D01*
X1043844Y530854D01*
X1043886Y531229D01*
X1043844Y531604D01*
X1043719Y531937D01*
X1043552Y532187D01*
X1043302Y532396D01*
X1042969Y532479D01*
G01X1046069Y529979D02*
Y532479D01*
X1045569Y531979D01*
G01Y529979D02*
X1046569D01*
G01X1032757Y507102D02*
Y504602D01*
G01X1031799Y507102D02*
X1033715D01*
G01X1035024Y504602D02*
Y507102D01*
X1036024D01*
X1036357Y506977D01*
X1036607Y506685D01*
X1036690Y506352D01*
X1036607Y506019D01*
X1036399Y505769D01*
X1036024Y505644D01*
X1035024D01*
G01X1038957Y504602D02*
Y507102D01*
X1038457Y506602D01*
G01Y504602D02*
X1039457D01*
G01X1042057D02*
X1042349Y504644D01*
X1042682Y504769D01*
X1042890Y504977D01*
X1042974Y505269D01*
X1042890Y505560D01*
X1042640Y505810D01*
X1042265Y505935D01*
X1041849D01*
X1041599Y506019D01*
X1041390Y506227D01*
X1041307Y506519D01*
X1041432Y506810D01*
X1041724Y507019D01*
X1042057Y507102D01*
X1042390Y507019D01*
X1042682Y506810D01*
X1042807Y506519D01*
X1042724Y506227D01*
X1042515Y506019D01*
X1042265Y505935D01*
X1041849D01*
X1041474Y505810D01*
X1041224Y505560D01*
X1041140Y505269D01*
X1041224Y504977D01*
X1041432Y504769D01*
X1041765Y504644D01*
X1042057Y504602D01*
G01X1045657D02*
Y507102D01*
X1044115Y505310D01*
X1046199D01*
G01X1032757Y513702D02*
Y511202D01*
G01X1031799Y513702D02*
X1033715D01*
G01X1035024Y511202D02*
Y513702D01*
X1036024D01*
X1036357Y513577D01*
X1036607Y513285D01*
X1036690Y512952D01*
X1036607Y512619D01*
X1036399Y512369D01*
X1036024Y512244D01*
X1035024D01*
G01X1038957Y511202D02*
Y513702D01*
X1038457Y513202D01*
G01Y511202D02*
X1039457D01*
G01X1042057D02*
X1042349Y511244D01*
X1042682Y511369D01*
X1042890Y511577D01*
X1042974Y511869D01*
X1042890Y512160D01*
X1042640Y512410D01*
X1042265Y512535D01*
X1041849D01*
X1041599Y512619D01*
X1041390Y512827D01*
X1041307Y513119D01*
X1041432Y513410D01*
X1041724Y513619D01*
X1042057Y513702D01*
X1042390Y513619D01*
X1042682Y513410D01*
X1042807Y513119D01*
X1042724Y512827D01*
X1042515Y512619D01*
X1042265Y512535D01*
X1041849D01*
X1041474Y512410D01*
X1041224Y512160D01*
X1041140Y511869D01*
X1041224Y511577D01*
X1041432Y511369D01*
X1041765Y511244D01*
X1042057Y511202D01*
G01X1044240Y511702D02*
X1044490Y511410D01*
X1044824Y511244D01*
X1045199Y511202D01*
X1045532Y511244D01*
X1045865Y511452D01*
X1046074Y511702D01*
X1046115Y511952D01*
X1046032Y512244D01*
X1045740Y512452D01*
X1045449Y512535D01*
X1045074D01*
G01X1045449D02*
X1045699Y512660D01*
X1045907Y512869D01*
X1045990Y513119D01*
X1045907Y513369D01*
X1045699Y513577D01*
X1045324Y513702D01*
X1044949Y513660D01*
X1044574Y513494D01*
G01X1009406Y556532D02*
Y552532D01*
X1016806D01*
G01X1026732Y555553D02*
Y558053D01*
X1027773D01*
X1028107Y557928D01*
X1028315Y557761D01*
X1028398Y557428D01*
X1028315Y557095D01*
X1028065Y556886D01*
X1027773Y556761D01*
X1026732D01*
G01X1027773D02*
X1028398Y555553D01*
G01X1029957Y555845D02*
X1030248Y555636D01*
X1030582Y555553D01*
X1030915Y555636D01*
X1031207Y555886D01*
X1031415Y556261D01*
X1031498Y556636D01*
Y557095D01*
X1031415Y557470D01*
X1031207Y557803D01*
X1030957Y557970D01*
X1030665Y558053D01*
X1030332Y557970D01*
X1030082Y557803D01*
X1029915Y557553D01*
X1029832Y557220D01*
X1029915Y556928D01*
X1030123Y556636D01*
X1030373Y556470D01*
X1030665Y556428D01*
X1030998Y556511D01*
X1031248Y556720D01*
X1031498Y557095D01*
G01X1033057Y555845D02*
X1033348Y555636D01*
X1033682Y555553D01*
X1034015Y555636D01*
X1034307Y555886D01*
X1034515Y556261D01*
X1034598Y556636D01*
Y557095D01*
X1034515Y557470D01*
X1034307Y557803D01*
X1034057Y557970D01*
X1033765Y558053D01*
X1033432Y557970D01*
X1033182Y557803D01*
X1033015Y557553D01*
X1032932Y557220D01*
X1033015Y556928D01*
X1033223Y556636D01*
X1033473Y556470D01*
X1033765Y556428D01*
X1034098Y556511D01*
X1034348Y556720D01*
X1034598Y557095D01*
G01X1035948Y556053D02*
X1036198Y555761D01*
X1036532Y555595D01*
X1036907Y555553D01*
X1037240Y555595D01*
X1037573Y555803D01*
X1037782Y556053D01*
X1037823Y556303D01*
X1037740Y556595D01*
X1037448Y556803D01*
X1037157Y556886D01*
X1036782D01*
G01X1037157D02*
X1037407Y557011D01*
X1037615Y557220D01*
X1037698Y557470D01*
X1037615Y557720D01*
X1037407Y557928D01*
X1037032Y558053D01*
X1036657Y558011D01*
X1036282Y557845D01*
G01X1003989Y584748D02*
X1006489D01*
G01X1003989Y583790D02*
Y585706D01*
G01X1006489Y587015D02*
X1003989D01*
Y588015D01*
X1004114Y588348D01*
X1004406Y588598D01*
X1004739Y588681D01*
X1005072Y588598D01*
X1005322Y588390D01*
X1005447Y588015D01*
Y587015D01*
G01X1004406Y590156D02*
X1004156Y590406D01*
X1004031Y590698D01*
X1003989Y591031D01*
X1004072Y591448D01*
X1004281Y591740D01*
X1004531Y591823D01*
X1004781Y591781D01*
X1004989Y591615D01*
X1005406Y590781D01*
X1005697Y590406D01*
X1006114Y590156D01*
X1006489Y590073D01*
Y591823D01*
G01X1004406Y593256D02*
X1004156Y593506D01*
X1004031Y593798D01*
X1003989Y594131D01*
X1004072Y594548D01*
X1004281Y594840D01*
X1004531Y594923D01*
X1004781Y594881D01*
X1004989Y594715D01*
X1005406Y593881D01*
X1005697Y593506D01*
X1006114Y593256D01*
X1006489Y593173D01*
Y594923D01*
G01Y597648D02*
X1003989D01*
X1005781Y596106D01*
Y598190D01*
G01X1028931Y587321D02*
Y584821D01*
G01X1027973Y587321D02*
X1029889D01*
G01X1031198Y584821D02*
Y587321D01*
X1032198D01*
X1032531Y587196D01*
X1032781Y586904D01*
X1032864Y586571D01*
X1032781Y586238D01*
X1032573Y585988D01*
X1032198Y585863D01*
X1031198D01*
G01X1035131Y584821D02*
Y587321D01*
X1034631Y586821D01*
G01Y584821D02*
X1035631D01*
G01X1038231D02*
X1038523Y584863D01*
X1038856Y584988D01*
X1039064Y585196D01*
X1039148Y585488D01*
X1039064Y585779D01*
X1038814Y586029D01*
X1038439Y586154D01*
X1038023D01*
X1037773Y586238D01*
X1037564Y586446D01*
X1037481Y586738D01*
X1037606Y587029D01*
X1037898Y587238D01*
X1038231Y587321D01*
X1038564Y587238D01*
X1038856Y587029D01*
X1038981Y586738D01*
X1038898Y586446D01*
X1038689Y586238D01*
X1038439Y586154D01*
X1038023D01*
X1037648Y586029D01*
X1037398Y585779D01*
X1037314Y585488D01*
X1037398Y585196D01*
X1037606Y584988D01*
X1037939Y584863D01*
X1038231Y584821D01*
G01X1041248D02*
X1041331Y585363D01*
X1041456Y585821D01*
X1041623Y586238D01*
X1041831Y586696D01*
X1042164Y587321D01*
X1040498D01*
G01X1028985Y575247D02*
Y572747D01*
G01X1028027Y575247D02*
X1029943D01*
G01X1031252Y572747D02*
Y575247D01*
X1032252D01*
X1032585Y575122D01*
X1032835Y574830D01*
X1032918Y574497D01*
X1032835Y574164D01*
X1032627Y573914D01*
X1032252Y573789D01*
X1031252D01*
G01X1034393Y574830D02*
X1034643Y575080D01*
X1034935Y575205D01*
X1035268Y575247D01*
X1035685Y575164D01*
X1035977Y574955D01*
X1036060Y574705D01*
X1036018Y574455D01*
X1035852Y574247D01*
X1035018Y573830D01*
X1034643Y573539D01*
X1034393Y573122D01*
X1034310Y572747D01*
X1036060D01*
G01X1037493Y574830D02*
X1037743Y575080D01*
X1038035Y575205D01*
X1038368Y575247D01*
X1038785Y575164D01*
X1039077Y574955D01*
X1039160Y574705D01*
X1039118Y574455D01*
X1038952Y574247D01*
X1038118Y573830D01*
X1037743Y573539D01*
X1037493Y573122D01*
X1037410Y572747D01*
X1039160D01*
G01X1041302D02*
X1041385Y573289D01*
X1041510Y573747D01*
X1041677Y574164D01*
X1041885Y574622D01*
X1042218Y575247D01*
X1040552D01*
G01X1028947Y599615D02*
Y597115D01*
G01X1027989Y599615D02*
X1029905D01*
G01X1031214Y597115D02*
Y599615D01*
X1032214D01*
X1032547Y599490D01*
X1032797Y599198D01*
X1032880Y598865D01*
X1032797Y598532D01*
X1032589Y598282D01*
X1032214Y598157D01*
X1031214D01*
G01X1035147Y597115D02*
Y599615D01*
X1034647Y599115D01*
G01Y597115D02*
X1035647D01*
G01X1037539Y597407D02*
X1037830Y597198D01*
X1038164Y597115D01*
X1038497Y597198D01*
X1038789Y597448D01*
X1038997Y597823D01*
X1039080Y598198D01*
Y598657D01*
X1038997Y599032D01*
X1038789Y599365D01*
X1038539Y599532D01*
X1038247Y599615D01*
X1037914Y599532D01*
X1037664Y599365D01*
X1037497Y599115D01*
X1037414Y598782D01*
X1037497Y598490D01*
X1037705Y598198D01*
X1037955Y598032D01*
X1038247Y597990D01*
X1038580Y598073D01*
X1038830Y598282D01*
X1039080Y598657D01*
G01X1041347Y599615D02*
X1041014Y599532D01*
X1040764Y599323D01*
X1040597Y599073D01*
X1040472Y598740D01*
X1040430Y598365D01*
X1040472Y597990D01*
X1040597Y597657D01*
X1040764Y597407D01*
X1041014Y597198D01*
X1041347Y597115D01*
X1041680Y597198D01*
X1041930Y597407D01*
X1042097Y597657D01*
X1042222Y597990D01*
X1042264Y598365D01*
X1042222Y598740D01*
X1042097Y599073D01*
X1041930Y599323D01*
X1041680Y599532D01*
X1041347Y599615D01*
G01X1028947Y593415D02*
Y590915D01*
G01X1027989Y593415D02*
X1029905D01*
G01X1031214Y590915D02*
Y593415D01*
X1032214D01*
X1032547Y593290D01*
X1032797Y592998D01*
X1032880Y592665D01*
X1032797Y592332D01*
X1032589Y592082D01*
X1032214Y591957D01*
X1031214D01*
G01X1035147Y590915D02*
Y593415D01*
X1034647Y592915D01*
G01Y590915D02*
X1035647D01*
G01X1038247D02*
X1038539Y590957D01*
X1038872Y591082D01*
X1039080Y591290D01*
X1039164Y591582D01*
X1039080Y591873D01*
X1038830Y592123D01*
X1038455Y592248D01*
X1038039D01*
X1037789Y592332D01*
X1037580Y592540D01*
X1037497Y592832D01*
X1037622Y593123D01*
X1037914Y593332D01*
X1038247Y593415D01*
X1038580Y593332D01*
X1038872Y593123D01*
X1038997Y592832D01*
X1038914Y592540D01*
X1038705Y592332D01*
X1038455Y592248D01*
X1038039D01*
X1037664Y592123D01*
X1037414Y591873D01*
X1037330Y591582D01*
X1037414Y591290D01*
X1037622Y591082D01*
X1037955Y590957D01*
X1038247Y590915D01*
G01X1040639Y591207D02*
X1040930Y590998D01*
X1041264Y590915D01*
X1041597Y590998D01*
X1041889Y591248D01*
X1042097Y591623D01*
X1042180Y591998D01*
Y592457D01*
X1042097Y592832D01*
X1041889Y593165D01*
X1041639Y593332D01*
X1041347Y593415D01*
X1041014Y593332D01*
X1040764Y593165D01*
X1040597Y592915D01*
X1040514Y592582D01*
X1040597Y592290D01*
X1040805Y591998D01*
X1041055Y591832D01*
X1041347Y591790D01*
X1041680Y591873D01*
X1041930Y592082D01*
X1042180Y592457D01*
G01X1028985Y581347D02*
Y578847D01*
G01X1028027Y581347D02*
X1029943D01*
G01X1031252Y578847D02*
Y581347D01*
X1032252D01*
X1032585Y581222D01*
X1032835Y580930D01*
X1032918Y580597D01*
X1032835Y580264D01*
X1032627Y580014D01*
X1032252Y579889D01*
X1031252D01*
G01X1035185Y578847D02*
Y581347D01*
X1034685Y580847D01*
G01Y578847D02*
X1035685D01*
G01X1038285D02*
X1038577Y578889D01*
X1038910Y579014D01*
X1039118Y579222D01*
X1039202Y579514D01*
X1039118Y579805D01*
X1038868Y580055D01*
X1038493Y580180D01*
X1038077D01*
X1037827Y580264D01*
X1037618Y580472D01*
X1037535Y580764D01*
X1037660Y581055D01*
X1037952Y581264D01*
X1038285Y581347D01*
X1038618Y581264D01*
X1038910Y581055D01*
X1039035Y580764D01*
X1038952Y580472D01*
X1038743Y580264D01*
X1038493Y580180D01*
X1038077D01*
X1037702Y580055D01*
X1037452Y579805D01*
X1037368Y579514D01*
X1037452Y579222D01*
X1037660Y579014D01*
X1037993Y578889D01*
X1038285Y578847D01*
G01X1041385D02*
X1041677Y578889D01*
X1042010Y579014D01*
X1042218Y579222D01*
X1042302Y579514D01*
X1042218Y579805D01*
X1041968Y580055D01*
X1041593Y580180D01*
X1041177D01*
X1040927Y580264D01*
X1040718Y580472D01*
X1040635Y580764D01*
X1040760Y581055D01*
X1041052Y581264D01*
X1041385Y581347D01*
X1041718Y581264D01*
X1042010Y581055D01*
X1042135Y580764D01*
X1042052Y580472D01*
X1041843Y580264D01*
X1041593Y580180D01*
X1041177D01*
X1040802Y580055D01*
X1040552Y579805D01*
X1040468Y579514D01*
X1040552Y579222D01*
X1040760Y579014D01*
X1041093Y578889D01*
X1041385Y578847D01*
G01X1029000Y569300D02*
Y566800D01*
G01X1028042Y569300D02*
X1029958D01*
G01X1031267Y566800D02*
Y569300D01*
X1032267D01*
X1032600Y569175D01*
X1032850Y568883D01*
X1032933Y568550D01*
X1032850Y568217D01*
X1032642Y567967D01*
X1032267Y567842D01*
X1031267D01*
G01X1034408Y568883D02*
X1034658Y569133D01*
X1034950Y569258D01*
X1035283Y569300D01*
X1035700Y569217D01*
X1035992Y569008D01*
X1036075Y568758D01*
X1036033Y568508D01*
X1035867Y568300D01*
X1035033Y567883D01*
X1034658Y567592D01*
X1034408Y567175D01*
X1034325Y566800D01*
X1036075D01*
G01X1038300Y569300D02*
X1037967Y569217D01*
X1037717Y569008D01*
X1037550Y568758D01*
X1037425Y568425D01*
X1037383Y568050D01*
X1037425Y567675D01*
X1037550Y567342D01*
X1037717Y567092D01*
X1037967Y566883D01*
X1038300Y566800D01*
X1038633Y566883D01*
X1038883Y567092D01*
X1039050Y567342D01*
X1039175Y567675D01*
X1039217Y568050D01*
X1039175Y568425D01*
X1039050Y568758D01*
X1038883Y569008D01*
X1038633Y569217D01*
X1038300Y569300D01*
G01X1040608Y568883D02*
X1040858Y569133D01*
X1041150Y569258D01*
X1041483Y569300D01*
X1041900Y569217D01*
X1042192Y569008D01*
X1042275Y568758D01*
X1042233Y568508D01*
X1042067Y568300D01*
X1041233Y567883D01*
X1040858Y567592D01*
X1040608Y567175D01*
X1040525Y566800D01*
X1042275D01*
G01X1028981Y563366D02*
Y560866D01*
G01X1028023Y563366D02*
X1029939D01*
G01X1031248Y560866D02*
Y563366D01*
X1032248D01*
X1032581Y563241D01*
X1032831Y562949D01*
X1032914Y562616D01*
X1032831Y562283D01*
X1032623Y562033D01*
X1032248Y561908D01*
X1031248D01*
G01X1034389Y562949D02*
X1034639Y563199D01*
X1034931Y563324D01*
X1035264Y563366D01*
X1035681Y563283D01*
X1035973Y563074D01*
X1036056Y562824D01*
X1036014Y562574D01*
X1035848Y562366D01*
X1035014Y561949D01*
X1034639Y561658D01*
X1034389Y561241D01*
X1034306Y560866D01*
X1036056D01*
G01X1038781D02*
Y563366D01*
X1037239Y561574D01*
X1039323D01*
G01X1040589Y562949D02*
X1040839Y563199D01*
X1041131Y563324D01*
X1041464Y563366D01*
X1041881Y563283D01*
X1042173Y563074D01*
X1042256Y562824D01*
X1042214Y562574D01*
X1042048Y562366D01*
X1041214Y561949D01*
X1040839Y561658D01*
X1040589Y561241D01*
X1040506Y560866D01*
X1042256D01*
G01X1032715Y820658D02*
X1030215D01*
Y821699D01*
X1030340Y822033D01*
X1030507Y822241D01*
X1030840Y822324D01*
X1031173Y822241D01*
X1031382Y821991D01*
X1031507Y821699D01*
Y820658D01*
G01Y821699D02*
X1032715Y822324D01*
G01Y825091D02*
X1030215D01*
X1032007Y823549D01*
Y825633D01*
G01X1030215Y827691D02*
X1030298Y827358D01*
X1030507Y827108D01*
X1030757Y826941D01*
X1031090Y826816D01*
X1031465Y826774D01*
X1031840Y826816D01*
X1032173Y826941D01*
X1032423Y827108D01*
X1032632Y827358D01*
X1032715Y827691D01*
X1032632Y828024D01*
X1032423Y828274D01*
X1032173Y828441D01*
X1031840Y828566D01*
X1031465Y828608D01*
X1031090Y828566D01*
X1030757Y828441D01*
X1030507Y828274D01*
X1030298Y828024D01*
X1030215Y827691D01*
G01X1030632Y829999D02*
X1030382Y830249D01*
X1030257Y830541D01*
X1030215Y830874D01*
X1030298Y831291D01*
X1030507Y831583D01*
X1030757Y831666D01*
X1031007Y831624D01*
X1031215Y831458D01*
X1031632Y830624D01*
X1031923Y830249D01*
X1032340Y829999D01*
X1032715Y829916D01*
Y831666D01*
G01X1038773Y825503D02*
X1042773D01*
Y832903D01*
G01X1027915Y820658D02*
X1025415D01*
Y821699D01*
X1025540Y822033D01*
X1025707Y822241D01*
X1026040Y822324D01*
X1026373Y822241D01*
X1026582Y821991D01*
X1026707Y821699D01*
Y820658D01*
G01Y821699D02*
X1027915Y822324D01*
G01X1027415Y823674D02*
X1027707Y823924D01*
X1027873Y824258D01*
X1027915Y824633D01*
X1027873Y824966D01*
X1027665Y825299D01*
X1027415Y825508D01*
X1027165Y825549D01*
X1026873Y825466D01*
X1026665Y825174D01*
X1026582Y824883D01*
Y824508D01*
G01Y824883D02*
X1026457Y825133D01*
X1026248Y825341D01*
X1025998Y825424D01*
X1025748Y825341D01*
X1025540Y825133D01*
X1025415Y824758D01*
X1025457Y824383D01*
X1025623Y824008D01*
G01X1027915Y827608D02*
X1027373Y827691D01*
X1026915Y827816D01*
X1026498Y827983D01*
X1026040Y828191D01*
X1025415Y828524D01*
Y826858D01*
G01X1027915Y830791D02*
X1025415D01*
X1025915Y830291D01*
G01X1027915D02*
Y831291D01*
G01X1033973Y825503D02*
X1037973D01*
Y832903D01*
G01X1038773Y837703D02*
Y833703D01*
X1046173D01*
G01X1016922Y835946D02*
X1016672Y836071D01*
X1016380Y836154D01*
X1016047D01*
X1015672Y836029D01*
X1015380Y835821D01*
X1015172Y835571D01*
X1015005Y835154D01*
X1014963Y834779D01*
X1015047Y834404D01*
X1015172Y834154D01*
X1015422Y833904D01*
X1015713Y833737D01*
X1016005Y833654D01*
X1016297D01*
X1016588Y833737D01*
X1016838Y833862D01*
X1017047Y834029D01*
G01X1019105Y833654D02*
Y836154D01*
X1018605Y835654D01*
G01Y833654D02*
X1019605D01*
G01X1022205D02*
Y836154D01*
X1021705Y835654D01*
G01Y833654D02*
X1022705D01*
G01X1024388Y834029D02*
X1024638Y833821D01*
X1024930Y833696D01*
X1025305Y833654D01*
X1025680Y833737D01*
X1025972Y833904D01*
X1026180Y834196D01*
X1026222Y834529D01*
X1026138Y834862D01*
X1025930Y835071D01*
X1025638Y835237D01*
X1025347Y835279D01*
X1025055Y835237D01*
X1024680Y835071D01*
X1024805Y836154D01*
X1025930D01*
G01X1011728Y888517D02*
X1009228D01*
Y889558D01*
X1009353Y889892D01*
X1009520Y890100D01*
X1009853Y890183D01*
X1010186Y890100D01*
X1010395Y889850D01*
X1010520Y889558D01*
Y888517D01*
G01Y889558D02*
X1011728Y890183D01*
G01Y892950D02*
X1009228D01*
X1011020Y891408D01*
Y893492D01*
G01X1011228Y894633D02*
X1011520Y894883D01*
X1011686Y895217D01*
X1011728Y895592D01*
X1011686Y895925D01*
X1011478Y896258D01*
X1011228Y896467D01*
X1010978Y896508D01*
X1010686Y896425D01*
X1010478Y896133D01*
X1010395Y895842D01*
Y895467D01*
G01Y895842D02*
X1010270Y896092D01*
X1010061Y896300D01*
X1009811Y896383D01*
X1009561Y896300D01*
X1009353Y896092D01*
X1009228Y895717D01*
X1009270Y895342D01*
X1009436Y894967D01*
G01X1011728Y899150D02*
X1009228D01*
X1011020Y897608D01*
Y899692D01*
G01X1019017Y890000D02*
Y892500D01*
X1020058D01*
X1020392Y892375D01*
X1020600Y892208D01*
X1020683Y891875D01*
X1020600Y891542D01*
X1020350Y891333D01*
X1020058Y891208D01*
X1019017D01*
G01X1020058D02*
X1020683Y890000D01*
G01X1023450D02*
Y892500D01*
X1021908Y890708D01*
X1023992D01*
G01X1025133Y890500D02*
X1025383Y890208D01*
X1025717Y890042D01*
X1026092Y890000D01*
X1026425Y890042D01*
X1026758Y890250D01*
X1026967Y890500D01*
X1027008Y890750D01*
X1026925Y891042D01*
X1026633Y891250D01*
X1026342Y891333D01*
X1025967D01*
G01X1026342D02*
X1026592Y891458D01*
X1026800Y891667D01*
X1026883Y891917D01*
X1026800Y892167D01*
X1026592Y892375D01*
X1026217Y892500D01*
X1025842Y892458D01*
X1025467Y892292D01*
G01X1028358Y892083D02*
X1028608Y892333D01*
X1028900Y892458D01*
X1029233Y892500D01*
X1029650Y892417D01*
X1029942Y892208D01*
X1030025Y891958D01*
X1029983Y891708D01*
X1029817Y891500D01*
X1028983Y891083D01*
X1028608Y890792D01*
X1028358Y890375D01*
X1028275Y890000D01*
X1030025D01*
G01X1014774Y872617D02*
Y875117D01*
X1015815D01*
X1016149Y874992D01*
X1016357Y874825D01*
X1016440Y874492D01*
X1016357Y874159D01*
X1016107Y873950D01*
X1015815Y873825D01*
X1014774D01*
G01X1015815D02*
X1016440Y872617D01*
G01X1019207D02*
Y875117D01*
X1017665Y873325D01*
X1019749D01*
G01X1021807Y875117D02*
X1021474Y875034D01*
X1021224Y874825D01*
X1021057Y874575D01*
X1020932Y874242D01*
X1020890Y873867D01*
X1020932Y873492D01*
X1021057Y873159D01*
X1021224Y872909D01*
X1021474Y872700D01*
X1021807Y872617D01*
X1022140Y872700D01*
X1022390Y872909D01*
X1022557Y873159D01*
X1022682Y873492D01*
X1022724Y873867D01*
X1022682Y874242D01*
X1022557Y874575D01*
X1022390Y874825D01*
X1022140Y875034D01*
X1021807Y875117D01*
G01X1023990Y873117D02*
X1024240Y872825D01*
X1024574Y872659D01*
X1024949Y872617D01*
X1025282Y872659D01*
X1025615Y872867D01*
X1025824Y873117D01*
X1025865Y873367D01*
X1025782Y873659D01*
X1025490Y873867D01*
X1025199Y873950D01*
X1024824D01*
G01X1025199D02*
X1025449Y874075D01*
X1025657Y874284D01*
X1025740Y874534D01*
X1025657Y874784D01*
X1025449Y874992D01*
X1025074Y875117D01*
X1024699Y875075D01*
X1024324Y874909D01*
G01X1028814Y874741D02*
Y870741D01*
X1036214D01*
G01X1036673Y874703D02*
Y870703D01*
X1044073D01*
G01X1028734Y841683D02*
X1030526D01*
X1030901Y841850D01*
X1031151Y842183D01*
X1031234Y842600D01*
X1031151Y843017D01*
X1030901Y843350D01*
X1030526Y843517D01*
X1028734D01*
G01X1031234Y845700D02*
X1028734D01*
X1029234Y845200D01*
G01X1031234D02*
Y846200D01*
G01X1030859Y847883D02*
X1031067Y848133D01*
X1031192Y848425D01*
X1031234Y848800D01*
X1031151Y849175D01*
X1030984Y849467D01*
X1030692Y849675D01*
X1030359Y849717D01*
X1030026Y849633D01*
X1029817Y849425D01*
X1029651Y849133D01*
X1029609Y848842D01*
X1029651Y848550D01*
X1029817Y848175D01*
X1028734Y848300D01*
Y849425D01*
G01X1045623Y849803D02*
X1033723D01*
G01Y857803D02*
X1045623D01*
G01X1033723Y849803D02*
Y857803D01*
G01X1035323Y853803D02*
X1033723Y855403D01*
G01X1035323Y853803D02*
X1033723Y852203D01*
G01X1016908Y855617D02*
X1016783Y855367D01*
X1016700Y855075D01*
Y854742D01*
X1016825Y854367D01*
X1017033Y854075D01*
X1017283Y853867D01*
X1017700Y853700D01*
X1018075Y853658D01*
X1018450Y853742D01*
X1018700Y853867D01*
X1018950Y854117D01*
X1019117Y854408D01*
X1019200Y854700D01*
Y854992D01*
X1019117Y855283D01*
X1018992Y855533D01*
X1018825Y855742D01*
G01X1017117Y857008D02*
X1016867Y857258D01*
X1016742Y857550D01*
X1016700Y857883D01*
X1016783Y858300D01*
X1016992Y858592D01*
X1017242Y858675D01*
X1017492Y858633D01*
X1017700Y858467D01*
X1018117Y857633D01*
X1018408Y857258D01*
X1018825Y857008D01*
X1019200Y856925D01*
Y858675D01*
G01X1018700Y859983D02*
X1018992Y860233D01*
X1019158Y860567D01*
X1019200Y860942D01*
X1019158Y861275D01*
X1018950Y861608D01*
X1018700Y861817D01*
X1018450Y861858D01*
X1018158Y861775D01*
X1017950Y861483D01*
X1017867Y861192D01*
Y860817D01*
G01Y861192D02*
X1017742Y861442D01*
X1017533Y861650D01*
X1017283Y861733D01*
X1017033Y861650D01*
X1016825Y861442D01*
X1016700Y861067D01*
X1016742Y860692D01*
X1016908Y860317D01*
G01X1021271Y855670D02*
X1021146Y855420D01*
X1021063Y855128D01*
Y854795D01*
X1021188Y854420D01*
X1021396Y854128D01*
X1021646Y853920D01*
X1022063Y853753D01*
X1022438Y853711D01*
X1022813Y853795D01*
X1023063Y853920D01*
X1023313Y854170D01*
X1023480Y854461D01*
X1023563Y854753D01*
Y855045D01*
X1023480Y855336D01*
X1023355Y855586D01*
X1023188Y855795D01*
G01Y856936D02*
X1023396Y857186D01*
X1023521Y857478D01*
X1023563Y857853D01*
X1023480Y858228D01*
X1023313Y858520D01*
X1023021Y858728D01*
X1022688Y858770D01*
X1022355Y858686D01*
X1022146Y858478D01*
X1021980Y858186D01*
X1021938Y857895D01*
X1021980Y857603D01*
X1022146Y857228D01*
X1021063Y857353D01*
Y858478D01*
G01X1022521Y860161D02*
X1022230Y860453D01*
X1022063Y860703D01*
X1021980Y861036D01*
X1022063Y861328D01*
X1022230Y861536D01*
X1022480Y861703D01*
X1022771Y861745D01*
X1023021Y861703D01*
X1023271Y861536D01*
X1023480Y861286D01*
X1023563Y860995D01*
X1023480Y860661D01*
X1023230Y860370D01*
X1022855Y860203D01*
X1022438Y860161D01*
X1021896Y860245D01*
X1021605Y860370D01*
X1021313Y860578D01*
X1021105Y860870D01*
X1021063Y861161D01*
X1021146Y861453D01*
X1021355Y861661D01*
G01X1040100Y890267D02*
X1037600D01*
Y891308D01*
X1037725Y891642D01*
X1037892Y891850D01*
X1038225Y891933D01*
X1038558Y891850D01*
X1038767Y891600D01*
X1038892Y891308D01*
Y890267D01*
G01Y891308D02*
X1040100Y891933D01*
G01Y894200D02*
X1040058Y894492D01*
X1039933Y894825D01*
X1039725Y895033D01*
X1039433Y895117D01*
X1039142Y895033D01*
X1038892Y894783D01*
X1038767Y894408D01*
Y893992D01*
X1038683Y893742D01*
X1038475Y893533D01*
X1038183Y893450D01*
X1037892Y893575D01*
X1037683Y893867D01*
X1037600Y894200D01*
X1037683Y894533D01*
X1037892Y894825D01*
X1038183Y894950D01*
X1038475Y894867D01*
X1038683Y894658D01*
X1038767Y894408D01*
Y893992D01*
X1038892Y893617D01*
X1039142Y893367D01*
X1039433Y893283D01*
X1039725Y893367D01*
X1039933Y893575D01*
X1040058Y893908D01*
X1040100Y894200D01*
G01X1039808Y896592D02*
X1040017Y896883D01*
X1040100Y897217D01*
X1040017Y897550D01*
X1039767Y897842D01*
X1039392Y898050D01*
X1039017Y898133D01*
X1038558D01*
X1038183Y898050D01*
X1037850Y897842D01*
X1037683Y897592D01*
X1037600Y897300D01*
X1037683Y896967D01*
X1037850Y896717D01*
X1038100Y896550D01*
X1038433Y896467D01*
X1038725Y896550D01*
X1039017Y896758D01*
X1039183Y897008D01*
X1039225Y897300D01*
X1039142Y897633D01*
X1038933Y897883D01*
X1038558Y898133D01*
G01X1041100Y910400D02*
X1037100D01*
Y903000D01*
G01X1016480Y890067D02*
X1013980D01*
Y891108D01*
X1014105Y891442D01*
X1014272Y891650D01*
X1014605Y891733D01*
X1014938Y891650D01*
X1015147Y891400D01*
X1015272Y891108D01*
Y890067D01*
G01Y891108D02*
X1016480Y891733D01*
G01X1016188Y893292D02*
X1016397Y893583D01*
X1016480Y893917D01*
X1016397Y894250D01*
X1016147Y894542D01*
X1015772Y894750D01*
X1015397Y894833D01*
X1014938D01*
X1014563Y894750D01*
X1014230Y894542D01*
X1014063Y894292D01*
X1013980Y894000D01*
X1014063Y893667D01*
X1014230Y893417D01*
X1014480Y893250D01*
X1014813Y893167D01*
X1015105Y893250D01*
X1015397Y893458D01*
X1015563Y893708D01*
X1015605Y894000D01*
X1015522Y894333D01*
X1015313Y894583D01*
X1014938Y894833D01*
G01X1015980Y896183D02*
X1016272Y896433D01*
X1016438Y896767D01*
X1016480Y897142D01*
X1016438Y897475D01*
X1016230Y897808D01*
X1015980Y898017D01*
X1015730Y898058D01*
X1015438Y897975D01*
X1015230Y897683D01*
X1015147Y897392D01*
Y897017D01*
G01Y897392D02*
X1015022Y897642D01*
X1014813Y897850D01*
X1014563Y897933D01*
X1014313Y897850D01*
X1014105Y897642D01*
X1013980Y897267D01*
X1014022Y896892D01*
X1014188Y896517D01*
G01X1022480Y910200D02*
X1018480D01*
Y902800D01*
G01X1020567Y894000D02*
Y896500D01*
X1021608D01*
X1021942Y896375D01*
X1022150Y896208D01*
X1022233Y895875D01*
X1022150Y895542D01*
X1021900Y895333D01*
X1021608Y895208D01*
X1020567D01*
G01X1021608D02*
X1022233Y894000D01*
G01X1023792Y894292D02*
X1024083Y894083D01*
X1024417Y894000D01*
X1024750Y894083D01*
X1025042Y894333D01*
X1025250Y894708D01*
X1025333Y895083D01*
Y895542D01*
X1025250Y895917D01*
X1025042Y896250D01*
X1024792Y896417D01*
X1024500Y896500D01*
X1024167Y896417D01*
X1023917Y896250D01*
X1023750Y896000D01*
X1023667Y895667D01*
X1023750Y895375D01*
X1023958Y895083D01*
X1024208Y894917D01*
X1024500Y894875D01*
X1024833Y894958D01*
X1025083Y895167D01*
X1025333Y895542D01*
G01X1026683Y894375D02*
X1026933Y894167D01*
X1027225Y894042D01*
X1027600Y894000D01*
X1027975Y894083D01*
X1028267Y894250D01*
X1028475Y894542D01*
X1028517Y894875D01*
X1028433Y895208D01*
X1028225Y895417D01*
X1027933Y895583D01*
X1027642Y895625D01*
X1027350Y895583D01*
X1026975Y895417D01*
X1027100Y896500D01*
X1028225D01*
G01X1030635Y906603D02*
Y910603D01*
X1023235D01*
G01X1017728Y910200D02*
X1013728D01*
Y902800D01*
G01X1030600Y902200D02*
Y906200D01*
X1023200D01*
G01X1035400Y890267D02*
X1032900D01*
Y891308D01*
X1033025Y891642D01*
X1033192Y891850D01*
X1033525Y891933D01*
X1033858Y891850D01*
X1034067Y891600D01*
X1034192Y891308D01*
Y890267D01*
G01Y891308D02*
X1035400Y891933D01*
G01X1035108Y893492D02*
X1035317Y893783D01*
X1035400Y894117D01*
X1035317Y894450D01*
X1035067Y894742D01*
X1034692Y894950D01*
X1034317Y895033D01*
X1033858D01*
X1033483Y894950D01*
X1033150Y894742D01*
X1032983Y894492D01*
X1032900Y894200D01*
X1032983Y893867D01*
X1033150Y893617D01*
X1033400Y893450D01*
X1033733Y893367D01*
X1034025Y893450D01*
X1034317Y893658D01*
X1034483Y893908D01*
X1034525Y894200D01*
X1034442Y894533D01*
X1034233Y894783D01*
X1033858Y895033D01*
G01X1034358Y896508D02*
X1034067Y896800D01*
X1033900Y897050D01*
X1033817Y897383D01*
X1033900Y897675D01*
X1034067Y897883D01*
X1034317Y898050D01*
X1034608Y898092D01*
X1034858Y898050D01*
X1035108Y897883D01*
X1035317Y897633D01*
X1035400Y897342D01*
X1035317Y897008D01*
X1035067Y896717D01*
X1034692Y896550D01*
X1034275Y896508D01*
X1033733Y896592D01*
X1033442Y896717D01*
X1033150Y896925D01*
X1032942Y897217D01*
X1032900Y897508D01*
X1032983Y897800D01*
X1033192Y898008D01*
G01X1032400Y903000D02*
X1036400D01*
Y910400D01*
G01X998378Y925265D02*
Y927765D01*
X999419D01*
X999753Y927640D01*
X999961Y927473D01*
X1000044Y927140D01*
X999961Y926807D01*
X999711Y926598D01*
X999419Y926473D01*
X998378D01*
G01X999419D02*
X1000044Y925265D01*
G01X1002311D02*
Y927765D01*
X1001811Y927265D01*
G01Y925265D02*
X1002811D01*
G01X1004619Y927348D02*
X1004869Y927598D01*
X1005161Y927723D01*
X1005494Y927765D01*
X1005911Y927682D01*
X1006203Y927473D01*
X1006286Y927223D01*
X1006244Y926973D01*
X1006078Y926765D01*
X1005244Y926348D01*
X1004869Y926057D01*
X1004619Y925640D01*
X1004536Y925265D01*
X1006286D01*
G01X1007803Y925557D02*
X1008094Y925348D01*
X1008428Y925265D01*
X1008761Y925348D01*
X1009053Y925598D01*
X1009261Y925973D01*
X1009344Y926348D01*
Y926807D01*
X1009261Y927182D01*
X1009053Y927515D01*
X1008803Y927682D01*
X1008511Y927765D01*
X1008178Y927682D01*
X1007928Y927515D01*
X1007761Y927265D01*
X1007678Y926932D01*
X1007761Y926640D01*
X1007969Y926348D01*
X1008219Y926182D01*
X1008511Y926140D01*
X1008844Y926223D01*
X1009094Y926432D01*
X1009344Y926807D01*
G01X1015200Y928500D02*
Y932500D01*
X1007800D01*
G01X999347Y914475D02*
X999305Y914142D01*
X999139Y913850D01*
X998889Y913600D01*
X998597Y913433D01*
X998264Y913350D01*
X997930D01*
X997597Y913433D01*
X997305Y913600D01*
X997055Y913850D01*
X996889Y914142D01*
X996847Y914475D01*
X996889Y914808D01*
X997055Y915100D01*
X997305Y915350D01*
X997597Y915517D01*
X997930Y915600D01*
X998264D01*
X998597Y915517D01*
X998889Y915350D01*
X999139Y915100D01*
X999305Y914808D01*
X999347Y914475D01*
G01X998680Y914808D02*
X999347Y915308D01*
G01Y917575D02*
X996847D01*
X997347Y917075D01*
G01X999347D02*
Y918075D01*
G01Y920592D02*
X998805Y920675D01*
X998347Y920800D01*
X997930Y920967D01*
X997472Y921175D01*
X996847Y921508D01*
Y919842D01*
G01X1002000Y911000D02*
X1016000D01*
G01X1002000Y924000D02*
Y911000D01*
G01X1016000Y924000D02*
X1002000D01*
G01X1016000Y911000D02*
Y924000D01*
G01X1019500Y932500D02*
X1017300Y930300D01*
G01X1019500Y932500D02*
X1017300Y934700D01*
G01Y939500D02*
Y925500D01*
G01X1038800D02*
X1018000D01*
G01X1038800Y939500D02*
Y925500D01*
G01X1030134Y954267D02*
X1027634D01*
Y955308D01*
X1027759Y955642D01*
X1027926Y955850D01*
X1028259Y955933D01*
X1028592Y955850D01*
X1028801Y955600D01*
X1028926Y955308D01*
Y954267D01*
G01Y955308D02*
X1030134Y955933D01*
G01X1029842Y957492D02*
X1030051Y957783D01*
X1030134Y958117D01*
X1030051Y958450D01*
X1029801Y958742D01*
X1029426Y958950D01*
X1029051Y959033D01*
X1028592D01*
X1028217Y958950D01*
X1027884Y958742D01*
X1027717Y958492D01*
X1027634Y958200D01*
X1027717Y957867D01*
X1027884Y957617D01*
X1028134Y957450D01*
X1028467Y957367D01*
X1028759Y957450D01*
X1029051Y957658D01*
X1029217Y957908D01*
X1029259Y958200D01*
X1029176Y958533D01*
X1028967Y958783D01*
X1028592Y959033D01*
G01X1030134Y961800D02*
X1027634D01*
X1029426Y960258D01*
Y962342D01*
G01X1025100Y961450D02*
X1021100D01*
Y954050D01*
G01X999694Y983540D02*
X995694D01*
Y976140D01*
G01X1017684Y978231D02*
X1015184D01*
Y979272D01*
X1015309Y979606D01*
X1015476Y979814D01*
X1015809Y979897D01*
X1016142Y979814D01*
X1016351Y979564D01*
X1016476Y979272D01*
Y978231D01*
G01Y979272D02*
X1017684Y979897D01*
G01X1017309Y981247D02*
X1017517Y981497D01*
X1017642Y981789D01*
X1017684Y982164D01*
X1017601Y982539D01*
X1017434Y982831D01*
X1017142Y983039D01*
X1016809Y983081D01*
X1016476Y982997D01*
X1016267Y982789D01*
X1016101Y982497D01*
X1016059Y982206D01*
X1016101Y981914D01*
X1016267Y981539D01*
X1015184Y981664D01*
Y982789D01*
G01X1017309Y984347D02*
X1017517Y984597D01*
X1017642Y984889D01*
X1017684Y985264D01*
X1017601Y985639D01*
X1017434Y985931D01*
X1017142Y986139D01*
X1016809Y986181D01*
X1016476Y986097D01*
X1016267Y985889D01*
X1016101Y985597D01*
X1016059Y985306D01*
X1016101Y985014D01*
X1016267Y984639D01*
X1015184Y984764D01*
Y985889D01*
G01X1013194Y983540D02*
X1009194D01*
Y976140D01*
G01X1003034Y967531D02*
X1000534D01*
Y968572D01*
X1000659Y968906D01*
X1000826Y969114D01*
X1001159Y969197D01*
X1001492Y969114D01*
X1001701Y968864D01*
X1001826Y968572D01*
Y967531D01*
G01Y968572D02*
X1003034Y969197D01*
G01X1001992Y970672D02*
X1001701Y970964D01*
X1001534Y971214D01*
X1001451Y971547D01*
X1001534Y971839D01*
X1001701Y972047D01*
X1001951Y972214D01*
X1002242Y972256D01*
X1002492Y972214D01*
X1002742Y972047D01*
X1002951Y971797D01*
X1003034Y971506D01*
X1002951Y971172D01*
X1002701Y970881D01*
X1002326Y970714D01*
X1001909Y970672D01*
X1001367Y970756D01*
X1001076Y970881D01*
X1000784Y971089D01*
X1000576Y971381D01*
X1000534Y971672D01*
X1000617Y971964D01*
X1000826Y972172D01*
G01X1003034Y974564D02*
X1000534D01*
X1001034Y974064D01*
G01X1003034D02*
Y975064D01*
G01X1000194Y976140D02*
X1004194D01*
Y983540D01*
G01X1008104Y967038D02*
X1005604D01*
Y968079D01*
X1005729Y968413D01*
X1005896Y968621D01*
X1006229Y968704D01*
X1006562Y968621D01*
X1006771Y968371D01*
X1006896Y968079D01*
Y967038D01*
G01Y968079D02*
X1008104Y968704D01*
G01X1007062Y970179D02*
X1006771Y970471D01*
X1006604Y970721D01*
X1006521Y971054D01*
X1006604Y971346D01*
X1006771Y971554D01*
X1007021Y971721D01*
X1007312Y971763D01*
X1007562Y971721D01*
X1007812Y971554D01*
X1008021Y971304D01*
X1008104Y971013D01*
X1008021Y970679D01*
X1007771Y970388D01*
X1007396Y970221D01*
X1006979Y970179D01*
X1006437Y970263D01*
X1006146Y970388D01*
X1005854Y970596D01*
X1005646Y970888D01*
X1005604Y971179D01*
X1005687Y971471D01*
X1005896Y971679D01*
G01X1006021Y973279D02*
X1005771Y973529D01*
X1005646Y973821D01*
X1005604Y974154D01*
X1005687Y974571D01*
X1005896Y974863D01*
X1006146Y974946D01*
X1006396Y974904D01*
X1006604Y974738D01*
X1007021Y973904D01*
X1007312Y973529D01*
X1007729Y973279D01*
X1008104Y973196D01*
Y974946D01*
G01X1004694Y976140D02*
X1008694D01*
Y983540D01*
G01X1029833Y952267D02*
Y950475D01*
X1030000Y950100D01*
X1030333Y949850D01*
X1030750Y949767D01*
X1031167Y949850D01*
X1031500Y950100D01*
X1031667Y950475D01*
Y952267D01*
G01X1033142Y950059D02*
X1033433Y949850D01*
X1033767Y949767D01*
X1034100Y949850D01*
X1034392Y950100D01*
X1034600Y950475D01*
X1034683Y950850D01*
Y951309D01*
X1034600Y951684D01*
X1034392Y952017D01*
X1034142Y952184D01*
X1033850Y952267D01*
X1033517Y952184D01*
X1033267Y952017D01*
X1033100Y951767D01*
X1033017Y951434D01*
X1033100Y951142D01*
X1033308Y950850D01*
X1033558Y950684D01*
X1033850Y950642D01*
X1034183Y950725D01*
X1034433Y950934D01*
X1034683Y951309D01*
G01X1017300Y939500D02*
X1038800D01*
G01X1007917Y944289D02*
X1007667Y944414D01*
X1007375Y944497D01*
X1007042D01*
X1006667Y944372D01*
X1006375Y944164D01*
X1006167Y943914D01*
X1006000Y943497D01*
X1005958Y943122D01*
X1006042Y942747D01*
X1006167Y942497D01*
X1006417Y942247D01*
X1006708Y942080D01*
X1007000Y941997D01*
X1007292D01*
X1007583Y942080D01*
X1007833Y942205D01*
X1008042Y942372D01*
G01X1009308Y944080D02*
X1009558Y944330D01*
X1009850Y944455D01*
X1010183Y944497D01*
X1010600Y944414D01*
X1010892Y944205D01*
X1010975Y943955D01*
X1010933Y943705D01*
X1010767Y943497D01*
X1009933Y943080D01*
X1009558Y942789D01*
X1009308Y942372D01*
X1009225Y941997D01*
X1010975D01*
G01X1012492Y942289D02*
X1012783Y942080D01*
X1013117Y941997D01*
X1013450Y942080D01*
X1013742Y942330D01*
X1013950Y942705D01*
X1014033Y943080D01*
Y943539D01*
X1013950Y943914D01*
X1013742Y944247D01*
X1013492Y944414D01*
X1013200Y944497D01*
X1012867Y944414D01*
X1012617Y944247D01*
X1012450Y943997D01*
X1012367Y943664D01*
X1012450Y943372D01*
X1012658Y943080D01*
X1012908Y942914D01*
X1013200Y942872D01*
X1013533Y942955D01*
X1013783Y943164D01*
X1014033Y943539D01*
G01X1007917Y947989D02*
X1007667Y948114D01*
X1007375Y948197D01*
X1007042D01*
X1006667Y948072D01*
X1006375Y947864D01*
X1006167Y947614D01*
X1006000Y947197D01*
X1005958Y946822D01*
X1006042Y946447D01*
X1006167Y946197D01*
X1006417Y945947D01*
X1006708Y945780D01*
X1007000Y945697D01*
X1007292D01*
X1007583Y945780D01*
X1007833Y945905D01*
X1008042Y946072D01*
G01X1009183Y946197D02*
X1009433Y945905D01*
X1009767Y945739D01*
X1010142Y945697D01*
X1010475Y945739D01*
X1010808Y945947D01*
X1011017Y946197D01*
X1011058Y946447D01*
X1010975Y946739D01*
X1010683Y946947D01*
X1010392Y947030D01*
X1010017D01*
G01X1010392D02*
X1010642Y947155D01*
X1010850Y947364D01*
X1010933Y947614D01*
X1010850Y947864D01*
X1010642Y948072D01*
X1010267Y948197D01*
X1009892Y948155D01*
X1009517Y947989D01*
G01X1013200Y948197D02*
X1012867Y948114D01*
X1012617Y947905D01*
X1012450Y947655D01*
X1012325Y947322D01*
X1012283Y946947D01*
X1012325Y946572D01*
X1012450Y946239D01*
X1012617Y945989D01*
X1012867Y945780D01*
X1013200Y945697D01*
X1013533Y945780D01*
X1013783Y945989D01*
X1013950Y946239D01*
X1014075Y946572D01*
X1014117Y946947D01*
X1014075Y947322D01*
X1013950Y947655D01*
X1013783Y947905D01*
X1013533Y948114D01*
X1013200Y948197D01*
G01X1005849Y1025143D02*
X1009849D01*
Y1032543D01*
G01X1001194Y1025140D02*
X1005194D01*
Y1032540D01*
G01X991649Y1025143D02*
X995649D01*
Y1032543D01*
G01X1010494Y1025240D02*
X1014494D01*
Y1032640D01*
G01X996439Y1025137D02*
X1000439D01*
Y1032537D01*
G01X1019194Y1032640D02*
X1015194D01*
Y1025240D01*
G01X1023033Y1023000D02*
Y1021208D01*
X1023200Y1020833D01*
X1023533Y1020583D01*
X1023950Y1020500D01*
X1024367Y1020583D01*
X1024700Y1020833D01*
X1024867Y1021208D01*
Y1023000D01*
G01X1026258Y1021542D02*
X1026550Y1021833D01*
X1026800Y1022000D01*
X1027133Y1022083D01*
X1027425Y1022000D01*
X1027633Y1021833D01*
X1027800Y1021583D01*
X1027842Y1021292D01*
X1027800Y1021042D01*
X1027633Y1020792D01*
X1027383Y1020583D01*
X1027092Y1020500D01*
X1026758Y1020583D01*
X1026467Y1020833D01*
X1026300Y1021208D01*
X1026258Y1021625D01*
X1026342Y1022167D01*
X1026467Y1022458D01*
X1026675Y1022750D01*
X1026967Y1022958D01*
X1027258Y1023000D01*
X1027550Y1022917D01*
X1027758Y1022708D01*
G01X995044Y988340D02*
Y1009340D01*
X1026694D01*
Y998340D01*
X995044D01*
G01Y1006990D02*
X998194Y1003840D01*
X995044Y1000690D01*
G01X1033122Y1053517D02*
X1030622D01*
Y1054558D01*
X1030747Y1054892D01*
X1030914Y1055100D01*
X1031247Y1055183D01*
X1031580Y1055100D01*
X1031789Y1054850D01*
X1031914Y1054558D01*
Y1053517D01*
G01Y1054558D02*
X1033122Y1055183D01*
G01Y1057450D02*
X1030622D01*
X1031122Y1056950D01*
G01X1033122D02*
Y1057950D01*
G01X1030622Y1060550D02*
X1030705Y1060217D01*
X1030914Y1059967D01*
X1031164Y1059800D01*
X1031497Y1059675D01*
X1031872Y1059633D01*
X1032247Y1059675D01*
X1032580Y1059800D01*
X1032830Y1059967D01*
X1033039Y1060217D01*
X1033122Y1060550D01*
X1033039Y1060883D01*
X1032830Y1061133D01*
X1032580Y1061300D01*
X1032247Y1061425D01*
X1031872Y1061467D01*
X1031497Y1061425D01*
X1031164Y1061300D01*
X1030914Y1061133D01*
X1030705Y1060883D01*
X1030622Y1060550D01*
G01X1033122Y1063650D02*
X1033080Y1063942D01*
X1032955Y1064275D01*
X1032747Y1064483D01*
X1032455Y1064567D01*
X1032164Y1064483D01*
X1031914Y1064233D01*
X1031789Y1063858D01*
Y1063442D01*
X1031705Y1063192D01*
X1031497Y1062983D01*
X1031205Y1062900D01*
X1030914Y1063025D01*
X1030705Y1063317D01*
X1030622Y1063650D01*
X1030705Y1063983D01*
X1030914Y1064275D01*
X1031205Y1064400D01*
X1031497Y1064317D01*
X1031705Y1064108D01*
X1031789Y1063858D01*
Y1063442D01*
X1031914Y1063067D01*
X1032164Y1062817D01*
X1032455Y1062733D01*
X1032747Y1062817D01*
X1032955Y1063025D01*
X1033080Y1063358D01*
X1033122Y1063650D01*
G01X1034500Y1075700D02*
X1030500D01*
Y1068300D01*
G01X1039500D02*
X1043500D01*
Y1075700D01*
G01X1009849Y1035860D02*
X1007349D01*
Y1036901D01*
X1007474Y1037235D01*
X1007641Y1037443D01*
X1007974Y1037526D01*
X1008307Y1037443D01*
X1008516Y1037193D01*
X1008641Y1036901D01*
Y1035860D01*
G01Y1036901D02*
X1009849Y1037526D01*
G01Y1040293D02*
X1007349D01*
X1009141Y1038751D01*
Y1040835D01*
G01X1009349Y1041976D02*
X1009641Y1042226D01*
X1009807Y1042560D01*
X1009849Y1042935D01*
X1009807Y1043268D01*
X1009599Y1043601D01*
X1009349Y1043810D01*
X1009099Y1043851D01*
X1008807Y1043768D01*
X1008599Y1043476D01*
X1008516Y1043185D01*
Y1042810D01*
G01Y1043185D02*
X1008391Y1043435D01*
X1008182Y1043643D01*
X1007932Y1043726D01*
X1007682Y1043643D01*
X1007474Y1043435D01*
X1007349Y1043060D01*
X1007391Y1042685D01*
X1007557Y1042310D01*
G01X1009849Y1045993D02*
X1007349D01*
X1007849Y1045493D01*
G01X1009849D02*
Y1046493D01*
G01X1005194Y1037407D02*
X1002694D01*
Y1038448D01*
X1002819Y1038782D01*
X1002986Y1038990D01*
X1003319Y1039073D01*
X1003652Y1038990D01*
X1003861Y1038740D01*
X1003986Y1038448D01*
Y1037407D01*
G01Y1038448D02*
X1005194Y1039073D01*
G01X1004819Y1040423D02*
X1005027Y1040673D01*
X1005152Y1040965D01*
X1005194Y1041340D01*
X1005111Y1041715D01*
X1004944Y1042007D01*
X1004652Y1042215D01*
X1004319Y1042257D01*
X1003986Y1042173D01*
X1003777Y1041965D01*
X1003611Y1041673D01*
X1003569Y1041382D01*
X1003611Y1041090D01*
X1003777Y1040715D01*
X1002694Y1040840D01*
Y1041965D01*
G01X1005194Y1044357D02*
X1004652Y1044440D01*
X1004194Y1044565D01*
X1003777Y1044732D01*
X1003319Y1044940D01*
X1002694Y1045273D01*
Y1043607D01*
G01X1028622Y1053517D02*
X1026122D01*
Y1054558D01*
X1026247Y1054892D01*
X1026414Y1055100D01*
X1026747Y1055183D01*
X1027080Y1055100D01*
X1027289Y1054850D01*
X1027414Y1054558D01*
Y1053517D01*
G01Y1054558D02*
X1028622Y1055183D01*
G01Y1057450D02*
X1026122D01*
X1026622Y1056950D01*
G01X1028622D02*
Y1057950D01*
G01X1026122Y1060550D02*
X1026205Y1060217D01*
X1026414Y1059967D01*
X1026664Y1059800D01*
X1026997Y1059675D01*
X1027372Y1059633D01*
X1027747Y1059675D01*
X1028080Y1059800D01*
X1028330Y1059967D01*
X1028539Y1060217D01*
X1028622Y1060550D01*
X1028539Y1060883D01*
X1028330Y1061133D01*
X1028080Y1061300D01*
X1027747Y1061425D01*
X1027372Y1061467D01*
X1026997Y1061425D01*
X1026664Y1061300D01*
X1026414Y1061133D01*
X1026205Y1060883D01*
X1026122Y1060550D01*
G01X1026539Y1062858D02*
X1026289Y1063108D01*
X1026164Y1063400D01*
X1026122Y1063733D01*
X1026205Y1064150D01*
X1026414Y1064442D01*
X1026664Y1064525D01*
X1026914Y1064483D01*
X1027122Y1064317D01*
X1027539Y1063483D01*
X1027830Y1063108D01*
X1028247Y1062858D01*
X1028622Y1062775D01*
Y1064525D01*
G01X1026000Y1068300D02*
X1030000D01*
Y1075700D01*
G01X1037622Y1053517D02*
X1035122D01*
Y1054558D01*
X1035247Y1054892D01*
X1035414Y1055100D01*
X1035747Y1055183D01*
X1036080Y1055100D01*
X1036289Y1054850D01*
X1036414Y1054558D01*
Y1053517D01*
G01Y1054558D02*
X1037622Y1055183D01*
G01Y1057450D02*
X1035122D01*
X1035622Y1056950D01*
G01X1037622D02*
Y1057950D01*
G01X1035122Y1060550D02*
X1035205Y1060217D01*
X1035414Y1059967D01*
X1035664Y1059800D01*
X1035997Y1059675D01*
X1036372Y1059633D01*
X1036747Y1059675D01*
X1037080Y1059800D01*
X1037330Y1059967D01*
X1037539Y1060217D01*
X1037622Y1060550D01*
X1037539Y1060883D01*
X1037330Y1061133D01*
X1037080Y1061300D01*
X1036747Y1061425D01*
X1036372Y1061467D01*
X1035997Y1061425D01*
X1035664Y1061300D01*
X1035414Y1061133D01*
X1035205Y1060883D01*
X1035122Y1060550D01*
G01X1037122Y1062733D02*
X1037414Y1062983D01*
X1037580Y1063317D01*
X1037622Y1063692D01*
X1037580Y1064025D01*
X1037372Y1064358D01*
X1037122Y1064567D01*
X1036872Y1064608D01*
X1036580Y1064525D01*
X1036372Y1064233D01*
X1036289Y1063942D01*
Y1063567D01*
G01Y1063942D02*
X1036164Y1064192D01*
X1035955Y1064400D01*
X1035705Y1064483D01*
X1035455Y1064400D01*
X1035247Y1064192D01*
X1035122Y1063817D01*
X1035164Y1063442D01*
X1035330Y1063067D01*
G01X1039000Y1075700D02*
X1035000D01*
Y1068300D01*
G01X1023956Y1053517D02*
X1021456D01*
Y1054558D01*
X1021581Y1054892D01*
X1021748Y1055100D01*
X1022081Y1055183D01*
X1022414Y1055100D01*
X1022623Y1054850D01*
X1022748Y1054558D01*
Y1053517D01*
G01Y1054558D02*
X1023956Y1055183D01*
G01Y1057450D02*
X1021456D01*
X1021956Y1056950D01*
G01X1023956D02*
Y1057950D01*
G01X1021456Y1060550D02*
X1021539Y1060217D01*
X1021748Y1059967D01*
X1021998Y1059800D01*
X1022331Y1059675D01*
X1022706Y1059633D01*
X1023081Y1059675D01*
X1023414Y1059800D01*
X1023664Y1059967D01*
X1023873Y1060217D01*
X1023956Y1060550D01*
X1023873Y1060883D01*
X1023664Y1061133D01*
X1023414Y1061300D01*
X1023081Y1061425D01*
X1022706Y1061467D01*
X1022331Y1061425D01*
X1021998Y1061300D01*
X1021748Y1061133D01*
X1021539Y1060883D01*
X1021456Y1060550D01*
G01X1023956Y1064150D02*
X1021456D01*
X1023248Y1062608D01*
Y1064692D01*
G01X1025500Y1075700D02*
X1021500D01*
Y1068300D01*
G01X995649Y1035860D02*
X993149D01*
Y1036901D01*
X993274Y1037235D01*
X993441Y1037443D01*
X993774Y1037526D01*
X994107Y1037443D01*
X994316Y1037193D01*
X994441Y1036901D01*
Y1035860D01*
G01Y1036901D02*
X995649Y1037526D01*
G01Y1040293D02*
X993149D01*
X994941Y1038751D01*
Y1040835D01*
G01X993566Y1042101D02*
X993316Y1042351D01*
X993191Y1042643D01*
X993149Y1042976D01*
X993232Y1043393D01*
X993441Y1043685D01*
X993691Y1043768D01*
X993941Y1043726D01*
X994149Y1043560D01*
X994566Y1042726D01*
X994857Y1042351D01*
X995274Y1042101D01*
X995649Y1042018D01*
Y1043768D01*
G01Y1045910D02*
X995107Y1045993D01*
X994649Y1046118D01*
X994232Y1046285D01*
X993774Y1046493D01*
X993149Y1046826D01*
Y1045160D01*
G01X1014494Y1037507D02*
X1011994D01*
Y1038548D01*
X1012119Y1038882D01*
X1012286Y1039090D01*
X1012619Y1039173D01*
X1012952Y1039090D01*
X1013161Y1038840D01*
X1013286Y1038548D01*
Y1037507D01*
G01Y1038548D02*
X1014494Y1039173D01*
G01X1014119Y1040523D02*
X1014327Y1040773D01*
X1014452Y1041065D01*
X1014494Y1041440D01*
X1014411Y1041815D01*
X1014244Y1042107D01*
X1013952Y1042315D01*
X1013619Y1042357D01*
X1013286Y1042273D01*
X1013077Y1042065D01*
X1012911Y1041773D01*
X1012869Y1041482D01*
X1012911Y1041190D01*
X1013077Y1040815D01*
X1011994Y1040940D01*
Y1042065D01*
G01X1013994Y1043623D02*
X1014286Y1043873D01*
X1014452Y1044207D01*
X1014494Y1044582D01*
X1014452Y1044915D01*
X1014244Y1045248D01*
X1013994Y1045457D01*
X1013744Y1045498D01*
X1013452Y1045415D01*
X1013244Y1045123D01*
X1013161Y1044832D01*
Y1044457D01*
G01Y1044832D02*
X1013036Y1045082D01*
X1012827Y1045290D01*
X1012577Y1045373D01*
X1012327Y1045290D01*
X1012119Y1045082D01*
X1011994Y1044707D01*
X1012036Y1044332D01*
X1012202Y1043957D01*
G01X1000439Y1037404D02*
X997939D01*
Y1038445D01*
X998064Y1038779D01*
X998231Y1038987D01*
X998564Y1039070D01*
X998897Y1038987D01*
X999106Y1038737D01*
X999231Y1038445D01*
Y1037404D01*
G01Y1038445D02*
X1000439Y1039070D01*
G01X1000064Y1040420D02*
X1000272Y1040670D01*
X1000397Y1040962D01*
X1000439Y1041337D01*
X1000356Y1041712D01*
X1000189Y1042004D01*
X999897Y1042212D01*
X999564Y1042254D01*
X999231Y1042170D01*
X999022Y1041962D01*
X998856Y1041670D01*
X998814Y1041379D01*
X998856Y1041087D01*
X999022Y1040712D01*
X997939Y1040837D01*
Y1041962D01*
G01X1000147Y1043729D02*
X1000356Y1044020D01*
X1000439Y1044354D01*
X1000356Y1044687D01*
X1000106Y1044979D01*
X999731Y1045187D01*
X999356Y1045270D01*
X998897D01*
X998522Y1045187D01*
X998189Y1044979D01*
X998022Y1044729D01*
X997939Y1044437D01*
X998022Y1044104D01*
X998189Y1043854D01*
X998439Y1043687D01*
X998772Y1043604D01*
X999064Y1043687D01*
X999356Y1043895D01*
X999522Y1044145D01*
X999564Y1044437D01*
X999481Y1044770D01*
X999272Y1045020D01*
X998897Y1045270D01*
G01X1019194Y1037507D02*
X1016694D01*
Y1038548D01*
X1016819Y1038882D01*
X1016986Y1039090D01*
X1017319Y1039173D01*
X1017652Y1039090D01*
X1017861Y1038840D01*
X1017986Y1038548D01*
Y1037507D01*
G01Y1038548D02*
X1019194Y1039173D01*
G01X1018152Y1040648D02*
X1017861Y1040940D01*
X1017694Y1041190D01*
X1017611Y1041523D01*
X1017694Y1041815D01*
X1017861Y1042023D01*
X1018111Y1042190D01*
X1018402Y1042232D01*
X1018652Y1042190D01*
X1018902Y1042023D01*
X1019111Y1041773D01*
X1019194Y1041482D01*
X1019111Y1041148D01*
X1018861Y1040857D01*
X1018486Y1040690D01*
X1018069Y1040648D01*
X1017527Y1040732D01*
X1017236Y1040857D01*
X1016944Y1041065D01*
X1016736Y1041357D01*
X1016694Y1041648D01*
X1016777Y1041940D01*
X1016986Y1042148D01*
G01X1016694Y1044540D02*
X1016777Y1044207D01*
X1016986Y1043957D01*
X1017236Y1043790D01*
X1017569Y1043665D01*
X1017944Y1043623D01*
X1018319Y1043665D01*
X1018652Y1043790D01*
X1018902Y1043957D01*
X1019111Y1044207D01*
X1019194Y1044540D01*
X1019111Y1044873D01*
X1018902Y1045123D01*
X1018652Y1045290D01*
X1018319Y1045415D01*
X1017944Y1045457D01*
X1017569Y1045415D01*
X1017236Y1045290D01*
X1016986Y1045123D01*
X1016777Y1044873D01*
X1016694Y1044540D01*
G01X1023350Y1079500D02*
Y1100500D01*
X1055000D01*
Y1089500D01*
X1023350D01*
G01X1005400Y1114317D02*
X1002900D01*
Y1115358D01*
X1003025Y1115692D01*
X1003192Y1115900D01*
X1003525Y1115983D01*
X1003858Y1115900D01*
X1004067Y1115650D01*
X1004192Y1115358D01*
Y1114317D01*
G01Y1115358D02*
X1005400Y1115983D01*
G01Y1118250D02*
X1002900D01*
X1003400Y1117750D01*
G01X1005400D02*
Y1118750D01*
G01X1002900Y1121350D02*
X1002983Y1121017D01*
X1003192Y1120767D01*
X1003442Y1120600D01*
X1003775Y1120475D01*
X1004150Y1120433D01*
X1004525Y1120475D01*
X1004858Y1120600D01*
X1005108Y1120767D01*
X1005317Y1121017D01*
X1005400Y1121350D01*
X1005317Y1121683D01*
X1005108Y1121933D01*
X1004858Y1122100D01*
X1004525Y1122225D01*
X1004150Y1122267D01*
X1003775Y1122225D01*
X1003442Y1122100D01*
X1003192Y1121933D01*
X1002983Y1121683D01*
X1002900Y1121350D01*
G01X1004358Y1123658D02*
X1004067Y1123950D01*
X1003900Y1124200D01*
X1003817Y1124533D01*
X1003900Y1124825D01*
X1004067Y1125033D01*
X1004317Y1125200D01*
X1004608Y1125242D01*
X1004858Y1125200D01*
X1005108Y1125033D01*
X1005317Y1124783D01*
X1005400Y1124492D01*
X1005317Y1124158D01*
X1005067Y1123867D01*
X1004692Y1123700D01*
X1004275Y1123658D01*
X1003733Y1123742D01*
X1003442Y1123867D01*
X1003150Y1124075D01*
X1002942Y1124367D01*
X1002900Y1124658D01*
X1002983Y1124950D01*
X1003192Y1125158D01*
G01X1020400Y1116100D02*
X1024400D01*
Y1123500D01*
G01X1018900Y1114317D02*
X1016400D01*
Y1115358D01*
X1016525Y1115692D01*
X1016692Y1115900D01*
X1017025Y1115983D01*
X1017358Y1115900D01*
X1017567Y1115650D01*
X1017692Y1115358D01*
Y1114317D01*
G01Y1115358D02*
X1018900Y1115983D01*
G01Y1118250D02*
X1016400D01*
X1016900Y1117750D01*
G01X1018900D02*
Y1118750D01*
G01X1016400Y1121350D02*
X1016483Y1121017D01*
X1016692Y1120767D01*
X1016942Y1120600D01*
X1017275Y1120475D01*
X1017650Y1120433D01*
X1018025Y1120475D01*
X1018358Y1120600D01*
X1018608Y1120767D01*
X1018817Y1121017D01*
X1018900Y1121350D01*
X1018817Y1121683D01*
X1018608Y1121933D01*
X1018358Y1122100D01*
X1018025Y1122225D01*
X1017650Y1122267D01*
X1017275Y1122225D01*
X1016942Y1122100D01*
X1016692Y1121933D01*
X1016483Y1121683D01*
X1016400Y1121350D01*
G01X1018900Y1124367D02*
X1018358Y1124450D01*
X1017900Y1124575D01*
X1017483Y1124742D01*
X1017025Y1124950D01*
X1016400Y1125283D01*
Y1123617D01*
G01X1037900Y1123500D02*
X1033900D01*
Y1116100D01*
G01X1014900Y1129617D02*
X1012400D01*
Y1130658D01*
X1012525Y1130992D01*
X1012692Y1131200D01*
X1013025Y1131283D01*
X1013358Y1131200D01*
X1013567Y1130950D01*
X1013692Y1130658D01*
Y1129617D01*
G01Y1130658D02*
X1014900Y1131283D01*
G01Y1133550D02*
X1014858Y1133842D01*
X1014733Y1134175D01*
X1014525Y1134383D01*
X1014233Y1134467D01*
X1013942Y1134383D01*
X1013692Y1134133D01*
X1013567Y1133758D01*
Y1133342D01*
X1013483Y1133092D01*
X1013275Y1132883D01*
X1012983Y1132800D01*
X1012692Y1132925D01*
X1012483Y1133217D01*
X1012400Y1133550D01*
X1012483Y1133883D01*
X1012692Y1134175D01*
X1012983Y1134300D01*
X1013275Y1134217D01*
X1013483Y1134008D01*
X1013567Y1133758D01*
Y1133342D01*
X1013692Y1132967D01*
X1013942Y1132717D01*
X1014233Y1132633D01*
X1014525Y1132717D01*
X1014733Y1132925D01*
X1014858Y1133258D01*
X1014900Y1133550D01*
G01X1019300Y1129617D02*
X1016800D01*
Y1130658D01*
X1016925Y1130992D01*
X1017092Y1131200D01*
X1017425Y1131283D01*
X1017758Y1131200D01*
X1017967Y1130950D01*
X1018092Y1130658D01*
Y1129617D01*
G01Y1130658D02*
X1019300Y1131283D01*
G01X1018800Y1132633D02*
X1019092Y1132883D01*
X1019258Y1133217D01*
X1019300Y1133592D01*
X1019258Y1133925D01*
X1019050Y1134258D01*
X1018800Y1134467D01*
X1018550Y1134508D01*
X1018258Y1134425D01*
X1018050Y1134133D01*
X1017967Y1133842D01*
Y1133467D01*
G01Y1133842D02*
X1017842Y1134092D01*
X1017633Y1134300D01*
X1017383Y1134383D01*
X1017133Y1134300D01*
X1016925Y1134092D01*
X1016800Y1133717D01*
X1016842Y1133342D01*
X1017008Y1132967D01*
G01X1005800Y1129617D02*
X1003300D01*
Y1130658D01*
X1003425Y1130992D01*
X1003592Y1131200D01*
X1003925Y1131283D01*
X1004258Y1131200D01*
X1004467Y1130950D01*
X1004592Y1130658D01*
Y1129617D01*
G01Y1130658D02*
X1005800Y1131283D01*
G01X1003717Y1132758D02*
X1003467Y1133008D01*
X1003342Y1133300D01*
X1003300Y1133633D01*
X1003383Y1134050D01*
X1003592Y1134342D01*
X1003842Y1134425D01*
X1004092Y1134383D01*
X1004300Y1134217D01*
X1004717Y1133383D01*
X1005008Y1133008D01*
X1005425Y1132758D01*
X1005800Y1132675D01*
Y1134425D01*
G01X1010200Y1129617D02*
X1007700D01*
Y1130658D01*
X1007825Y1130992D01*
X1007992Y1131200D01*
X1008325Y1131283D01*
X1008658Y1131200D01*
X1008867Y1130950D01*
X1008992Y1130658D01*
Y1129617D01*
G01Y1130658D02*
X1010200Y1131283D01*
G01Y1133467D02*
X1009658Y1133550D01*
X1009200Y1133675D01*
X1008783Y1133842D01*
X1008325Y1134050D01*
X1007700Y1134383D01*
Y1132717D01*
G01X1001200Y1129617D02*
X998700D01*
Y1130658D01*
X998825Y1130992D01*
X998992Y1131200D01*
X999325Y1131283D01*
X999658Y1131200D01*
X999867Y1130950D01*
X999992Y1130658D01*
Y1129617D01*
G01Y1130658D02*
X1001200Y1131283D01*
G01X1000158Y1132758D02*
X999867Y1133050D01*
X999700Y1133300D01*
X999617Y1133633D01*
X999700Y1133925D01*
X999867Y1134133D01*
X1000117Y1134300D01*
X1000408Y1134342D01*
X1000658Y1134300D01*
X1000908Y1134133D01*
X1001117Y1133883D01*
X1001200Y1133592D01*
X1001117Y1133258D01*
X1000867Y1132967D01*
X1000492Y1132800D01*
X1000075Y1132758D01*
X999533Y1132842D01*
X999242Y1132967D01*
X998950Y1133175D01*
X998742Y1133467D01*
X998700Y1133758D01*
X998783Y1134050D01*
X998992Y1134258D01*
G01X996500Y1129617D02*
X994000D01*
Y1130658D01*
X994125Y1130992D01*
X994292Y1131200D01*
X994625Y1131283D01*
X994958Y1131200D01*
X995167Y1130950D01*
X995292Y1130658D01*
Y1129617D01*
G01Y1130658D02*
X996500Y1131283D01*
G01Y1133550D02*
X994000D01*
X994500Y1133050D01*
G01X996500D02*
Y1134050D01*
G01X1014400Y1114317D02*
X1011900D01*
Y1115358D01*
X1012025Y1115692D01*
X1012192Y1115900D01*
X1012525Y1115983D01*
X1012858Y1115900D01*
X1013067Y1115650D01*
X1013192Y1115358D01*
Y1114317D01*
G01Y1115358D02*
X1014400Y1115983D01*
G01Y1118250D02*
X1011900D01*
X1012400Y1117750D01*
G01X1014400D02*
Y1118750D01*
G01X1011900Y1121350D02*
X1011983Y1121017D01*
X1012192Y1120767D01*
X1012442Y1120600D01*
X1012775Y1120475D01*
X1013150Y1120433D01*
X1013525Y1120475D01*
X1013858Y1120600D01*
X1014108Y1120767D01*
X1014317Y1121017D01*
X1014400Y1121350D01*
X1014317Y1121683D01*
X1014108Y1121933D01*
X1013858Y1122100D01*
X1013525Y1122225D01*
X1013150Y1122267D01*
X1012775Y1122225D01*
X1012442Y1122100D01*
X1012192Y1121933D01*
X1011983Y1121683D01*
X1011900Y1121350D01*
G01X1014400Y1124450D02*
X1011900D01*
X1012400Y1123950D01*
G01X1014400D02*
Y1124950D01*
G01X1029400Y1116100D02*
X1033400D01*
Y1123500D01*
G01X1009900Y1114317D02*
X1007400D01*
Y1115358D01*
X1007525Y1115692D01*
X1007692Y1115900D01*
X1008025Y1115983D01*
X1008358Y1115900D01*
X1008567Y1115650D01*
X1008692Y1115358D01*
Y1114317D01*
G01Y1115358D02*
X1009900Y1115983D01*
G01Y1118250D02*
X1007400D01*
X1007900Y1117750D01*
G01X1009900D02*
Y1118750D01*
G01X1007400Y1121350D02*
X1007483Y1121017D01*
X1007692Y1120767D01*
X1007942Y1120600D01*
X1008275Y1120475D01*
X1008650Y1120433D01*
X1009025Y1120475D01*
X1009358Y1120600D01*
X1009608Y1120767D01*
X1009817Y1121017D01*
X1009900Y1121350D01*
X1009817Y1121683D01*
X1009608Y1121933D01*
X1009358Y1122100D01*
X1009025Y1122225D01*
X1008650Y1122267D01*
X1008275Y1122225D01*
X1007942Y1122100D01*
X1007692Y1121933D01*
X1007483Y1121683D01*
X1007400Y1121350D01*
G01X1009525Y1123533D02*
X1009733Y1123783D01*
X1009858Y1124075D01*
X1009900Y1124450D01*
X1009817Y1124825D01*
X1009650Y1125117D01*
X1009358Y1125325D01*
X1009025Y1125367D01*
X1008692Y1125283D01*
X1008483Y1125075D01*
X1008317Y1124783D01*
X1008275Y1124492D01*
X1008317Y1124200D01*
X1008483Y1123825D01*
X1007400Y1123950D01*
Y1125075D01*
G01X1024900Y1116100D02*
X1028900D01*
Y1123500D01*
G01X1041834Y1115017D02*
X1039334D01*
Y1116058D01*
X1039459Y1116392D01*
X1039626Y1116600D01*
X1039959Y1116683D01*
X1040292Y1116600D01*
X1040501Y1116350D01*
X1040626Y1116058D01*
Y1115017D01*
G01Y1116058D02*
X1041834Y1116683D01*
G01Y1119450D02*
X1039334D01*
X1041126Y1117908D01*
Y1119992D01*
G01X1041334Y1121133D02*
X1041626Y1121383D01*
X1041792Y1121717D01*
X1041834Y1122092D01*
X1041792Y1122425D01*
X1041584Y1122758D01*
X1041334Y1122967D01*
X1041084Y1123008D01*
X1040792Y1122925D01*
X1040584Y1122633D01*
X1040501Y1122342D01*
Y1121967D01*
G01Y1122342D02*
X1040376Y1122592D01*
X1040167Y1122800D01*
X1039917Y1122883D01*
X1039667Y1122800D01*
X1039459Y1122592D01*
X1039334Y1122217D01*
X1039376Y1121842D01*
X1039542Y1121467D01*
G01X1041459Y1124233D02*
X1041667Y1124483D01*
X1041792Y1124775D01*
X1041834Y1125150D01*
X1041751Y1125525D01*
X1041584Y1125817D01*
X1041292Y1126025D01*
X1040959Y1126067D01*
X1040626Y1125983D01*
X1040417Y1125775D01*
X1040251Y1125483D01*
X1040209Y1125192D01*
X1040251Y1124900D01*
X1040417Y1124525D01*
X1039334Y1124650D01*
Y1125775D01*
G01X1017500Y1083983D02*
X1019292D01*
X1019667Y1084150D01*
X1019917Y1084483D01*
X1020000Y1084900D01*
X1019917Y1085317D01*
X1019667Y1085650D01*
X1019292Y1085817D01*
X1017500D01*
G01X1020000Y1088000D02*
X1017500D01*
X1018000Y1087500D01*
G01X1020000D02*
Y1088500D01*
G01X1017500Y1091100D02*
X1017583Y1090767D01*
X1017792Y1090517D01*
X1018042Y1090350D01*
X1018375Y1090225D01*
X1018750Y1090183D01*
X1019125Y1090225D01*
X1019458Y1090350D01*
X1019708Y1090517D01*
X1019917Y1090767D01*
X1020000Y1091100D01*
X1019917Y1091433D01*
X1019708Y1091683D01*
X1019458Y1091850D01*
X1019125Y1091975D01*
X1018750Y1092017D01*
X1018375Y1091975D01*
X1018042Y1091850D01*
X1017792Y1091683D01*
X1017583Y1091433D01*
X1017500Y1091100D01*
G01X1023350Y1098150D02*
X1026500Y1095000D01*
X1023350Y1091850D01*
G01X1006708Y1099817D02*
X1006583Y1099567D01*
X1006500Y1099275D01*
Y1098942D01*
X1006625Y1098567D01*
X1006833Y1098275D01*
X1007083Y1098067D01*
X1007500Y1097900D01*
X1007875Y1097858D01*
X1008250Y1097942D01*
X1008500Y1098067D01*
X1008750Y1098317D01*
X1008917Y1098608D01*
X1009000Y1098900D01*
Y1099192D01*
X1008917Y1099483D01*
X1008792Y1099733D01*
X1008625Y1099942D01*
G01X1008500Y1101083D02*
X1008792Y1101333D01*
X1008958Y1101667D01*
X1009000Y1102042D01*
X1008958Y1102375D01*
X1008750Y1102708D01*
X1008500Y1102917D01*
X1008250Y1102958D01*
X1007958Y1102875D01*
X1007750Y1102583D01*
X1007667Y1102292D01*
Y1101917D01*
G01Y1102292D02*
X1007542Y1102542D01*
X1007333Y1102750D01*
X1007083Y1102833D01*
X1006833Y1102750D01*
X1006625Y1102542D01*
X1006500Y1102167D01*
X1006542Y1101792D01*
X1006708Y1101417D01*
G01X1009000Y1105600D02*
X1006500D01*
X1008292Y1104058D01*
Y1106142D01*
G01X1010908Y1100417D02*
X1010783Y1100167D01*
X1010700Y1099875D01*
Y1099542D01*
X1010825Y1099167D01*
X1011033Y1098875D01*
X1011283Y1098667D01*
X1011700Y1098500D01*
X1012075Y1098458D01*
X1012450Y1098542D01*
X1012700Y1098667D01*
X1012950Y1098917D01*
X1013117Y1099208D01*
X1013200Y1099500D01*
Y1099792D01*
X1013117Y1100083D01*
X1012992Y1100333D01*
X1012825Y1100542D01*
G01X1012700Y1101683D02*
X1012992Y1101933D01*
X1013158Y1102267D01*
X1013200Y1102642D01*
X1013158Y1102975D01*
X1012950Y1103308D01*
X1012700Y1103517D01*
X1012450Y1103558D01*
X1012158Y1103475D01*
X1011950Y1103183D01*
X1011867Y1102892D01*
Y1102517D01*
G01Y1102892D02*
X1011742Y1103142D01*
X1011533Y1103350D01*
X1011283Y1103433D01*
X1011033Y1103350D01*
X1010825Y1103142D01*
X1010700Y1102767D01*
X1010742Y1102392D01*
X1010908Y1102017D01*
G01X1012700Y1104783D02*
X1012992Y1105033D01*
X1013158Y1105367D01*
X1013200Y1105742D01*
X1013158Y1106075D01*
X1012950Y1106408D01*
X1012700Y1106617D01*
X1012450Y1106658D01*
X1012158Y1106575D01*
X1011950Y1106283D01*
X1011867Y1105992D01*
Y1105617D01*
G01Y1105992D02*
X1011742Y1106242D01*
X1011533Y1106450D01*
X1011283Y1106533D01*
X1011033Y1106450D01*
X1010825Y1106242D01*
X1010700Y1105867D01*
X1010742Y1105492D01*
X1010908Y1105117D01*
G01X1015400Y1146200D02*
X1011400D01*
Y1138800D01*
G01X1015800D02*
X1019800D01*
Y1146200D01*
G01X1006300D02*
X1002300D01*
Y1138800D01*
G01X1006700D02*
X1010700D01*
Y1146200D01*
G01X1001700D02*
X997700D01*
Y1138800D01*
G01X993000D02*
X997000D01*
Y1146200D01*
G01X1019500Y1162533D02*
X1021292D01*
X1021667Y1162700D01*
X1021917Y1163033D01*
X1022000Y1163450D01*
X1021917Y1163867D01*
X1021667Y1164200D01*
X1021292Y1164367D01*
X1019500D01*
G01X1022000Y1166550D02*
X1019500D01*
X1020000Y1166050D01*
G01X1022000D02*
Y1167050D01*
G01X996300Y1166500D02*
X998400Y1164700D01*
X996300Y1162500D01*
G01X996200Y1158900D02*
X1015400D01*
Y1170100D01*
X996200D01*
Y1158900D01*
X996600D01*
G01X1021500Y1182617D02*
X1019000D01*
Y1183658D01*
X1019125Y1183992D01*
X1019292Y1184200D01*
X1019625Y1184283D01*
X1019958Y1184200D01*
X1020167Y1183950D01*
X1020292Y1183658D01*
Y1182617D01*
G01Y1183658D02*
X1021500Y1184283D01*
G01Y1187050D02*
X1019000D01*
X1020792Y1185508D01*
Y1187592D01*
G01X1007500Y1182300D02*
X1011500D01*
Y1189700D01*
G01X1026500Y1182617D02*
X1024000D01*
Y1183658D01*
X1024125Y1183992D01*
X1024292Y1184200D01*
X1024625Y1184283D01*
X1024958Y1184200D01*
X1025167Y1183950D01*
X1025292Y1183658D01*
Y1182617D01*
G01Y1183658D02*
X1026500Y1184283D01*
G01X1026125Y1185633D02*
X1026333Y1185883D01*
X1026458Y1186175D01*
X1026500Y1186550D01*
X1026417Y1186925D01*
X1026250Y1187217D01*
X1025958Y1187425D01*
X1025625Y1187467D01*
X1025292Y1187383D01*
X1025083Y1187175D01*
X1024917Y1186883D01*
X1024875Y1186592D01*
X1024917Y1186300D01*
X1025083Y1185925D01*
X1024000Y1186050D01*
Y1187175D01*
G01X1012500Y1182300D02*
X1016500D01*
Y1189700D01*
G01X1002500Y1182300D02*
X1006500D01*
Y1189700D01*
G01X1034667Y1258475D02*
X1034875Y1258808D01*
X1035000Y1259183D01*
Y1259517D01*
X1034875Y1259850D01*
X1034667Y1260100D01*
X1034375Y1260225D01*
X1034083Y1260142D01*
X1033833Y1259933D01*
X1033667Y1259558D01*
X1033583Y1259058D01*
X1033417Y1258767D01*
X1033125Y1258642D01*
X1032833Y1258725D01*
X1032625Y1258933D01*
X1032500Y1259225D01*
Y1259517D01*
X1032583Y1259808D01*
X1032792Y1260058D01*
G01X1035000Y1261408D02*
X1032500Y1262450D01*
X1035000Y1263492D01*
G01X1034125Y1263117D02*
Y1261783D01*
G01X1034667Y1264675D02*
X1034875Y1265008D01*
X1035000Y1265383D01*
Y1265717D01*
X1034875Y1266050D01*
X1034667Y1266300D01*
X1034375Y1266425D01*
X1034083Y1266342D01*
X1033833Y1266133D01*
X1033667Y1265758D01*
X1033583Y1265258D01*
X1033417Y1264967D01*
X1033125Y1264842D01*
X1032833Y1264925D01*
X1032625Y1265133D01*
X1032500Y1265425D01*
Y1265717D01*
X1032583Y1266008D01*
X1032792Y1266258D01*
G01X1035000Y1268650D02*
X1032500D01*
X1033000Y1268150D01*
G01X1035000D02*
Y1269150D01*
G01X1003555Y1320152D02*
Y1322652D01*
X1004596D01*
X1004930Y1322527D01*
X1005138Y1322360D01*
X1005221Y1322027D01*
X1005138Y1321694D01*
X1004888Y1321485D01*
X1004596Y1321360D01*
X1003555D01*
G01X1004596D02*
X1005221Y1320152D01*
G01X1006571Y1320652D02*
X1006821Y1320360D01*
X1007155Y1320194D01*
X1007530Y1320152D01*
X1007863Y1320194D01*
X1008196Y1320402D01*
X1008405Y1320652D01*
X1008446Y1320902D01*
X1008363Y1321194D01*
X1008071Y1321402D01*
X1007780Y1321485D01*
X1007405D01*
G01X1007780D02*
X1008030Y1321610D01*
X1008238Y1321819D01*
X1008321Y1322069D01*
X1008238Y1322319D01*
X1008030Y1322527D01*
X1007655Y1322652D01*
X1007280Y1322610D01*
X1006905Y1322444D01*
G01X1010588Y1320152D02*
X1010880Y1320194D01*
X1011213Y1320319D01*
X1011421Y1320527D01*
X1011505Y1320819D01*
X1011421Y1321110D01*
X1011171Y1321360D01*
X1010796Y1321485D01*
X1010380D01*
X1010130Y1321569D01*
X1009921Y1321777D01*
X1009838Y1322069D01*
X1009963Y1322360D01*
X1010255Y1322569D01*
X1010588Y1322652D01*
X1010921Y1322569D01*
X1011213Y1322360D01*
X1011338Y1322069D01*
X1011255Y1321777D01*
X1011046Y1321569D01*
X1010796Y1321485D01*
X1010380D01*
X1010005Y1321360D01*
X1009755Y1321110D01*
X1009671Y1320819D01*
X1009755Y1320527D01*
X1009963Y1320319D01*
X1010296Y1320194D01*
X1010588Y1320152D01*
G01X1012896Y1321194D02*
X1013188Y1321485D01*
X1013438Y1321652D01*
X1013771Y1321735D01*
X1014063Y1321652D01*
X1014271Y1321485D01*
X1014438Y1321235D01*
X1014480Y1320944D01*
X1014438Y1320694D01*
X1014271Y1320444D01*
X1014021Y1320235D01*
X1013730Y1320152D01*
X1013396Y1320235D01*
X1013105Y1320485D01*
X1012938Y1320860D01*
X1012896Y1321277D01*
X1012980Y1321819D01*
X1013105Y1322110D01*
X1013313Y1322402D01*
X1013605Y1322610D01*
X1013896Y1322652D01*
X1014188Y1322569D01*
X1014396Y1322360D01*
G01X1027529Y1326216D02*
Y1322216D01*
X1034929D01*
G01X1003555Y1323852D02*
Y1326352D01*
X1004596D01*
X1004930Y1326227D01*
X1005138Y1326060D01*
X1005221Y1325727D01*
X1005138Y1325394D01*
X1004888Y1325185D01*
X1004596Y1325060D01*
X1003555D01*
G01X1004596D02*
X1005221Y1323852D01*
G01X1006571Y1324352D02*
X1006821Y1324060D01*
X1007155Y1323894D01*
X1007530Y1323852D01*
X1007863Y1323894D01*
X1008196Y1324102D01*
X1008405Y1324352D01*
X1008446Y1324602D01*
X1008363Y1324894D01*
X1008071Y1325102D01*
X1007780Y1325185D01*
X1007405D01*
G01X1007780D02*
X1008030Y1325310D01*
X1008238Y1325519D01*
X1008321Y1325769D01*
X1008238Y1326019D01*
X1008030Y1326227D01*
X1007655Y1326352D01*
X1007280Y1326310D01*
X1006905Y1326144D01*
G01X1010588Y1323852D02*
X1010880Y1323894D01*
X1011213Y1324019D01*
X1011421Y1324227D01*
X1011505Y1324519D01*
X1011421Y1324810D01*
X1011171Y1325060D01*
X1010796Y1325185D01*
X1010380D01*
X1010130Y1325269D01*
X1009921Y1325477D01*
X1009838Y1325769D01*
X1009963Y1326060D01*
X1010255Y1326269D01*
X1010588Y1326352D01*
X1010921Y1326269D01*
X1011213Y1326060D01*
X1011338Y1325769D01*
X1011255Y1325477D01*
X1011046Y1325269D01*
X1010796Y1325185D01*
X1010380D01*
X1010005Y1325060D01*
X1009755Y1324810D01*
X1009671Y1324519D01*
X1009755Y1324227D01*
X1009963Y1324019D01*
X1010296Y1323894D01*
X1010588Y1323852D01*
G01X1013688D02*
X1013980Y1323894D01*
X1014313Y1324019D01*
X1014521Y1324227D01*
X1014605Y1324519D01*
X1014521Y1324810D01*
X1014271Y1325060D01*
X1013896Y1325185D01*
X1013480D01*
X1013230Y1325269D01*
X1013021Y1325477D01*
X1012938Y1325769D01*
X1013063Y1326060D01*
X1013355Y1326269D01*
X1013688Y1326352D01*
X1014021Y1326269D01*
X1014313Y1326060D01*
X1014438Y1325769D01*
X1014355Y1325477D01*
X1014146Y1325269D01*
X1013896Y1325185D01*
X1013480D01*
X1013105Y1325060D01*
X1012855Y1324810D01*
X1012771Y1324519D01*
X1012855Y1324227D01*
X1013063Y1324019D01*
X1013396Y1323894D01*
X1013688Y1323852D01*
G01X1011204Y1340530D02*
Y1343030D01*
X1012245D01*
X1012579Y1342905D01*
X1012787Y1342738D01*
X1012870Y1342405D01*
X1012787Y1342072D01*
X1012537Y1341863D01*
X1012245Y1341738D01*
X1011204D01*
G01X1012245D02*
X1012870Y1340530D01*
G01X1014429Y1340822D02*
X1014720Y1340613D01*
X1015054Y1340530D01*
X1015387Y1340613D01*
X1015679Y1340863D01*
X1015887Y1341238D01*
X1015970Y1341613D01*
Y1342072D01*
X1015887Y1342447D01*
X1015679Y1342780D01*
X1015429Y1342947D01*
X1015137Y1343030D01*
X1014804Y1342947D01*
X1014554Y1342780D01*
X1014387Y1342530D01*
X1014304Y1342197D01*
X1014387Y1341905D01*
X1014595Y1341613D01*
X1014845Y1341447D01*
X1015137Y1341405D01*
X1015470Y1341488D01*
X1015720Y1341697D01*
X1015970Y1342072D01*
G01X1018237Y1340530D02*
X1018529Y1340572D01*
X1018862Y1340697D01*
X1019070Y1340905D01*
X1019154Y1341197D01*
X1019070Y1341488D01*
X1018820Y1341738D01*
X1018445Y1341863D01*
X1018029D01*
X1017779Y1341947D01*
X1017570Y1342155D01*
X1017487Y1342447D01*
X1017612Y1342738D01*
X1017904Y1342947D01*
X1018237Y1343030D01*
X1018570Y1342947D01*
X1018862Y1342738D01*
X1018987Y1342447D01*
X1018904Y1342155D01*
X1018695Y1341947D01*
X1018445Y1341863D01*
X1018029D01*
X1017654Y1341738D01*
X1017404Y1341488D01*
X1017320Y1341197D01*
X1017404Y1340905D01*
X1017612Y1340697D01*
X1017945Y1340572D01*
X1018237Y1340530D01*
G01X1021337D02*
Y1343030D01*
X1020837Y1342530D01*
G01Y1340530D02*
X1021837D01*
G01X1040074Y1352526D02*
Y1356526D01*
X1032674D01*
G01X1011204Y1336830D02*
Y1339330D01*
X1012245D01*
X1012579Y1339205D01*
X1012787Y1339038D01*
X1012870Y1338705D01*
X1012787Y1338372D01*
X1012537Y1338163D01*
X1012245Y1338038D01*
X1011204D01*
G01X1012245D02*
X1012870Y1336830D01*
G01X1014429Y1337122D02*
X1014720Y1336913D01*
X1015054Y1336830D01*
X1015387Y1336913D01*
X1015679Y1337163D01*
X1015887Y1337538D01*
X1015970Y1337913D01*
Y1338372D01*
X1015887Y1338747D01*
X1015679Y1339080D01*
X1015429Y1339247D01*
X1015137Y1339330D01*
X1014804Y1339247D01*
X1014554Y1339080D01*
X1014387Y1338830D01*
X1014304Y1338497D01*
X1014387Y1338205D01*
X1014595Y1337913D01*
X1014845Y1337747D01*
X1015137Y1337705D01*
X1015470Y1337788D01*
X1015720Y1337997D01*
X1015970Y1338372D01*
G01X1018237Y1336830D02*
X1018529Y1336872D01*
X1018862Y1336997D01*
X1019070Y1337205D01*
X1019154Y1337497D01*
X1019070Y1337788D01*
X1018820Y1338038D01*
X1018445Y1338163D01*
X1018029D01*
X1017779Y1338247D01*
X1017570Y1338455D01*
X1017487Y1338747D01*
X1017612Y1339038D01*
X1017904Y1339247D01*
X1018237Y1339330D01*
X1018570Y1339247D01*
X1018862Y1339038D01*
X1018987Y1338747D01*
X1018904Y1338455D01*
X1018695Y1338247D01*
X1018445Y1338163D01*
X1018029D01*
X1017654Y1338038D01*
X1017404Y1337788D01*
X1017320Y1337497D01*
X1017404Y1337205D01*
X1017612Y1336997D01*
X1017945Y1336872D01*
X1018237Y1336830D01*
G01X1021337Y1339330D02*
X1021004Y1339247D01*
X1020754Y1339038D01*
X1020587Y1338788D01*
X1020462Y1338455D01*
X1020420Y1338080D01*
X1020462Y1337705D01*
X1020587Y1337372D01*
X1020754Y1337122D01*
X1021004Y1336913D01*
X1021337Y1336830D01*
X1021670Y1336913D01*
X1021920Y1337122D01*
X1022087Y1337372D01*
X1022212Y1337705D01*
X1022254Y1338080D01*
X1022212Y1338455D01*
X1022087Y1338788D01*
X1021920Y1339038D01*
X1021670Y1339247D01*
X1021337Y1339330D01*
G01X1032653Y1351992D02*
Y1347992D01*
X1040053D01*
G01X1003626Y1328756D02*
Y1331256D01*
X1004667D01*
X1005001Y1331131D01*
X1005209Y1330964D01*
X1005292Y1330631D01*
X1005209Y1330298D01*
X1004959Y1330089D01*
X1004667Y1329964D01*
X1003626D01*
G01X1004667D02*
X1005292Y1328756D01*
G01X1006642Y1329256D02*
X1006892Y1328964D01*
X1007226Y1328798D01*
X1007601Y1328756D01*
X1007934Y1328798D01*
X1008267Y1329006D01*
X1008476Y1329256D01*
X1008517Y1329506D01*
X1008434Y1329798D01*
X1008142Y1330006D01*
X1007851Y1330089D01*
X1007476D01*
G01X1007851D02*
X1008101Y1330214D01*
X1008309Y1330423D01*
X1008392Y1330673D01*
X1008309Y1330923D01*
X1008101Y1331131D01*
X1007726Y1331256D01*
X1007351Y1331214D01*
X1006976Y1331048D01*
G01X1010659Y1328756D02*
X1010951Y1328798D01*
X1011284Y1328923D01*
X1011492Y1329131D01*
X1011576Y1329423D01*
X1011492Y1329714D01*
X1011242Y1329964D01*
X1010867Y1330089D01*
X1010451D01*
X1010201Y1330173D01*
X1009992Y1330381D01*
X1009909Y1330673D01*
X1010034Y1330964D01*
X1010326Y1331173D01*
X1010659Y1331256D01*
X1010992Y1331173D01*
X1011284Y1330964D01*
X1011409Y1330673D01*
X1011326Y1330381D01*
X1011117Y1330173D01*
X1010867Y1330089D01*
X1010451D01*
X1010076Y1329964D01*
X1009826Y1329714D01*
X1009742Y1329423D01*
X1009826Y1329131D01*
X1010034Y1328923D01*
X1010367Y1328798D01*
X1010659Y1328756D01*
G01X1013759D02*
Y1331256D01*
X1013259Y1330756D01*
G01Y1328756D02*
X1014259D01*
G01X1027529Y1339616D02*
Y1335616D01*
X1034929D01*
G01X1003626Y1332456D02*
Y1334956D01*
X1004667D01*
X1005001Y1334831D01*
X1005209Y1334664D01*
X1005292Y1334331D01*
X1005209Y1333998D01*
X1004959Y1333789D01*
X1004667Y1333664D01*
X1003626D01*
G01X1004667D02*
X1005292Y1332456D01*
G01X1006642Y1332956D02*
X1006892Y1332664D01*
X1007226Y1332498D01*
X1007601Y1332456D01*
X1007934Y1332498D01*
X1008267Y1332706D01*
X1008476Y1332956D01*
X1008517Y1333206D01*
X1008434Y1333498D01*
X1008142Y1333706D01*
X1007851Y1333789D01*
X1007476D01*
G01X1007851D02*
X1008101Y1333914D01*
X1008309Y1334123D01*
X1008392Y1334373D01*
X1008309Y1334623D01*
X1008101Y1334831D01*
X1007726Y1334956D01*
X1007351Y1334914D01*
X1006976Y1334748D01*
G01X1010659Y1332456D02*
X1010951Y1332498D01*
X1011284Y1332623D01*
X1011492Y1332831D01*
X1011576Y1333123D01*
X1011492Y1333414D01*
X1011242Y1333664D01*
X1010867Y1333789D01*
X1010451D01*
X1010201Y1333873D01*
X1009992Y1334081D01*
X1009909Y1334373D01*
X1010034Y1334664D01*
X1010326Y1334873D01*
X1010659Y1334956D01*
X1010992Y1334873D01*
X1011284Y1334664D01*
X1011409Y1334373D01*
X1011326Y1334081D01*
X1011117Y1333873D01*
X1010867Y1333789D01*
X1010451D01*
X1010076Y1333664D01*
X1009826Y1333414D01*
X1009742Y1333123D01*
X1009826Y1332831D01*
X1010034Y1332623D01*
X1010367Y1332498D01*
X1010659Y1332456D01*
G01X1012842Y1332831D02*
X1013092Y1332623D01*
X1013384Y1332498D01*
X1013759Y1332456D01*
X1014134Y1332539D01*
X1014426Y1332706D01*
X1014634Y1332998D01*
X1014676Y1333331D01*
X1014592Y1333664D01*
X1014384Y1333873D01*
X1014092Y1334039D01*
X1013801Y1334081D01*
X1013509Y1334039D01*
X1013134Y1333873D01*
X1013259Y1334956D01*
X1014384D01*
G01X1027629Y1344668D02*
Y1340668D01*
X1035029D01*
G01X1027529Y1332916D02*
Y1328916D01*
X1034929D01*
G01X1013417Y1449500D02*
Y1452000D01*
X1014458D01*
X1014792Y1451875D01*
X1015000Y1451708D01*
X1015083Y1451375D01*
X1015000Y1451042D01*
X1014750Y1450833D01*
X1014458Y1450708D01*
X1013417D01*
G01X1014458D02*
X1015083Y1449500D01*
G01X1017350D02*
Y1452000D01*
X1016850Y1451500D01*
G01Y1449500D02*
X1017850D01*
G01X1020450D02*
Y1452000D01*
X1019950Y1451500D01*
G01Y1449500D02*
X1020950D01*
G01X1023467D02*
X1023550Y1450042D01*
X1023675Y1450500D01*
X1023842Y1450917D01*
X1024050Y1451375D01*
X1024383Y1452000D01*
X1022717D01*
G01X1027150Y1449500D02*
Y1452000D01*
X1025608Y1450208D01*
X1027692D01*
G01X1021983Y1470825D02*
Y1465625D01*
G01X1014983Y1470825D02*
Y1463025D01*
G01X1021983Y1457425D02*
Y1466125D01*
G01X1014983Y1457425D02*
X1021983D01*
G01X1014983Y1463825D02*
Y1457425D01*
G01X1021983Y1470825D02*
X1014983D01*
G01X1026155Y1478511D02*
Y1508511D01*
X1048955D01*
Y1478511D01*
X1026155D01*
G01X998355D02*
Y1508511D01*
X1021155D01*
Y1478511D01*
X998355D01*
G01X993874Y1485439D02*
X991374D01*
Y1486480D01*
X991499Y1486814D01*
X991666Y1487022D01*
X991999Y1487105D01*
X992332Y1487022D01*
X992541Y1486772D01*
X992666Y1486480D01*
Y1485439D01*
G01Y1486480D02*
X993874Y1487105D01*
G01Y1489372D02*
X991374D01*
X991874Y1488872D01*
G01X993874D02*
Y1489872D01*
G01Y1492472D02*
X991374D01*
X991874Y1491972D01*
G01X993874D02*
Y1492972D01*
G01Y1496072D02*
X991374D01*
X993166Y1494530D01*
Y1496614D01*
G01X991374Y1498672D02*
X991457Y1498339D01*
X991666Y1498089D01*
X991916Y1497922D01*
X992249Y1497797D01*
X992624Y1497755D01*
X992999Y1497797D01*
X993332Y1497922D01*
X993582Y1498089D01*
X993791Y1498339D01*
X993874Y1498672D01*
X993791Y1499005D01*
X993582Y1499255D01*
X993332Y1499422D01*
X992999Y1499547D01*
X992624Y1499589D01*
X992249Y1499547D01*
X991916Y1499422D01*
X991666Y1499255D01*
X991457Y1499005D01*
X991374Y1498672D01*
G01X1035286Y1515547D02*
X1004286D01*
Y1559547D01*
X1035286D01*
Y1515547D01*
G01X1001123Y1541333D02*
X998623D01*
Y1542374D01*
X998748Y1542708D01*
X998915Y1542916D01*
X999248Y1542999D01*
X999581Y1542916D01*
X999790Y1542666D01*
X999915Y1542374D01*
Y1541333D01*
G01Y1542374D02*
X1001123Y1542999D01*
G01Y1545266D02*
X998623D01*
X999123Y1544766D01*
G01X1001123D02*
Y1545766D01*
G01Y1548366D02*
X998623D01*
X999123Y1547866D01*
G01X1001123D02*
Y1548866D01*
G01X1000081Y1550674D02*
X999790Y1550966D01*
X999623Y1551216D01*
X999540Y1551549D01*
X999623Y1551841D01*
X999790Y1552049D01*
X1000040Y1552216D01*
X1000331Y1552258D01*
X1000581Y1552216D01*
X1000831Y1552049D01*
X1001040Y1551799D01*
X1001123Y1551508D01*
X1001040Y1551174D01*
X1000790Y1550883D01*
X1000415Y1550716D01*
X999998Y1550674D01*
X999456Y1550758D01*
X999165Y1550883D01*
X998873Y1551091D01*
X998665Y1551383D01*
X998623Y1551674D01*
X998706Y1551966D01*
X998915Y1552174D01*
G01X1000081Y1553774D02*
X999790Y1554066D01*
X999623Y1554316D01*
X999540Y1554649D01*
X999623Y1554941D01*
X999790Y1555149D01*
X1000040Y1555316D01*
X1000331Y1555358D01*
X1000581Y1555316D01*
X1000831Y1555149D01*
X1001040Y1554899D01*
X1001123Y1554608D01*
X1001040Y1554274D01*
X1000790Y1553983D01*
X1000415Y1553816D01*
X999998Y1553774D01*
X999456Y1553858D01*
X999165Y1553983D01*
X998873Y1554191D01*
X998665Y1554483D01*
X998623Y1554774D01*
X998706Y1555066D01*
X998915Y1555274D01*
G01X1075734Y-99683D02*
X1073234D01*
Y-98642D01*
X1073359Y-98308D01*
X1073526Y-98100D01*
X1073859Y-98017D01*
X1074192Y-98100D01*
X1074401Y-98350D01*
X1074526Y-98642D01*
Y-99683D01*
G01Y-98642D02*
X1075734Y-98017D01*
G01X1074692Y-96542D02*
X1074401Y-96250D01*
X1074234Y-96000D01*
X1074151Y-95667D01*
X1074234Y-95375D01*
X1074401Y-95167D01*
X1074651Y-95000D01*
X1074942Y-94958D01*
X1075192Y-95000D01*
X1075442Y-95167D01*
X1075651Y-95417D01*
X1075734Y-95708D01*
X1075651Y-96042D01*
X1075401Y-96333D01*
X1075026Y-96500D01*
X1074609Y-96542D01*
X1074067Y-96458D01*
X1073776Y-96333D01*
X1073484Y-96125D01*
X1073276Y-95833D01*
X1073234Y-95542D01*
X1073317Y-95250D01*
X1073526Y-95042D01*
G01X1075734Y-92650D02*
X1073234D01*
X1073734Y-93150D01*
G01X1075734D02*
Y-92150D01*
G01X1074692Y-90342D02*
X1074401Y-90050D01*
X1074234Y-89800D01*
X1074151Y-89467D01*
X1074234Y-89175D01*
X1074401Y-88967D01*
X1074651Y-88800D01*
X1074942Y-88758D01*
X1075192Y-88800D01*
X1075442Y-88967D01*
X1075651Y-89217D01*
X1075734Y-89508D01*
X1075651Y-89842D01*
X1075401Y-90133D01*
X1075026Y-90300D01*
X1074609Y-90342D01*
X1074067Y-90258D01*
X1073776Y-90133D01*
X1073484Y-89925D01*
X1073276Y-89633D01*
X1073234Y-89342D01*
X1073317Y-89050D01*
X1073526Y-88842D01*
G01X1076400Y-71668D02*
X1072400D01*
Y-79068D01*
G01X1083517Y-95334D02*
Y-92834D01*
X1084558D01*
X1084892Y-92959D01*
X1085100Y-93126D01*
X1085183Y-93459D01*
X1085100Y-93792D01*
X1084850Y-94001D01*
X1084558Y-94126D01*
X1083517D01*
G01X1084558D02*
X1085183Y-95334D01*
G01X1086658Y-94292D02*
X1086950Y-94001D01*
X1087200Y-93834D01*
X1087533Y-93751D01*
X1087825Y-93834D01*
X1088033Y-94001D01*
X1088200Y-94251D01*
X1088242Y-94542D01*
X1088200Y-94792D01*
X1088033Y-95042D01*
X1087783Y-95251D01*
X1087492Y-95334D01*
X1087158Y-95251D01*
X1086867Y-95001D01*
X1086700Y-94626D01*
X1086658Y-94209D01*
X1086742Y-93667D01*
X1086867Y-93376D01*
X1087075Y-93084D01*
X1087367Y-92876D01*
X1087658Y-92834D01*
X1087950Y-92917D01*
X1088158Y-93126D01*
G01X1089633Y-94834D02*
X1089883Y-95126D01*
X1090217Y-95292D01*
X1090592Y-95334D01*
X1090925Y-95292D01*
X1091258Y-95084D01*
X1091467Y-94834D01*
X1091508Y-94584D01*
X1091425Y-94292D01*
X1091133Y-94084D01*
X1090842Y-94001D01*
X1090467D01*
G01X1090842D02*
X1091092Y-93876D01*
X1091300Y-93667D01*
X1091383Y-93417D01*
X1091300Y-93167D01*
X1091092Y-92959D01*
X1090717Y-92834D01*
X1090342Y-92876D01*
X1089967Y-93042D01*
G01X1092733Y-94834D02*
X1092983Y-95126D01*
X1093317Y-95292D01*
X1093692Y-95334D01*
X1094025Y-95292D01*
X1094358Y-95084D01*
X1094567Y-94834D01*
X1094608Y-94584D01*
X1094525Y-94292D01*
X1094233Y-94084D01*
X1093942Y-94001D01*
X1093567D01*
G01X1093942D02*
X1094192Y-93876D01*
X1094400Y-93667D01*
X1094483Y-93417D01*
X1094400Y-93167D01*
X1094192Y-92959D01*
X1093817Y-92834D01*
X1093442Y-92876D01*
X1093067Y-93042D01*
G01X1083868Y-85500D02*
Y-89500D01*
X1091268D01*
G01X1057309Y-91301D02*
Y-88801D01*
X1058350D01*
X1058684Y-88926D01*
X1058892Y-89093D01*
X1058975Y-89426D01*
X1058892Y-89759D01*
X1058642Y-89968D01*
X1058350Y-90093D01*
X1057309D01*
G01X1058350D02*
X1058975Y-91301D01*
G01X1061242D02*
Y-88801D01*
X1060742Y-89301D01*
G01Y-91301D02*
X1061742D01*
G01X1064842D02*
Y-88801D01*
X1063300Y-90593D01*
X1065384D01*
G01X1067442Y-91301D02*
Y-88801D01*
X1066942Y-89301D01*
G01Y-91301D02*
X1067942D01*
G01X1060171Y-78978D02*
Y-82978D01*
X1067571D01*
G01X1057309Y-87601D02*
Y-85101D01*
X1058350D01*
X1058684Y-85226D01*
X1058892Y-85393D01*
X1058975Y-85726D01*
X1058892Y-86059D01*
X1058642Y-86268D01*
X1058350Y-86393D01*
X1057309D01*
G01X1058350D02*
X1058975Y-87601D01*
G01X1061242D02*
Y-85101D01*
X1060742Y-85601D01*
G01Y-87601D02*
X1061742D01*
G01X1064842D02*
Y-85101D01*
X1063300Y-86893D01*
X1065384D01*
G01X1067442Y-85101D02*
X1067109Y-85184D01*
X1066859Y-85393D01*
X1066692Y-85643D01*
X1066567Y-85976D01*
X1066525Y-86351D01*
X1066567Y-86726D01*
X1066692Y-87059D01*
X1066859Y-87309D01*
X1067109Y-87518D01*
X1067442Y-87601D01*
X1067775Y-87518D01*
X1068025Y-87309D01*
X1068192Y-87059D01*
X1068317Y-86726D01*
X1068359Y-86351D01*
X1068317Y-85976D01*
X1068192Y-85643D01*
X1068025Y-85393D01*
X1067775Y-85184D01*
X1067442Y-85101D01*
G01X1067521Y-78578D02*
Y-74578D01*
X1060121D01*
G01X1083600Y-80432D02*
X1095000D01*
G01X1083600Y-67032D02*
Y-80432D01*
G01X1051257Y-92926D02*
X1051007Y-92801D01*
X1050715Y-92718D01*
X1050382D01*
X1050007Y-92843D01*
X1049715Y-93051D01*
X1049507Y-93301D01*
X1049340Y-93718D01*
X1049298Y-94093D01*
X1049382Y-94468D01*
X1049507Y-94718D01*
X1049757Y-94968D01*
X1050048Y-95135D01*
X1050340Y-95218D01*
X1050632D01*
X1050923Y-95135D01*
X1051173Y-95010D01*
X1051382Y-94843D01*
G01X1053440Y-95218D02*
X1053732Y-95176D01*
X1054065Y-95051D01*
X1054273Y-94843D01*
X1054357Y-94551D01*
X1054273Y-94260D01*
X1054023Y-94010D01*
X1053648Y-93885D01*
X1053232D01*
X1052982Y-93801D01*
X1052773Y-93593D01*
X1052690Y-93301D01*
X1052815Y-93010D01*
X1053107Y-92801D01*
X1053440Y-92718D01*
X1053773Y-92801D01*
X1054065Y-93010D01*
X1054190Y-93301D01*
X1054107Y-93593D01*
X1053898Y-93801D01*
X1053648Y-93885D01*
X1053232D01*
X1052857Y-94010D01*
X1052607Y-94260D01*
X1052523Y-94551D01*
X1052607Y-94843D01*
X1052815Y-95051D01*
X1053148Y-95176D01*
X1053440Y-95218D01*
G01X1055832Y-94926D02*
X1056123Y-95135D01*
X1056457Y-95218D01*
X1056790Y-95135D01*
X1057082Y-94885D01*
X1057290Y-94510D01*
X1057373Y-94135D01*
Y-93676D01*
X1057290Y-93301D01*
X1057082Y-92968D01*
X1056832Y-92801D01*
X1056540Y-92718D01*
X1056207Y-92801D01*
X1055957Y-92968D01*
X1055790Y-93218D01*
X1055707Y-93551D01*
X1055790Y-93843D01*
X1055998Y-94135D01*
X1056248Y-94301D01*
X1056540Y-94343D01*
X1056873Y-94260D01*
X1057123Y-94051D01*
X1057373Y-93676D01*
G01X1043817Y-99708D02*
X1043567Y-99583D01*
X1043275Y-99500D01*
X1042942D01*
X1042567Y-99625D01*
X1042275Y-99833D01*
X1042067Y-100083D01*
X1041900Y-100500D01*
X1041858Y-100875D01*
X1041942Y-101250D01*
X1042067Y-101500D01*
X1042317Y-101750D01*
X1042608Y-101917D01*
X1042900Y-102000D01*
X1043192D01*
X1043483Y-101917D01*
X1043733Y-101792D01*
X1043942Y-101625D01*
G01X1045917Y-102000D02*
X1046000Y-101458D01*
X1046125Y-101000D01*
X1046292Y-100583D01*
X1046500Y-100125D01*
X1046833Y-99500D01*
X1045167D01*
G01X1048308Y-100958D02*
X1048600Y-100667D01*
X1048850Y-100500D01*
X1049183Y-100417D01*
X1049475Y-100500D01*
X1049683Y-100667D01*
X1049850Y-100917D01*
X1049892Y-101208D01*
X1049850Y-101458D01*
X1049683Y-101708D01*
X1049433Y-101917D01*
X1049142Y-102000D01*
X1048808Y-101917D01*
X1048517Y-101667D01*
X1048350Y-101292D01*
X1048308Y-100875D01*
X1048392Y-100333D01*
X1048517Y-100042D01*
X1048725Y-99750D01*
X1049017Y-99542D01*
X1049308Y-99500D01*
X1049600Y-99583D01*
X1049808Y-99792D01*
G01X1049197Y-91067D02*
X1055397D01*
Y-78667D01*
X1049197D01*
G01X1045112Y-36608D02*
X1041112D01*
Y-44008D01*
G01X1063500Y-37205D02*
X1061000D01*
Y-36164D01*
X1061125Y-35830D01*
X1061292Y-35622D01*
X1061625Y-35539D01*
X1061958Y-35622D01*
X1062167Y-35872D01*
X1062292Y-36164D01*
Y-37205D01*
G01Y-36164D02*
X1063500Y-35539D01*
G01Y-33272D02*
X1061000D01*
X1061500Y-33772D01*
G01X1063500D02*
Y-32772D01*
G01X1063000Y-31089D02*
X1063292Y-30839D01*
X1063458Y-30505D01*
X1063500Y-30130D01*
X1063458Y-29797D01*
X1063250Y-29464D01*
X1063000Y-29255D01*
X1062750Y-29214D01*
X1062458Y-29297D01*
X1062250Y-29589D01*
X1062167Y-29880D01*
Y-30255D01*
G01Y-29880D02*
X1062042Y-29630D01*
X1061833Y-29422D01*
X1061583Y-29339D01*
X1061333Y-29422D01*
X1061125Y-29630D01*
X1061000Y-30005D01*
X1061042Y-30380D01*
X1061208Y-30755D01*
G01X1063208Y-27780D02*
X1063417Y-27489D01*
X1063500Y-27155D01*
X1063417Y-26822D01*
X1063167Y-26530D01*
X1062792Y-26322D01*
X1062417Y-26239D01*
X1061958D01*
X1061583Y-26322D01*
X1061250Y-26530D01*
X1061083Y-26780D01*
X1061000Y-27072D01*
X1061083Y-27405D01*
X1061250Y-27655D01*
X1061500Y-27822D01*
X1061833Y-27905D01*
X1062125Y-27822D01*
X1062417Y-27614D01*
X1062583Y-27364D01*
X1062625Y-27072D01*
X1062542Y-26739D01*
X1062333Y-26489D01*
X1061958Y-26239D01*
G01X1059325Y-49400D02*
X1063325D01*
Y-42000D01*
G01X1067200Y-37205D02*
X1064700D01*
Y-36164D01*
X1064825Y-35830D01*
X1064992Y-35622D01*
X1065325Y-35539D01*
X1065658Y-35622D01*
X1065867Y-35872D01*
X1065992Y-36164D01*
Y-37205D01*
G01Y-36164D02*
X1067200Y-35539D01*
G01Y-33272D02*
X1064700D01*
X1065200Y-33772D01*
G01X1067200D02*
Y-32772D01*
G01X1066700Y-31089D02*
X1066992Y-30839D01*
X1067158Y-30505D01*
X1067200Y-30130D01*
X1067158Y-29797D01*
X1066950Y-29464D01*
X1066700Y-29255D01*
X1066450Y-29214D01*
X1066158Y-29297D01*
X1065950Y-29589D01*
X1065867Y-29880D01*
Y-30255D01*
G01Y-29880D02*
X1065742Y-29630D01*
X1065533Y-29422D01*
X1065283Y-29339D01*
X1065033Y-29422D01*
X1064825Y-29630D01*
X1064700Y-30005D01*
X1064742Y-30380D01*
X1064908Y-30755D01*
G01X1067200Y-27072D02*
X1067158Y-26780D01*
X1067033Y-26447D01*
X1066825Y-26239D01*
X1066533Y-26155D01*
X1066242Y-26239D01*
X1065992Y-26489D01*
X1065867Y-26864D01*
Y-27280D01*
X1065783Y-27530D01*
X1065575Y-27739D01*
X1065283Y-27822D01*
X1064992Y-27697D01*
X1064783Y-27405D01*
X1064700Y-27072D01*
X1064783Y-26739D01*
X1064992Y-26447D01*
X1065283Y-26322D01*
X1065575Y-26405D01*
X1065783Y-26614D01*
X1065867Y-26864D01*
Y-27280D01*
X1065992Y-27655D01*
X1066242Y-27905D01*
X1066533Y-27989D01*
X1066825Y-27905D01*
X1067033Y-27697D01*
X1067158Y-27364D01*
X1067200Y-27072D01*
G01X1068225Y-42000D02*
X1064225D01*
Y-49400D01*
G01X1083850Y-58300D02*
Y-62300D01*
X1091250D01*
G01X1075801Y-37183D02*
X1073301D01*
Y-36142D01*
X1073426Y-35808D01*
X1073593Y-35600D01*
X1073926Y-35517D01*
X1074259Y-35600D01*
X1074468Y-35850D01*
X1074593Y-36142D01*
Y-37183D01*
G01Y-36142D02*
X1075801Y-35517D01*
G01X1074759Y-34042D02*
X1074468Y-33750D01*
X1074301Y-33500D01*
X1074218Y-33167D01*
X1074301Y-32875D01*
X1074468Y-32667D01*
X1074718Y-32500D01*
X1075009Y-32458D01*
X1075259Y-32500D01*
X1075509Y-32667D01*
X1075718Y-32917D01*
X1075801Y-33208D01*
X1075718Y-33542D01*
X1075468Y-33833D01*
X1075093Y-34000D01*
X1074676Y-34042D01*
X1074134Y-33958D01*
X1073843Y-33833D01*
X1073551Y-33625D01*
X1073343Y-33333D01*
X1073301Y-33042D01*
X1073384Y-32750D01*
X1073593Y-32542D01*
G01X1075801Y-30150D02*
X1073301D01*
X1073801Y-30650D01*
G01X1075801D02*
Y-29650D01*
G01X1075426Y-27967D02*
X1075634Y-27717D01*
X1075759Y-27425D01*
X1075801Y-27050D01*
X1075718Y-26675D01*
X1075551Y-26383D01*
X1075259Y-26175D01*
X1074926Y-26133D01*
X1074593Y-26217D01*
X1074384Y-26425D01*
X1074218Y-26717D01*
X1074176Y-27008D01*
X1074218Y-27300D01*
X1074384Y-27675D01*
X1073301Y-27550D01*
Y-26425D01*
G01X1072400Y-47732D02*
X1076400D01*
Y-40332D01*
G01X1067483Y-52461D02*
X1067150Y-52419D01*
X1066858Y-52253D01*
X1066608Y-52003D01*
X1066441Y-51711D01*
X1066358Y-51378D01*
Y-51044D01*
X1066441Y-50711D01*
X1066608Y-50419D01*
X1066858Y-50169D01*
X1067150Y-50003D01*
X1067483Y-49961D01*
X1067816Y-50003D01*
X1068108Y-50169D01*
X1068358Y-50419D01*
X1068525Y-50711D01*
X1068608Y-51044D01*
Y-51378D01*
X1068525Y-51711D01*
X1068358Y-52003D01*
X1068108Y-52253D01*
X1067816Y-52419D01*
X1067483Y-52461D01*
G01X1067816Y-51794D02*
X1068316Y-52461D01*
G01X1071083D02*
Y-49961D01*
X1069541Y-51753D01*
X1071625D01*
G01X1068700Y-66832D02*
X1080100D01*
G01X1068700Y-53432D02*
Y-66832D01*
G01X1080100Y-53432D02*
X1068700D01*
G01X1080100Y-66832D02*
Y-53432D01*
G01X1082232Y-74950D02*
X1082190Y-75283D01*
X1082024Y-75575D01*
X1081774Y-75825D01*
X1081482Y-75992D01*
X1081149Y-76075D01*
X1080815D01*
X1080482Y-75992D01*
X1080190Y-75825D01*
X1079940Y-75575D01*
X1079774Y-75283D01*
X1079732Y-74950D01*
X1079774Y-74617D01*
X1079940Y-74325D01*
X1080190Y-74075D01*
X1080482Y-73908D01*
X1080815Y-73825D01*
X1081149D01*
X1081482Y-73908D01*
X1081774Y-74075D01*
X1082024Y-74325D01*
X1082190Y-74617D01*
X1082232Y-74950D01*
G01X1081565Y-74617D02*
X1082232Y-74117D01*
G01X1081732Y-72767D02*
X1082024Y-72517D01*
X1082190Y-72183D01*
X1082232Y-71808D01*
X1082190Y-71475D01*
X1081982Y-71142D01*
X1081732Y-70933D01*
X1081482Y-70892D01*
X1081190Y-70975D01*
X1080982Y-71267D01*
X1080899Y-71558D01*
Y-71933D01*
G01Y-71558D02*
X1080774Y-71308D01*
X1080565Y-71100D01*
X1080315Y-71017D01*
X1080065Y-71100D01*
X1079857Y-71308D01*
X1079732Y-71683D01*
X1079774Y-72058D01*
X1079940Y-72433D01*
G01X1095000Y-67032D02*
X1083600D01*
G01X1043834Y-56017D02*
X1045626D01*
X1046001Y-55850D01*
X1046251Y-55517D01*
X1046334Y-55100D01*
X1046251Y-54683D01*
X1046001Y-54350D01*
X1045626Y-54183D01*
X1043834D01*
G01X1045834Y-52917D02*
X1046126Y-52667D01*
X1046292Y-52333D01*
X1046334Y-51958D01*
X1046292Y-51625D01*
X1046084Y-51292D01*
X1045834Y-51083D01*
X1045584Y-51042D01*
X1045292Y-51125D01*
X1045084Y-51417D01*
X1045001Y-51708D01*
Y-52083D01*
G01Y-51708D02*
X1044876Y-51458D01*
X1044667Y-51250D01*
X1044417Y-51167D01*
X1044167Y-51250D01*
X1043959Y-51458D01*
X1043834Y-51833D01*
X1043876Y-52208D01*
X1044042Y-52583D01*
G01X1046334Y-48400D02*
X1043834D01*
X1045626Y-49942D01*
Y-47858D01*
G01X1042820Y-65855D02*
Y-47855D01*
G01X1047834Y-69017D02*
X1049626D01*
X1050001Y-68850D01*
X1050251Y-68517D01*
X1050334Y-68100D01*
X1050251Y-67683D01*
X1050001Y-67350D01*
X1049626Y-67183D01*
X1047834D01*
G01X1049834Y-65917D02*
X1050126Y-65667D01*
X1050292Y-65333D01*
X1050334Y-64958D01*
X1050292Y-64625D01*
X1050084Y-64292D01*
X1049834Y-64083D01*
X1049584Y-64042D01*
X1049292Y-64125D01*
X1049084Y-64417D01*
X1049001Y-64708D01*
Y-65083D01*
G01Y-64708D02*
X1048876Y-64458D01*
X1048667Y-64250D01*
X1048417Y-64167D01*
X1048167Y-64250D01*
X1047959Y-64458D01*
X1047834Y-64833D01*
X1047876Y-65208D01*
X1048042Y-65583D01*
G01X1049959Y-62817D02*
X1050167Y-62567D01*
X1050292Y-62275D01*
X1050334Y-61900D01*
X1050251Y-61525D01*
X1050084Y-61233D01*
X1049792Y-61025D01*
X1049459Y-60983D01*
X1049126Y-61067D01*
X1048917Y-61275D01*
X1048751Y-61567D01*
X1048709Y-61858D01*
X1048751Y-62150D01*
X1048917Y-62525D01*
X1047834Y-62400D01*
Y-61275D01*
G01X1057333Y-71097D02*
X1065333D01*
G01X1051333D02*
X1057333D01*
G01X1051333D02*
X1065333D01*
G01X1051333Y-53097D02*
Y-71097D01*
G01X1065333Y-53097D02*
X1051333D01*
G01X1065333Y-71097D02*
Y-53097D01*
G01X1049542Y-47183D02*
X1049417Y-47433D01*
X1049334Y-47725D01*
Y-48058D01*
X1049459Y-48433D01*
X1049667Y-48725D01*
X1049917Y-48933D01*
X1050334Y-49100D01*
X1050709Y-49142D01*
X1051084Y-49058D01*
X1051334Y-48933D01*
X1051584Y-48683D01*
X1051751Y-48392D01*
X1051834Y-48100D01*
Y-47808D01*
X1051751Y-47517D01*
X1051626Y-47267D01*
X1051459Y-47058D01*
G01X1051834Y-44500D02*
X1049334D01*
X1051126Y-46042D01*
Y-43958D01*
G01X1051542Y-42608D02*
X1051751Y-42317D01*
X1051834Y-41983D01*
X1051751Y-41650D01*
X1051501Y-41358D01*
X1051126Y-41150D01*
X1050751Y-41067D01*
X1050292D01*
X1049917Y-41150D01*
X1049584Y-41358D01*
X1049417Y-41608D01*
X1049334Y-41900D01*
X1049417Y-42233D01*
X1049584Y-42483D01*
X1049834Y-42650D01*
X1050167Y-42733D01*
X1050459Y-42650D01*
X1050751Y-42442D01*
X1050917Y-42192D01*
X1050959Y-41900D01*
X1050876Y-41567D01*
X1050667Y-41317D01*
X1050292Y-41067D01*
G01X1082522Y-48127D02*
X1080022D01*
Y-47293D01*
X1080147Y-46960D01*
X1080314Y-46710D01*
X1080564Y-46502D01*
X1080855Y-46335D01*
X1081272Y-46293D01*
X1081689Y-46335D01*
X1081980Y-46502D01*
X1082230Y-46710D01*
X1082397Y-46960D01*
X1082522Y-47293D01*
Y-48127D01*
G01Y-43610D02*
X1080022D01*
X1081814Y-45152D01*
Y-43068D01*
G01X1082522Y-40510D02*
X1080022D01*
X1081814Y-42052D01*
Y-39968D01*
G01X1084200Y-55200D02*
Y-39100D01*
G01X1091200Y-55200D02*
X1084200D01*
G01Y-39100D02*
X1091200D01*
G01X1060017Y15167D02*
Y17667D01*
X1061058D01*
X1061392Y17542D01*
X1061600Y17375D01*
X1061683Y17042D01*
X1061600Y16709D01*
X1061350Y16500D01*
X1061058Y16375D01*
X1060017D01*
G01X1061058D02*
X1061683Y15167D01*
G01X1063242Y15459D02*
X1063533Y15250D01*
X1063867Y15167D01*
X1064200Y15250D01*
X1064492Y15500D01*
X1064700Y15875D01*
X1064783Y16250D01*
Y16709D01*
X1064700Y17084D01*
X1064492Y17417D01*
X1064242Y17584D01*
X1063950Y17667D01*
X1063617Y17584D01*
X1063367Y17417D01*
X1063200Y17167D01*
X1063117Y16834D01*
X1063200Y16542D01*
X1063408Y16250D01*
X1063658Y16084D01*
X1063950Y16042D01*
X1064283Y16125D01*
X1064533Y16334D01*
X1064783Y16709D01*
G01X1066342Y15459D02*
X1066633Y15250D01*
X1066967Y15167D01*
X1067300Y15250D01*
X1067592Y15500D01*
X1067800Y15875D01*
X1067883Y16250D01*
Y16709D01*
X1067800Y17084D01*
X1067592Y17417D01*
X1067342Y17584D01*
X1067050Y17667D01*
X1066717Y17584D01*
X1066467Y17417D01*
X1066300Y17167D01*
X1066217Y16834D01*
X1066300Y16542D01*
X1066508Y16250D01*
X1066758Y16084D01*
X1067050Y16042D01*
X1067383Y16125D01*
X1067633Y16334D01*
X1067883Y16709D01*
G01X1069233Y15542D02*
X1069483Y15334D01*
X1069775Y15209D01*
X1070150Y15167D01*
X1070525Y15250D01*
X1070817Y15417D01*
X1071025Y15709D01*
X1071067Y16042D01*
X1070983Y16375D01*
X1070775Y16584D01*
X1070483Y16750D01*
X1070192Y16792D01*
X1069900Y16750D01*
X1069525Y16584D01*
X1069650Y17667D01*
X1070775D01*
G01X1064218Y24405D02*
Y20405D01*
X1071618D01*
G01X1047805Y31182D02*
Y28682D01*
G01X1046847Y31182D02*
X1048763D01*
G01X1050072Y28682D02*
Y31182D01*
X1051072D01*
X1051405Y31057D01*
X1051655Y30765D01*
X1051738Y30432D01*
X1051655Y30099D01*
X1051447Y29849D01*
X1051072Y29724D01*
X1050072D01*
G01X1054005Y28682D02*
Y31182D01*
X1053505Y30682D01*
G01Y28682D02*
X1054505D01*
G01X1056397Y28974D02*
X1056688Y28765D01*
X1057022Y28682D01*
X1057355Y28765D01*
X1057647Y29015D01*
X1057855Y29390D01*
X1057938Y29765D01*
Y30224D01*
X1057855Y30599D01*
X1057647Y30932D01*
X1057397Y31099D01*
X1057105Y31182D01*
X1056772Y31099D01*
X1056522Y30932D01*
X1056355Y30682D01*
X1056272Y30349D01*
X1056355Y30057D01*
X1056563Y29765D01*
X1056813Y29599D01*
X1057105Y29557D01*
X1057438Y29640D01*
X1057688Y29849D01*
X1057938Y30224D01*
G01X1060205Y28682D02*
Y31182D01*
X1059705Y30682D01*
G01Y28682D02*
X1060705D01*
G01X1047805Y39082D02*
Y36582D01*
G01X1046847Y39082D02*
X1048763D01*
G01X1050072Y36582D02*
Y39082D01*
X1051072D01*
X1051405Y38957D01*
X1051655Y38665D01*
X1051738Y38332D01*
X1051655Y37999D01*
X1051447Y37749D01*
X1051072Y37624D01*
X1050072D01*
G01X1054005Y36582D02*
Y39082D01*
X1053505Y38582D01*
G01Y36582D02*
X1054505D01*
G01X1056397Y36874D02*
X1056688Y36665D01*
X1057022Y36582D01*
X1057355Y36665D01*
X1057647Y36915D01*
X1057855Y37290D01*
X1057938Y37665D01*
Y38124D01*
X1057855Y38499D01*
X1057647Y38832D01*
X1057397Y38999D01*
X1057105Y39082D01*
X1056772Y38999D01*
X1056522Y38832D01*
X1056355Y38582D01*
X1056272Y38249D01*
X1056355Y37957D01*
X1056563Y37665D01*
X1056813Y37499D01*
X1057105Y37457D01*
X1057438Y37540D01*
X1057688Y37749D01*
X1057938Y38124D01*
G01X1059413Y38665D02*
X1059663Y38915D01*
X1059955Y39040D01*
X1060288Y39082D01*
X1060705Y38999D01*
X1060997Y38790D01*
X1061080Y38540D01*
X1061038Y38290D01*
X1060872Y38082D01*
X1060038Y37665D01*
X1059663Y37374D01*
X1059413Y36957D01*
X1059330Y36582D01*
X1061080D01*
G01X1043305Y35282D02*
Y32782D01*
G01X1042347Y35282D02*
X1044263D01*
G01X1045572Y32782D02*
Y35282D01*
X1046572D01*
X1046905Y35157D01*
X1047155Y34865D01*
X1047238Y34532D01*
X1047155Y34199D01*
X1046947Y33949D01*
X1046572Y33824D01*
X1045572D01*
G01X1049505Y32782D02*
Y35282D01*
X1049005Y34782D01*
G01Y32782D02*
X1050005D01*
G01X1051897Y33074D02*
X1052188Y32865D01*
X1052522Y32782D01*
X1052855Y32865D01*
X1053147Y33115D01*
X1053355Y33490D01*
X1053438Y33865D01*
Y34324D01*
X1053355Y34699D01*
X1053147Y35032D01*
X1052897Y35199D01*
X1052605Y35282D01*
X1052272Y35199D01*
X1052022Y35032D01*
X1051855Y34782D01*
X1051772Y34449D01*
X1051855Y34157D01*
X1052063Y33865D01*
X1052313Y33699D01*
X1052605Y33657D01*
X1052938Y33740D01*
X1053188Y33949D01*
X1053438Y34324D01*
G01X1054788Y33282D02*
X1055038Y32990D01*
X1055372Y32824D01*
X1055747Y32782D01*
X1056080Y32824D01*
X1056413Y33032D01*
X1056622Y33282D01*
X1056663Y33532D01*
X1056580Y33824D01*
X1056288Y34032D01*
X1055997Y34115D01*
X1055622D01*
G01X1055997D02*
X1056247Y34240D01*
X1056455Y34449D01*
X1056538Y34699D01*
X1056455Y34949D01*
X1056247Y35157D01*
X1055872Y35282D01*
X1055497Y35240D01*
X1055122Y35074D01*
G01X1043405Y27382D02*
Y24882D01*
G01X1042447Y27382D02*
X1044363D01*
G01X1045672Y24882D02*
Y27382D01*
X1046672D01*
X1047005Y27257D01*
X1047255Y26965D01*
X1047338Y26632D01*
X1047255Y26299D01*
X1047047Y26049D01*
X1046672Y25924D01*
X1045672D01*
G01X1049605Y24882D02*
Y27382D01*
X1049105Y26882D01*
G01Y24882D02*
X1050105D01*
G01X1051997Y25174D02*
X1052288Y24965D01*
X1052622Y24882D01*
X1052955Y24965D01*
X1053247Y25215D01*
X1053455Y25590D01*
X1053538Y25965D01*
Y26424D01*
X1053455Y26799D01*
X1053247Y27132D01*
X1052997Y27299D01*
X1052705Y27382D01*
X1052372Y27299D01*
X1052122Y27132D01*
X1051955Y26882D01*
X1051872Y26549D01*
X1051955Y26257D01*
X1052163Y25965D01*
X1052413Y25799D01*
X1052705Y25757D01*
X1053038Y25840D01*
X1053288Y26049D01*
X1053538Y26424D01*
G01X1055097Y25174D02*
X1055388Y24965D01*
X1055722Y24882D01*
X1056055Y24965D01*
X1056347Y25215D01*
X1056555Y25590D01*
X1056638Y25965D01*
Y26424D01*
X1056555Y26799D01*
X1056347Y27132D01*
X1056097Y27299D01*
X1055805Y27382D01*
X1055472Y27299D01*
X1055222Y27132D01*
X1055055Y26882D01*
X1054972Y26549D01*
X1055055Y26257D01*
X1055263Y25965D01*
X1055513Y25799D01*
X1055805Y25757D01*
X1056138Y25840D01*
X1056388Y26049D01*
X1056638Y26424D01*
G01X1043305Y42782D02*
Y40282D01*
G01X1042347Y42782D02*
X1044263D01*
G01X1045572Y40282D02*
Y42782D01*
X1046572D01*
X1046905Y42657D01*
X1047155Y42365D01*
X1047238Y42032D01*
X1047155Y41699D01*
X1046947Y41449D01*
X1046572Y41324D01*
X1045572D01*
G01X1048713Y42365D02*
X1048963Y42615D01*
X1049255Y42740D01*
X1049588Y42782D01*
X1050005Y42699D01*
X1050297Y42490D01*
X1050380Y42240D01*
X1050338Y41990D01*
X1050172Y41782D01*
X1049338Y41365D01*
X1048963Y41074D01*
X1048713Y40657D01*
X1048630Y40282D01*
X1050380D01*
G01X1052605Y42782D02*
X1052272Y42699D01*
X1052022Y42490D01*
X1051855Y42240D01*
X1051730Y41907D01*
X1051688Y41532D01*
X1051730Y41157D01*
X1051855Y40824D01*
X1052022Y40574D01*
X1052272Y40365D01*
X1052605Y40282D01*
X1052938Y40365D01*
X1053188Y40574D01*
X1053355Y40824D01*
X1053480Y41157D01*
X1053522Y41532D01*
X1053480Y41907D01*
X1053355Y42240D01*
X1053188Y42490D01*
X1052938Y42699D01*
X1052605Y42782D01*
G01X1055705D02*
X1055372Y42699D01*
X1055122Y42490D01*
X1054955Y42240D01*
X1054830Y41907D01*
X1054788Y41532D01*
X1054830Y41157D01*
X1054955Y40824D01*
X1055122Y40574D01*
X1055372Y40365D01*
X1055705Y40282D01*
X1056038Y40365D01*
X1056288Y40574D01*
X1056455Y40824D01*
X1056580Y41157D01*
X1056622Y41532D01*
X1056580Y41907D01*
X1056455Y42240D01*
X1056288Y42490D01*
X1056038Y42699D01*
X1055705Y42782D01*
G01X1047982Y46295D02*
Y43795D01*
G01X1047024Y46295D02*
X1048940D01*
G01X1050249Y43795D02*
Y46295D01*
X1051249D01*
X1051582Y46170D01*
X1051832Y45878D01*
X1051915Y45545D01*
X1051832Y45212D01*
X1051624Y44962D01*
X1051249Y44837D01*
X1050249D01*
G01X1054182Y43795D02*
Y46295D01*
X1053682Y45795D01*
G01Y43795D02*
X1054682D01*
G01X1056574Y44087D02*
X1056865Y43878D01*
X1057199Y43795D01*
X1057532Y43878D01*
X1057824Y44128D01*
X1058032Y44503D01*
X1058115Y44878D01*
Y45337D01*
X1058032Y45712D01*
X1057824Y46045D01*
X1057574Y46212D01*
X1057282Y46295D01*
X1056949Y46212D01*
X1056699Y46045D01*
X1056532Y45795D01*
X1056449Y45462D01*
X1056532Y45170D01*
X1056740Y44878D01*
X1056990Y44712D01*
X1057282Y44670D01*
X1057615Y44753D01*
X1057865Y44962D01*
X1058115Y45337D01*
G01X1060882Y43795D02*
Y46295D01*
X1059340Y44503D01*
X1061424D01*
G01X1042871Y49800D02*
Y47300D01*
G01X1041913Y49800D02*
X1043829D01*
G01X1045138Y47300D02*
Y49800D01*
X1046138D01*
X1046471Y49675D01*
X1046721Y49383D01*
X1046804Y49050D01*
X1046721Y48717D01*
X1046513Y48467D01*
X1046138Y48342D01*
X1045138D01*
G01X1049071Y47300D02*
Y49800D01*
X1048571Y49300D01*
G01Y47300D02*
X1049571D01*
G01X1051463Y47592D02*
X1051754Y47383D01*
X1052088Y47300D01*
X1052421Y47383D01*
X1052713Y47633D01*
X1052921Y48008D01*
X1053004Y48383D01*
Y48842D01*
X1052921Y49217D01*
X1052713Y49550D01*
X1052463Y49717D01*
X1052171Y49800D01*
X1051838Y49717D01*
X1051588Y49550D01*
X1051421Y49300D01*
X1051338Y48967D01*
X1051421Y48675D01*
X1051629Y48383D01*
X1051879Y48217D01*
X1052171Y48175D01*
X1052504Y48258D01*
X1052754Y48467D01*
X1053004Y48842D01*
G01X1054354Y47675D02*
X1054604Y47467D01*
X1054896Y47342D01*
X1055271Y47300D01*
X1055646Y47383D01*
X1055938Y47550D01*
X1056146Y47842D01*
X1056188Y48175D01*
X1056104Y48508D01*
X1055896Y48717D01*
X1055604Y48883D01*
X1055313Y48925D01*
X1055021Y48883D01*
X1054646Y48717D01*
X1054771Y49800D01*
X1055896D01*
G01X1047800Y53600D02*
Y51100D01*
G01X1046842Y53600D02*
X1048758D01*
G01X1050067Y51100D02*
Y53600D01*
X1051067D01*
X1051400Y53475D01*
X1051650Y53183D01*
X1051733Y52850D01*
X1051650Y52517D01*
X1051442Y52267D01*
X1051067Y52142D01*
X1050067D01*
G01X1054000Y51100D02*
Y53600D01*
X1053500Y53100D01*
G01Y51100D02*
X1054500D01*
G01X1056392Y51392D02*
X1056683Y51183D01*
X1057017Y51100D01*
X1057350Y51183D01*
X1057642Y51433D01*
X1057850Y51808D01*
X1057933Y52183D01*
Y52642D01*
X1057850Y53017D01*
X1057642Y53350D01*
X1057392Y53517D01*
X1057100Y53600D01*
X1056767Y53517D01*
X1056517Y53350D01*
X1056350Y53100D01*
X1056267Y52767D01*
X1056350Y52475D01*
X1056558Y52183D01*
X1056808Y52017D01*
X1057100Y51975D01*
X1057433Y52058D01*
X1057683Y52267D01*
X1057933Y52642D01*
G01X1059408Y52142D02*
X1059700Y52433D01*
X1059950Y52600D01*
X1060283Y52683D01*
X1060575Y52600D01*
X1060783Y52433D01*
X1060950Y52183D01*
X1060992Y51892D01*
X1060950Y51642D01*
X1060783Y51392D01*
X1060533Y51183D01*
X1060242Y51100D01*
X1059908Y51183D01*
X1059617Y51433D01*
X1059450Y51808D01*
X1059408Y52225D01*
X1059492Y52767D01*
X1059617Y53058D01*
X1059825Y53350D01*
X1060117Y53558D01*
X1060408Y53600D01*
X1060700Y53517D01*
X1060908Y53308D01*
G01X1052800Y66167D02*
Y63667D01*
G01X1051842Y66167D02*
X1053758D01*
G01X1055067Y63667D02*
Y66167D01*
X1056067D01*
X1056400Y66042D01*
X1056650Y65750D01*
X1056733Y65417D01*
X1056650Y65084D01*
X1056442Y64834D01*
X1056067Y64709D01*
X1055067D01*
G01X1058208Y65750D02*
X1058458Y66000D01*
X1058750Y66125D01*
X1059083Y66167D01*
X1059500Y66084D01*
X1059792Y65875D01*
X1059875Y65625D01*
X1059833Y65375D01*
X1059667Y65167D01*
X1058833Y64750D01*
X1058458Y64459D01*
X1058208Y64042D01*
X1058125Y63667D01*
X1059875D01*
G01X1062600D02*
Y66167D01*
X1061058Y64375D01*
X1063142D01*
G01X1064492Y63959D02*
X1064783Y63750D01*
X1065117Y63667D01*
X1065450Y63750D01*
X1065742Y64000D01*
X1065950Y64375D01*
X1066033Y64750D01*
Y65209D01*
X1065950Y65584D01*
X1065742Y65917D01*
X1065492Y66084D01*
X1065200Y66167D01*
X1064867Y66084D01*
X1064617Y65917D01*
X1064450Y65667D01*
X1064367Y65334D01*
X1064450Y65042D01*
X1064658Y64750D01*
X1064908Y64584D01*
X1065200Y64542D01*
X1065533Y64625D01*
X1065783Y64834D01*
X1066033Y65209D01*
G01X1052500Y70700D02*
Y68200D01*
G01X1051542Y70700D02*
X1053458D01*
G01X1054767Y68200D02*
Y70700D01*
X1055767D01*
X1056100Y70575D01*
X1056350Y70283D01*
X1056433Y69950D01*
X1056350Y69617D01*
X1056142Y69367D01*
X1055767Y69242D01*
X1054767D01*
G01X1057908Y70283D02*
X1058158Y70533D01*
X1058450Y70658D01*
X1058783Y70700D01*
X1059200Y70617D01*
X1059492Y70408D01*
X1059575Y70158D01*
X1059533Y69908D01*
X1059367Y69700D01*
X1058533Y69283D01*
X1058158Y68992D01*
X1057908Y68575D01*
X1057825Y68200D01*
X1059575D01*
G01X1060883Y68575D02*
X1061133Y68367D01*
X1061425Y68242D01*
X1061800Y68200D01*
X1062175Y68283D01*
X1062467Y68450D01*
X1062675Y68742D01*
X1062717Y69075D01*
X1062633Y69408D01*
X1062425Y69617D01*
X1062133Y69783D01*
X1061842Y69825D01*
X1061550Y69783D01*
X1061175Y69617D01*
X1061300Y70700D01*
X1062425D01*
G01X1064900D02*
X1064567Y70617D01*
X1064317Y70408D01*
X1064150Y70158D01*
X1064025Y69825D01*
X1063983Y69450D01*
X1064025Y69075D01*
X1064150Y68742D01*
X1064317Y68492D01*
X1064567Y68283D01*
X1064900Y68200D01*
X1065233Y68283D01*
X1065483Y68492D01*
X1065650Y68742D01*
X1065775Y69075D01*
X1065817Y69450D01*
X1065775Y69825D01*
X1065650Y70158D01*
X1065483Y70408D01*
X1065233Y70617D01*
X1064900Y70700D01*
G01X1068304Y77465D02*
Y81465D01*
X1060904D01*
G01X1051700Y440000D02*
Y444000D01*
X1044300D01*
G01X1051737Y427753D02*
Y431753D01*
X1044337D01*
G01X1051701Y432409D02*
Y436409D01*
X1044301D01*
G01X1051915Y555053D02*
Y559053D01*
X1044515D01*
G01X1061222Y830021D02*
X1058722D01*
Y831062D01*
X1058847Y831396D01*
X1059014Y831604D01*
X1059347Y831687D01*
X1059680Y831604D01*
X1059889Y831354D01*
X1060014Y831062D01*
Y830021D01*
G01Y831062D02*
X1061222Y831687D01*
G01X1060180Y833162D02*
X1059889Y833454D01*
X1059722Y833704D01*
X1059639Y834037D01*
X1059722Y834329D01*
X1059889Y834537D01*
X1060139Y834704D01*
X1060430Y834746D01*
X1060680Y834704D01*
X1060930Y834537D01*
X1061139Y834287D01*
X1061222Y833996D01*
X1061139Y833662D01*
X1060889Y833371D01*
X1060514Y833204D01*
X1060097Y833162D01*
X1059555Y833246D01*
X1059264Y833371D01*
X1058972Y833579D01*
X1058764Y833871D01*
X1058722Y834162D01*
X1058805Y834454D01*
X1059014Y834662D01*
G01X1058722Y837054D02*
X1058805Y836721D01*
X1059014Y836471D01*
X1059264Y836304D01*
X1059597Y836179D01*
X1059972Y836137D01*
X1060347Y836179D01*
X1060680Y836304D01*
X1060930Y836471D01*
X1061139Y836721D01*
X1061222Y837054D01*
X1061139Y837387D01*
X1060930Y837637D01*
X1060680Y837804D01*
X1060347Y837929D01*
X1059972Y837971D01*
X1059597Y837929D01*
X1059264Y837804D01*
X1059014Y837637D01*
X1058805Y837387D01*
X1058722Y837054D01*
G01X1060722Y839237D02*
X1061014Y839487D01*
X1061180Y839821D01*
X1061222Y840196D01*
X1061180Y840529D01*
X1060972Y840862D01*
X1060722Y841071D01*
X1060472Y841112D01*
X1060180Y841029D01*
X1059972Y840737D01*
X1059889Y840446D01*
Y840071D01*
G01Y840446D02*
X1059764Y840696D01*
X1059555Y840904D01*
X1059305Y840987D01*
X1059055Y840904D01*
X1058847Y840696D01*
X1058722Y840321D01*
X1058764Y839946D01*
X1058930Y839571D01*
G01X1052419Y830253D02*
X1056419D01*
Y837653D01*
G01X1050100Y889867D02*
X1047600D01*
Y890908D01*
X1047725Y891242D01*
X1047892Y891450D01*
X1048225Y891533D01*
X1048558Y891450D01*
X1048767Y891200D01*
X1048892Y890908D01*
Y889867D01*
G01Y890908D02*
X1050100Y891533D01*
G01X1049808Y893092D02*
X1050017Y893383D01*
X1050100Y893717D01*
X1050017Y894050D01*
X1049767Y894342D01*
X1049392Y894550D01*
X1049017Y894633D01*
X1048558D01*
X1048183Y894550D01*
X1047850Y894342D01*
X1047683Y894092D01*
X1047600Y893800D01*
X1047683Y893467D01*
X1047850Y893217D01*
X1048100Y893050D01*
X1048433Y892967D01*
X1048725Y893050D01*
X1049017Y893258D01*
X1049183Y893508D01*
X1049225Y893800D01*
X1049142Y894133D01*
X1048933Y894383D01*
X1048558Y894633D01*
G01X1047600Y896900D02*
X1047683Y896567D01*
X1047892Y896317D01*
X1048142Y896150D01*
X1048475Y896025D01*
X1048850Y895983D01*
X1049225Y896025D01*
X1049558Y896150D01*
X1049808Y896317D01*
X1050017Y896567D01*
X1050100Y896900D01*
X1050017Y897233D01*
X1049808Y897483D01*
X1049558Y897650D01*
X1049225Y897775D01*
X1048850Y897817D01*
X1048475Y897775D01*
X1048142Y897650D01*
X1047892Y897483D01*
X1047683Y897233D01*
X1047600Y896900D01*
G01X1054700Y889867D02*
X1052200D01*
Y890908D01*
X1052325Y891242D01*
X1052492Y891450D01*
X1052825Y891533D01*
X1053158Y891450D01*
X1053367Y891200D01*
X1053492Y890908D01*
Y889867D01*
G01Y890908D02*
X1054700Y891533D01*
G01X1054408Y893092D02*
X1054617Y893383D01*
X1054700Y893717D01*
X1054617Y894050D01*
X1054367Y894342D01*
X1053992Y894550D01*
X1053617Y894633D01*
X1053158D01*
X1052783Y894550D01*
X1052450Y894342D01*
X1052283Y894092D01*
X1052200Y893800D01*
X1052283Y893467D01*
X1052450Y893217D01*
X1052700Y893050D01*
X1053033Y892967D01*
X1053325Y893050D01*
X1053617Y893258D01*
X1053783Y893508D01*
X1053825Y893800D01*
X1053742Y894133D01*
X1053533Y894383D01*
X1053158Y894633D01*
G01X1054700Y896900D02*
X1054658Y897192D01*
X1054533Y897525D01*
X1054325Y897733D01*
X1054033Y897817D01*
X1053742Y897733D01*
X1053492Y897483D01*
X1053367Y897108D01*
Y896692D01*
X1053283Y896442D01*
X1053075Y896233D01*
X1052783Y896150D01*
X1052492Y896275D01*
X1052283Y896567D01*
X1052200Y896900D01*
X1052283Y897233D01*
X1052492Y897525D01*
X1052783Y897650D01*
X1053075Y897567D01*
X1053283Y897358D01*
X1053367Y897108D01*
Y896692D01*
X1053492Y896317D01*
X1053742Y896067D01*
X1054033Y895983D01*
X1054325Y896067D01*
X1054533Y896275D01*
X1054658Y896608D01*
X1054700Y896900D01*
G01X1068334Y871017D02*
X1065834D01*
Y872058D01*
X1065959Y872392D01*
X1066126Y872600D01*
X1066459Y872683D01*
X1066792Y872600D01*
X1067001Y872350D01*
X1067126Y872058D01*
Y871017D01*
G01Y872058D02*
X1068334Y872683D01*
G01Y875450D02*
X1065834D01*
X1067626Y873908D01*
Y875992D01*
G01X1065834Y878050D02*
X1065917Y877717D01*
X1066126Y877467D01*
X1066376Y877300D01*
X1066709Y877175D01*
X1067084Y877133D01*
X1067459Y877175D01*
X1067792Y877300D01*
X1068042Y877467D01*
X1068251Y877717D01*
X1068334Y878050D01*
X1068251Y878383D01*
X1068042Y878633D01*
X1067792Y878800D01*
X1067459Y878925D01*
X1067084Y878967D01*
X1066709Y878925D01*
X1066376Y878800D01*
X1066126Y878633D01*
X1065917Y878383D01*
X1065834Y878050D01*
G01X1068334Y881150D02*
X1065834D01*
X1066334Y880650D01*
G01X1068334D02*
Y881650D01*
G01X1048803Y878127D02*
X1044803D01*
Y870727D01*
G01X1052517Y870167D02*
Y872667D01*
X1053558D01*
X1053892Y872542D01*
X1054100Y872375D01*
X1054183Y872042D01*
X1054100Y871709D01*
X1053850Y871500D01*
X1053558Y871375D01*
X1052517D01*
G01X1053558D02*
X1054183Y870167D01*
G01X1056950D02*
Y872667D01*
X1055408Y870875D01*
X1057492D01*
G01X1059550Y872667D02*
X1059217Y872584D01*
X1058967Y872375D01*
X1058800Y872125D01*
X1058675Y871792D01*
X1058633Y871417D01*
X1058675Y871042D01*
X1058800Y870709D01*
X1058967Y870459D01*
X1059217Y870250D01*
X1059550Y870167D01*
X1059883Y870250D01*
X1060133Y870459D01*
X1060300Y870709D01*
X1060425Y871042D01*
X1060467Y871417D01*
X1060425Y871792D01*
X1060300Y872125D01*
X1060133Y872375D01*
X1059883Y872584D01*
X1059550Y872667D01*
G01X1062650Y870167D02*
X1062942Y870209D01*
X1063275Y870334D01*
X1063483Y870542D01*
X1063567Y870834D01*
X1063483Y871125D01*
X1063233Y871375D01*
X1062858Y871500D01*
X1062442D01*
X1062192Y871584D01*
X1061983Y871792D01*
X1061900Y872084D01*
X1062025Y872375D01*
X1062317Y872584D01*
X1062650Y872667D01*
X1062983Y872584D01*
X1063275Y872375D01*
X1063400Y872084D01*
X1063317Y871792D01*
X1063108Y871584D01*
X1062858Y871500D01*
X1062442D01*
X1062067Y871375D01*
X1061817Y871125D01*
X1061733Y870834D01*
X1061817Y870542D01*
X1062025Y870334D01*
X1062358Y870209D01*
X1062650Y870167D01*
G01X1050555Y842844D02*
Y845344D01*
X1051596D01*
X1051930Y845219D01*
X1052138Y845052D01*
X1052221Y844719D01*
X1052138Y844386D01*
X1051888Y844177D01*
X1051596Y844052D01*
X1050555D01*
G01X1051596D02*
X1052221Y842844D01*
G01X1054988D02*
Y845344D01*
X1053446Y843552D01*
X1055530D01*
G01X1057588Y845344D02*
X1057255Y845261D01*
X1057005Y845052D01*
X1056838Y844802D01*
X1056713Y844469D01*
X1056671Y844094D01*
X1056713Y843719D01*
X1056838Y843386D01*
X1057005Y843136D01*
X1057255Y842927D01*
X1057588Y842844D01*
X1057921Y842927D01*
X1058171Y843136D01*
X1058338Y843386D01*
X1058463Y843719D01*
X1058505Y844094D01*
X1058463Y844469D01*
X1058338Y844802D01*
X1058171Y845052D01*
X1057921Y845261D01*
X1057588Y845344D01*
G01X1061188Y842844D02*
Y845344D01*
X1059646Y843552D01*
X1061730D01*
G01X1058834Y874517D02*
X1056334D01*
Y875558D01*
X1056459Y875892D01*
X1056626Y876100D01*
X1056959Y876183D01*
X1057292Y876100D01*
X1057501Y875850D01*
X1057626Y875558D01*
Y874517D01*
G01Y875558D02*
X1058834Y876183D01*
G01X1057792Y877658D02*
X1057501Y877950D01*
X1057334Y878200D01*
X1057251Y878533D01*
X1057334Y878825D01*
X1057501Y879033D01*
X1057751Y879200D01*
X1058042Y879242D01*
X1058292Y879200D01*
X1058542Y879033D01*
X1058751Y878783D01*
X1058834Y878492D01*
X1058751Y878158D01*
X1058501Y877867D01*
X1058126Y877700D01*
X1057709Y877658D01*
X1057167Y877742D01*
X1056876Y877867D01*
X1056584Y878075D01*
X1056376Y878367D01*
X1056334Y878658D01*
X1056417Y878950D01*
X1056626Y879158D01*
G01X1056334Y881550D02*
X1056417Y881217D01*
X1056626Y880967D01*
X1056876Y880800D01*
X1057209Y880675D01*
X1057584Y880633D01*
X1057959Y880675D01*
X1058292Y880800D01*
X1058542Y880967D01*
X1058751Y881217D01*
X1058834Y881550D01*
X1058751Y881883D01*
X1058542Y882133D01*
X1058292Y882300D01*
X1057959Y882425D01*
X1057584Y882467D01*
X1057209Y882425D01*
X1056876Y882300D01*
X1056626Y882133D01*
X1056417Y881883D01*
X1056334Y881550D01*
G01X1058834Y884650D02*
X1056334D01*
X1056834Y884150D01*
G01X1058834D02*
Y885150D01*
G01X1044101Y882641D02*
X1040101D01*
Y875241D01*
G01X1045623Y857803D02*
Y849803D01*
G01X1046400Y903000D02*
X1050400D01*
Y910400D01*
G01X1059000Y890067D02*
X1056500D01*
Y891108D01*
X1056625Y891442D01*
X1056792Y891650D01*
X1057125Y891733D01*
X1057458Y891650D01*
X1057667Y891400D01*
X1057792Y891108D01*
Y890067D01*
G01Y891108D02*
X1059000Y891733D01*
G01X1058708Y893292D02*
X1058917Y893583D01*
X1059000Y893917D01*
X1058917Y894250D01*
X1058667Y894542D01*
X1058292Y894750D01*
X1057917Y894833D01*
X1057458D01*
X1057083Y894750D01*
X1056750Y894542D01*
X1056583Y894292D01*
X1056500Y894000D01*
X1056583Y893667D01*
X1056750Y893417D01*
X1057000Y893250D01*
X1057333Y893167D01*
X1057625Y893250D01*
X1057917Y893458D01*
X1058083Y893708D01*
X1058125Y894000D01*
X1058042Y894333D01*
X1057833Y894583D01*
X1057458Y894833D01*
G01X1059000Y897100D02*
X1056500D01*
X1057000Y896600D01*
G01X1059000D02*
Y897600D01*
G01X1055700Y903000D02*
X1059700D01*
Y910400D01*
G01X1044900Y890267D02*
X1042400D01*
Y891308D01*
X1042525Y891642D01*
X1042692Y891850D01*
X1043025Y891933D01*
X1043358Y891850D01*
X1043567Y891600D01*
X1043692Y891308D01*
Y890267D01*
G01Y891308D02*
X1044900Y891933D01*
G01X1044608Y893492D02*
X1044817Y893783D01*
X1044900Y894117D01*
X1044817Y894450D01*
X1044567Y894742D01*
X1044192Y894950D01*
X1043817Y895033D01*
X1043358D01*
X1042983Y894950D01*
X1042650Y894742D01*
X1042483Y894492D01*
X1042400Y894200D01*
X1042483Y893867D01*
X1042650Y893617D01*
X1042900Y893450D01*
X1043233Y893367D01*
X1043525Y893450D01*
X1043817Y893658D01*
X1043983Y893908D01*
X1044025Y894200D01*
X1043942Y894533D01*
X1043733Y894783D01*
X1043358Y895033D01*
G01X1044900Y897217D02*
X1044358Y897300D01*
X1043900Y897425D01*
X1043483Y897592D01*
X1043025Y897800D01*
X1042400Y898133D01*
Y896467D01*
G01X1045900Y910400D02*
X1041900D01*
Y903000D01*
G01X1055200Y910400D02*
X1051200D01*
Y903000D01*
G01X1065907Y924111D02*
X1063407D01*
Y925152D01*
X1063532Y925486D01*
X1063699Y925694D01*
X1064032Y925777D01*
X1064365Y925694D01*
X1064574Y925444D01*
X1064699Y925152D01*
Y924111D01*
G01Y925152D02*
X1065907Y925777D01*
G01Y928544D02*
X1063407D01*
X1065199Y927002D01*
Y929086D01*
G01X1065907Y931644D02*
X1063407D01*
X1065199Y930102D01*
Y932186D01*
G01X1063407Y934244D02*
X1063490Y933911D01*
X1063699Y933661D01*
X1063949Y933494D01*
X1064282Y933369D01*
X1064657Y933327D01*
X1065032Y933369D01*
X1065365Y933494D01*
X1065615Y933661D01*
X1065824Y933911D01*
X1065907Y934244D01*
X1065824Y934577D01*
X1065615Y934827D01*
X1065365Y934994D01*
X1065032Y935119D01*
X1064657Y935161D01*
X1064282Y935119D01*
X1063949Y934994D01*
X1063699Y934827D01*
X1063490Y934577D01*
X1063407Y934244D01*
G01X1062918Y936949D02*
X1066918D01*
Y944349D01*
G01X1071174Y924243D02*
X1068674D01*
Y925284D01*
X1068799Y925618D01*
X1068966Y925826D01*
X1069299Y925909D01*
X1069632Y925826D01*
X1069841Y925576D01*
X1069966Y925284D01*
Y924243D01*
G01Y925284D02*
X1071174Y925909D01*
G01Y928676D02*
X1068674D01*
X1070466Y927134D01*
Y929218D01*
G01X1071174Y931776D02*
X1068674D01*
X1070466Y930234D01*
Y932318D01*
G01X1070674Y933459D02*
X1070966Y933709D01*
X1071132Y934043D01*
X1071174Y934418D01*
X1071132Y934751D01*
X1070924Y935084D01*
X1070674Y935293D01*
X1070424Y935334D01*
X1070132Y935251D01*
X1069924Y934959D01*
X1069841Y934668D01*
Y934293D01*
G01Y934668D02*
X1069716Y934918D01*
X1069507Y935126D01*
X1069257Y935209D01*
X1069007Y935126D01*
X1068799Y934918D01*
X1068674Y934543D01*
X1068716Y934168D01*
X1068882Y933793D01*
G01X1067918Y936949D02*
X1071918D01*
Y944349D01*
G01X1082015Y1045698D02*
X1143515D01*
Y1037998D01*
X1141215D01*
Y1033798D01*
X1143515D01*
Y978798D01*
X1082015D01*
Y1045698D01*
G01X1052000Y1068017D02*
X1049500D01*
Y1069058D01*
X1049625Y1069392D01*
X1049792Y1069600D01*
X1050125Y1069683D01*
X1050458Y1069600D01*
X1050667Y1069350D01*
X1050792Y1069058D01*
Y1068017D01*
G01Y1069058D02*
X1052000Y1069683D01*
G01Y1071950D02*
X1049500D01*
X1050000Y1071450D01*
G01X1052000D02*
Y1072450D01*
G01Y1075050D02*
X1049500D01*
X1050000Y1074550D01*
G01X1052000D02*
Y1075550D01*
G01Y1078150D02*
X1049500D01*
X1050000Y1077650D01*
G01X1052000D02*
Y1078650D01*
G01X1075500Y1075700D02*
X1071500D01*
Y1068300D01*
G01X1065500Y1068017D02*
X1063000D01*
Y1069058D01*
X1063125Y1069392D01*
X1063292Y1069600D01*
X1063625Y1069683D01*
X1063958Y1069600D01*
X1064167Y1069350D01*
X1064292Y1069058D01*
Y1068017D01*
G01Y1069058D02*
X1065500Y1069683D01*
G01Y1071950D02*
X1063000D01*
X1063500Y1071450D01*
G01X1065500D02*
Y1072450D01*
G01Y1075050D02*
X1063000D01*
X1063500Y1074550D01*
G01X1065500D02*
Y1075550D01*
G01X1063417Y1077358D02*
X1063167Y1077608D01*
X1063042Y1077900D01*
X1063000Y1078233D01*
X1063083Y1078650D01*
X1063292Y1078942D01*
X1063542Y1079025D01*
X1063792Y1078983D01*
X1064000Y1078817D01*
X1064417Y1077983D01*
X1064708Y1077608D01*
X1065125Y1077358D01*
X1065500Y1077275D01*
Y1079025D01*
G01X1085000Y1068300D02*
X1089000D01*
Y1075700D01*
G01X1056500Y1068017D02*
X1054000D01*
Y1069058D01*
X1054125Y1069392D01*
X1054292Y1069600D01*
X1054625Y1069683D01*
X1054958Y1069600D01*
X1055167Y1069350D01*
X1055292Y1069058D01*
Y1068017D01*
G01Y1069058D02*
X1056500Y1069683D01*
G01Y1071950D02*
X1054000D01*
X1054500Y1071450D01*
G01X1056500D02*
Y1072450D01*
G01Y1075050D02*
X1054000D01*
X1054500Y1074550D01*
G01X1056500D02*
Y1075550D01*
G01Y1078067D02*
X1055958Y1078150D01*
X1055500Y1078275D01*
X1055083Y1078442D01*
X1054625Y1078650D01*
X1054000Y1078983D01*
Y1077317D01*
G01X1076000Y1068300D02*
X1080000D01*
Y1075700D01*
G01X1042122Y1053517D02*
X1039622D01*
Y1054558D01*
X1039747Y1054892D01*
X1039914Y1055100D01*
X1040247Y1055183D01*
X1040580Y1055100D01*
X1040789Y1054850D01*
X1040914Y1054558D01*
Y1053517D01*
G01Y1054558D02*
X1042122Y1055183D01*
G01Y1057450D02*
X1039622D01*
X1040122Y1056950D01*
G01X1042122D02*
Y1057950D01*
G01X1039622Y1060550D02*
X1039705Y1060217D01*
X1039914Y1059967D01*
X1040164Y1059800D01*
X1040497Y1059675D01*
X1040872Y1059633D01*
X1041247Y1059675D01*
X1041580Y1059800D01*
X1041830Y1059967D01*
X1042039Y1060217D01*
X1042122Y1060550D01*
X1042039Y1060883D01*
X1041830Y1061133D01*
X1041580Y1061300D01*
X1041247Y1061425D01*
X1040872Y1061467D01*
X1040497Y1061425D01*
X1040164Y1061300D01*
X1039914Y1061133D01*
X1039705Y1060883D01*
X1039622Y1060550D01*
G01X1041830Y1062942D02*
X1042039Y1063233D01*
X1042122Y1063567D01*
X1042039Y1063900D01*
X1041789Y1064192D01*
X1041414Y1064400D01*
X1041039Y1064483D01*
X1040580D01*
X1040205Y1064400D01*
X1039872Y1064192D01*
X1039705Y1063942D01*
X1039622Y1063650D01*
X1039705Y1063317D01*
X1039872Y1063067D01*
X1040122Y1062900D01*
X1040455Y1062817D01*
X1040747Y1062900D01*
X1041039Y1063108D01*
X1041205Y1063358D01*
X1041247Y1063650D01*
X1041164Y1063983D01*
X1040955Y1064233D01*
X1040580Y1064483D01*
G01X1047500Y1068017D02*
X1045000D01*
Y1069058D01*
X1045125Y1069392D01*
X1045292Y1069600D01*
X1045625Y1069683D01*
X1045958Y1069600D01*
X1046167Y1069350D01*
X1046292Y1069058D01*
Y1068017D01*
G01Y1069058D02*
X1047500Y1069683D01*
G01Y1071950D02*
X1045000D01*
X1045500Y1071450D01*
G01X1047500D02*
Y1072450D01*
G01Y1075050D02*
X1045000D01*
X1045500Y1074550D01*
G01X1047500D02*
Y1075550D01*
G01X1047000Y1077233D02*
X1047292Y1077483D01*
X1047458Y1077817D01*
X1047500Y1078192D01*
X1047458Y1078525D01*
X1047250Y1078858D01*
X1047000Y1079067D01*
X1046750Y1079108D01*
X1046458Y1079025D01*
X1046250Y1078733D01*
X1046167Y1078442D01*
Y1078067D01*
G01Y1078442D02*
X1046042Y1078692D01*
X1045833Y1078900D01*
X1045583Y1078983D01*
X1045333Y1078900D01*
X1045125Y1078692D01*
X1045000Y1078317D01*
X1045042Y1077942D01*
X1045208Y1077567D01*
G01X1071000Y1075700D02*
X1067000D01*
Y1068300D01*
G01X1061000Y1068017D02*
X1058500D01*
Y1069058D01*
X1058625Y1069392D01*
X1058792Y1069600D01*
X1059125Y1069683D01*
X1059458Y1069600D01*
X1059667Y1069350D01*
X1059792Y1069058D01*
Y1068017D01*
G01Y1069058D02*
X1061000Y1069683D01*
G01Y1071950D02*
X1058500D01*
X1059000Y1071450D01*
G01X1061000D02*
Y1072450D01*
G01Y1075050D02*
X1058500D01*
X1059000Y1074550D01*
G01X1061000D02*
Y1075550D01*
G01Y1078150D02*
X1060958Y1078442D01*
X1060833Y1078775D01*
X1060625Y1078983D01*
X1060333Y1079067D01*
X1060042Y1078983D01*
X1059792Y1078733D01*
X1059667Y1078358D01*
Y1077942D01*
X1059583Y1077692D01*
X1059375Y1077483D01*
X1059083Y1077400D01*
X1058792Y1077525D01*
X1058583Y1077817D01*
X1058500Y1078150D01*
X1058583Y1078483D01*
X1058792Y1078775D01*
X1059083Y1078900D01*
X1059375Y1078817D01*
X1059583Y1078608D01*
X1059667Y1078358D01*
Y1077942D01*
X1059792Y1077567D01*
X1060042Y1077317D01*
X1060333Y1077233D01*
X1060625Y1077317D01*
X1060833Y1077525D01*
X1060958Y1077858D01*
X1061000Y1078150D01*
G01X1084500Y1075700D02*
X1080500D01*
Y1068300D01*
G01X1070850Y1080500D02*
Y1101500D01*
X1102500D01*
Y1090500D01*
X1070850D01*
G01X1061700Y1115417D02*
X1059200D01*
Y1116458D01*
X1059325Y1116792D01*
X1059492Y1117000D01*
X1059825Y1117083D01*
X1060158Y1117000D01*
X1060367Y1116750D01*
X1060492Y1116458D01*
Y1115417D01*
G01Y1116458D02*
X1061700Y1117083D01*
G01Y1119350D02*
X1059200D01*
X1059700Y1118850D01*
G01X1061700D02*
Y1119850D01*
G01Y1122450D02*
X1059200D01*
X1059700Y1121950D01*
G01X1061700D02*
Y1122950D01*
G01X1059200Y1125550D02*
X1059283Y1125217D01*
X1059492Y1124967D01*
X1059742Y1124800D01*
X1060075Y1124675D01*
X1060450Y1124633D01*
X1060825Y1124675D01*
X1061158Y1124800D01*
X1061408Y1124967D01*
X1061617Y1125217D01*
X1061700Y1125550D01*
X1061617Y1125883D01*
X1061408Y1126133D01*
X1061158Y1126300D01*
X1060825Y1126425D01*
X1060450Y1126467D01*
X1060075Y1126425D01*
X1059742Y1126300D01*
X1059492Y1126133D01*
X1059283Y1125883D01*
X1059200Y1125550D01*
G01X1085700Y1117200D02*
X1089700D01*
Y1124600D01*
G01X1048500Y1115517D02*
X1046000D01*
Y1116558D01*
X1046125Y1116892D01*
X1046292Y1117100D01*
X1046625Y1117183D01*
X1046958Y1117100D01*
X1047167Y1116850D01*
X1047292Y1116558D01*
Y1115517D01*
G01Y1116558D02*
X1048500Y1117183D01*
G01Y1119450D02*
X1046000D01*
X1046500Y1118950D01*
G01X1048500D02*
Y1119950D01*
G01Y1122550D02*
X1046000D01*
X1046500Y1122050D01*
G01X1048500D02*
Y1123050D01*
G01X1048125Y1124733D02*
X1048333Y1124983D01*
X1048458Y1125275D01*
X1048500Y1125650D01*
X1048417Y1126025D01*
X1048250Y1126317D01*
X1047958Y1126525D01*
X1047625Y1126567D01*
X1047292Y1126483D01*
X1047083Y1126275D01*
X1046917Y1125983D01*
X1046875Y1125692D01*
X1046917Y1125400D01*
X1047083Y1125025D01*
X1046000Y1125150D01*
Y1126275D01*
G01X1072500Y1117300D02*
X1076500D01*
Y1124700D01*
G01X1053000Y1115517D02*
X1050500D01*
Y1116558D01*
X1050625Y1116892D01*
X1050792Y1117100D01*
X1051125Y1117183D01*
X1051458Y1117100D01*
X1051667Y1116850D01*
X1051792Y1116558D01*
Y1115517D01*
G01Y1116558D02*
X1053000Y1117183D01*
G01Y1119450D02*
X1050500D01*
X1051000Y1118950D01*
G01X1053000D02*
Y1119950D01*
G01Y1122550D02*
X1050500D01*
X1051000Y1122050D01*
G01X1053000D02*
Y1123050D01*
G01Y1126150D02*
X1050500D01*
X1052292Y1124608D01*
Y1126692D01*
G01X1077000Y1117300D02*
X1081000D01*
Y1124700D01*
G01X1066200Y1115417D02*
X1063700D01*
Y1116458D01*
X1063825Y1116792D01*
X1063992Y1117000D01*
X1064325Y1117083D01*
X1064658Y1117000D01*
X1064867Y1116750D01*
X1064992Y1116458D01*
Y1115417D01*
G01Y1116458D02*
X1066200Y1117083D01*
G01Y1119350D02*
X1063700D01*
X1064200Y1118850D01*
G01X1066200D02*
Y1119850D01*
G01Y1122450D02*
X1063700D01*
X1064200Y1121950D01*
G01X1066200D02*
Y1122950D01*
G01X1065158Y1124758D02*
X1064867Y1125050D01*
X1064700Y1125300D01*
X1064617Y1125633D01*
X1064700Y1125925D01*
X1064867Y1126133D01*
X1065117Y1126300D01*
X1065408Y1126342D01*
X1065658Y1126300D01*
X1065908Y1126133D01*
X1066117Y1125883D01*
X1066200Y1125592D01*
X1066117Y1125258D01*
X1065867Y1124967D01*
X1065492Y1124800D01*
X1065075Y1124758D01*
X1064533Y1124842D01*
X1064242Y1124967D01*
X1063950Y1125175D01*
X1063742Y1125467D01*
X1063700Y1125758D01*
X1063783Y1126050D01*
X1063992Y1126258D01*
G01X1068155Y1117303D02*
X1072155D01*
Y1124703D01*
G01X1057355Y1115520D02*
X1054855D01*
Y1116561D01*
X1054980Y1116895D01*
X1055147Y1117103D01*
X1055480Y1117186D01*
X1055813Y1117103D01*
X1056022Y1116853D01*
X1056147Y1116561D01*
Y1115520D01*
G01Y1116561D02*
X1057355Y1117186D01*
G01Y1119953D02*
X1054855D01*
X1056647Y1118411D01*
Y1120495D01*
G01X1056855Y1121636D02*
X1057147Y1121886D01*
X1057313Y1122220D01*
X1057355Y1122595D01*
X1057313Y1122928D01*
X1057105Y1123261D01*
X1056855Y1123470D01*
X1056605Y1123511D01*
X1056313Y1123428D01*
X1056105Y1123136D01*
X1056022Y1122845D01*
Y1122470D01*
G01Y1122845D02*
X1055897Y1123095D01*
X1055688Y1123303D01*
X1055438Y1123386D01*
X1055188Y1123303D01*
X1054980Y1123095D01*
X1054855Y1122720D01*
X1054897Y1122345D01*
X1055063Y1121970D01*
G01X1057355Y1125653D02*
X1057313Y1125945D01*
X1057188Y1126278D01*
X1056980Y1126486D01*
X1056688Y1126570D01*
X1056397Y1126486D01*
X1056147Y1126236D01*
X1056022Y1125861D01*
Y1125445D01*
X1055938Y1125195D01*
X1055730Y1124986D01*
X1055438Y1124903D01*
X1055147Y1125028D01*
X1054938Y1125320D01*
X1054855Y1125653D01*
X1054938Y1125986D01*
X1055147Y1126278D01*
X1055438Y1126403D01*
X1055730Y1126320D01*
X1055938Y1126111D01*
X1056022Y1125861D01*
Y1125445D01*
X1056147Y1125070D01*
X1056397Y1124820D01*
X1056688Y1124736D01*
X1056980Y1124820D01*
X1057188Y1125028D01*
X1057313Y1125361D01*
X1057355Y1125653D01*
G01X1081355Y1117303D02*
X1085355D01*
Y1124703D01*
G01X1065500Y1085483D02*
X1067292D01*
X1067667Y1085650D01*
X1067917Y1085983D01*
X1068000Y1086400D01*
X1067917Y1086817D01*
X1067667Y1087150D01*
X1067292Y1087317D01*
X1065500D01*
G01X1068000Y1089500D02*
X1065500D01*
X1066000Y1089000D01*
G01X1068000D02*
Y1090000D01*
G01Y1092600D02*
X1065500D01*
X1066000Y1092100D01*
G01X1068000D02*
Y1093100D01*
G01X1070850Y1099150D02*
X1074000Y1096000D01*
X1070850Y1092850D01*
G01X1057699Y1087046D02*
X1057574Y1086796D01*
X1057491Y1086504D01*
Y1086171D01*
X1057616Y1085796D01*
X1057824Y1085504D01*
X1058074Y1085296D01*
X1058491Y1085129D01*
X1058866Y1085087D01*
X1059241Y1085171D01*
X1059491Y1085296D01*
X1059741Y1085546D01*
X1059908Y1085837D01*
X1059991Y1086129D01*
Y1086421D01*
X1059908Y1086712D01*
X1059783Y1086962D01*
X1059616Y1087171D01*
G01X1059491Y1088312D02*
X1059783Y1088562D01*
X1059949Y1088896D01*
X1059991Y1089271D01*
X1059949Y1089604D01*
X1059741Y1089937D01*
X1059491Y1090146D01*
X1059241Y1090187D01*
X1058949Y1090104D01*
X1058741Y1089812D01*
X1058658Y1089521D01*
Y1089146D01*
G01Y1089521D02*
X1058533Y1089771D01*
X1058324Y1089979D01*
X1058074Y1090062D01*
X1057824Y1089979D01*
X1057616Y1089771D01*
X1057491Y1089396D01*
X1057533Y1089021D01*
X1057699Y1088646D01*
G01X1059616Y1091412D02*
X1059824Y1091662D01*
X1059949Y1091954D01*
X1059991Y1092329D01*
X1059908Y1092704D01*
X1059741Y1092996D01*
X1059449Y1093204D01*
X1059116Y1093246D01*
X1058783Y1093162D01*
X1058574Y1092954D01*
X1058408Y1092662D01*
X1058366Y1092371D01*
X1058408Y1092079D01*
X1058574Y1091704D01*
X1057491Y1091829D01*
Y1092954D01*
G01X1061399Y1087046D02*
X1061274Y1086796D01*
X1061191Y1086504D01*
Y1086171D01*
X1061316Y1085796D01*
X1061524Y1085504D01*
X1061774Y1085296D01*
X1062191Y1085129D01*
X1062566Y1085087D01*
X1062941Y1085171D01*
X1063191Y1085296D01*
X1063441Y1085546D01*
X1063608Y1085837D01*
X1063691Y1086129D01*
Y1086421D01*
X1063608Y1086712D01*
X1063483Y1086962D01*
X1063316Y1087171D01*
G01X1063191Y1088312D02*
X1063483Y1088562D01*
X1063649Y1088896D01*
X1063691Y1089271D01*
X1063649Y1089604D01*
X1063441Y1089937D01*
X1063191Y1090146D01*
X1062941Y1090187D01*
X1062649Y1090104D01*
X1062441Y1089812D01*
X1062358Y1089521D01*
Y1089146D01*
G01Y1089521D02*
X1062233Y1089771D01*
X1062024Y1089979D01*
X1061774Y1090062D01*
X1061524Y1089979D01*
X1061316Y1089771D01*
X1061191Y1089396D01*
X1061233Y1089021D01*
X1061399Y1088646D01*
G01X1062649Y1091537D02*
X1062358Y1091829D01*
X1062191Y1092079D01*
X1062108Y1092412D01*
X1062191Y1092704D01*
X1062358Y1092912D01*
X1062608Y1093079D01*
X1062899Y1093121D01*
X1063149Y1093079D01*
X1063399Y1092912D01*
X1063608Y1092662D01*
X1063691Y1092371D01*
X1063608Y1092037D01*
X1063358Y1091746D01*
X1062983Y1091579D01*
X1062566Y1091537D01*
X1062024Y1091621D01*
X1061733Y1091746D01*
X1061441Y1091954D01*
X1061233Y1092246D01*
X1061191Y1092537D01*
X1061274Y1092829D01*
X1061483Y1093037D01*
G01X1075334Y1173333D02*
X1074167Y1174500D01*
X1073500Y1175500D01*
X1073167Y1176833D01*
X1073500Y1178000D01*
X1074167Y1178833D01*
X1075167Y1179500D01*
X1076333Y1179667D01*
X1077333Y1179500D01*
X1078334Y1178833D01*
X1079167Y1177833D01*
X1079500Y1176667D01*
X1079167Y1175333D01*
X1078167Y1174167D01*
X1076667Y1173500D01*
X1075000Y1173333D01*
X1072834Y1173667D01*
X1071667Y1174167D01*
X1070500Y1175000D01*
X1069667Y1176167D01*
X1069500Y1177333D01*
X1069833Y1178500D01*
X1070667Y1179333D01*
G01X1140715Y1406788D02*
Y1402788D01*
X1143515D01*
Y1150838D01*
X1082015D01*
Y1415938D01*
G01X1068334Y1197333D02*
X1067167Y1198500D01*
X1066500Y1199500D01*
X1066167Y1200833D01*
X1066500Y1202000D01*
X1067167Y1202833D01*
X1068167Y1203500D01*
X1069333Y1203667D01*
X1070333Y1203500D01*
X1071334Y1202833D01*
X1072167Y1201833D01*
X1072500Y1200667D01*
X1072167Y1199333D01*
X1071167Y1198167D01*
X1069667Y1197500D01*
X1068000Y1197333D01*
X1065834Y1197667D01*
X1064667Y1198167D01*
X1063500Y1199000D01*
X1062667Y1200167D01*
X1062500Y1201333D01*
X1062833Y1202500D01*
X1063667Y1203333D01*
G01X1079500Y1271500D02*
X1079333Y1272667D01*
X1078833Y1274000D01*
X1078000Y1274833D01*
X1076833Y1275167D01*
X1075667Y1274833D01*
X1074667Y1273833D01*
X1074167Y1272333D01*
Y1270667D01*
X1073833Y1269667D01*
X1073000Y1268833D01*
X1071833Y1268500D01*
X1070667Y1269000D01*
X1069833Y1270166D01*
X1069500Y1271500D01*
X1069833Y1272833D01*
X1070667Y1274000D01*
X1071833Y1274500D01*
X1073000Y1274167D01*
X1073833Y1273333D01*
X1074167Y1272333D01*
Y1270667D01*
X1074667Y1269167D01*
X1075667Y1268167D01*
X1076833Y1267833D01*
X1078000Y1268167D01*
X1078833Y1269000D01*
X1079333Y1270333D01*
X1079500Y1271500D01*
G01Y1342500D02*
X1079333Y1343667D01*
X1078833Y1345000D01*
X1078000Y1345833D01*
X1076833Y1346167D01*
X1075667Y1345833D01*
X1074667Y1344833D01*
X1074167Y1343333D01*
Y1341667D01*
X1073833Y1340667D01*
X1073000Y1339833D01*
X1071833Y1339500D01*
X1070667Y1340000D01*
X1069833Y1341166D01*
X1069500Y1342500D01*
X1069833Y1343833D01*
X1070667Y1345000D01*
X1071833Y1345500D01*
X1073000Y1345167D01*
X1073833Y1344333D01*
X1074167Y1343333D01*
Y1341667D01*
X1074667Y1340167D01*
X1075667Y1339167D01*
X1076833Y1338833D01*
X1078000Y1339167D01*
X1078833Y1340000D01*
X1079333Y1341333D01*
X1079500Y1342500D01*
G01Y1365500D02*
X1079333Y1366667D01*
X1078833Y1368000D01*
X1078000Y1368833D01*
X1076833Y1369167D01*
X1075667Y1368833D01*
X1074667Y1367833D01*
X1074167Y1366333D01*
Y1364667D01*
X1073833Y1363667D01*
X1073000Y1362833D01*
X1071833Y1362500D01*
X1070667Y1363000D01*
X1069833Y1364166D01*
X1069500Y1365500D01*
X1069833Y1366833D01*
X1070667Y1368000D01*
X1071833Y1368500D01*
X1073000Y1368167D01*
X1073833Y1367333D01*
X1074167Y1366333D01*
Y1364667D01*
X1074667Y1363167D01*
X1075667Y1362167D01*
X1076833Y1361833D01*
X1078000Y1362167D01*
X1078833Y1363000D01*
X1079333Y1364333D01*
X1079500Y1365500D01*
G01X1140715Y1406788D02*
X1143515D01*
Y1415938D01*
X1082015D01*
G01X1071917Y1449000D02*
Y1451500D01*
X1072958D01*
X1073292Y1451375D01*
X1073500Y1451208D01*
X1073583Y1450875D01*
X1073500Y1450542D01*
X1073250Y1450333D01*
X1072958Y1450208D01*
X1071917D01*
G01X1072958D02*
X1073583Y1449000D01*
G01X1075850D02*
Y1451500D01*
X1075350Y1451000D01*
G01Y1449000D02*
X1076350D01*
G01X1078950D02*
Y1451500D01*
X1078450Y1451000D01*
G01Y1449000D02*
X1079450D01*
G01X1081967D02*
X1082050Y1449542D01*
X1082175Y1450000D01*
X1082342Y1450417D01*
X1082550Y1450875D01*
X1082883Y1451500D01*
X1081217D01*
G01X1084358Y1451083D02*
X1084608Y1451333D01*
X1084900Y1451458D01*
X1085233Y1451500D01*
X1085650Y1451417D01*
X1085942Y1451208D01*
X1086025Y1450958D01*
X1085983Y1450708D01*
X1085817Y1450500D01*
X1084983Y1450083D01*
X1084608Y1449792D01*
X1084358Y1449375D01*
X1084275Y1449000D01*
X1086025D01*
G01X1077955Y1470211D02*
Y1465011D01*
G01X1070955Y1470211D02*
Y1462411D01*
G01X1077955Y1456811D02*
Y1465511D01*
G01X1070955Y1456811D02*
X1077955D01*
G01X1070955Y1463211D02*
Y1456811D01*
G01X1040417Y1449500D02*
Y1452000D01*
X1041458D01*
X1041792Y1451875D01*
X1042000Y1451708D01*
X1042083Y1451375D01*
X1042000Y1451042D01*
X1041750Y1450833D01*
X1041458Y1450708D01*
X1040417D01*
G01X1041458D02*
X1042083Y1449500D01*
G01X1044350D02*
Y1452000D01*
X1043850Y1451500D01*
G01Y1449500D02*
X1044850D01*
G01X1047450D02*
Y1452000D01*
X1046950Y1451500D01*
G01Y1449500D02*
X1047950D01*
G01X1050467D02*
X1050550Y1450042D01*
X1050675Y1450500D01*
X1050842Y1450917D01*
X1051050Y1451375D01*
X1051383Y1452000D01*
X1049717D01*
G01X1052733Y1450000D02*
X1052983Y1449708D01*
X1053317Y1449542D01*
X1053692Y1449500D01*
X1054025Y1449542D01*
X1054358Y1449750D01*
X1054567Y1450000D01*
X1054608Y1450250D01*
X1054525Y1450542D01*
X1054233Y1450750D01*
X1053942Y1450833D01*
X1053567D01*
G01X1053942D02*
X1054192Y1450958D01*
X1054400Y1451167D01*
X1054483Y1451417D01*
X1054400Y1451667D01*
X1054192Y1451875D01*
X1053817Y1452000D01*
X1053442Y1451958D01*
X1053067Y1451792D01*
G01X1049855Y1470211D02*
Y1465011D01*
G01X1042855Y1470211D02*
Y1462411D01*
G01X1049855Y1456811D02*
Y1465511D01*
G01X1042855Y1456811D02*
X1049855D01*
G01X1042855Y1463211D02*
Y1456811D01*
G01X1077955Y1470211D02*
X1070955D01*
G01X1049855D02*
X1042855D01*
G01X1053955Y1478511D02*
Y1508511D01*
X1076755D01*
Y1478511D01*
X1053955D01*
G01X1088022Y1486519D02*
X1087980Y1486186D01*
X1087814Y1485894D01*
X1087564Y1485644D01*
X1087272Y1485477D01*
X1086939Y1485394D01*
X1086605D01*
X1086272Y1485477D01*
X1085980Y1485644D01*
X1085730Y1485894D01*
X1085564Y1486186D01*
X1085522Y1486519D01*
X1085564Y1486852D01*
X1085730Y1487144D01*
X1085980Y1487394D01*
X1086272Y1487561D01*
X1086605Y1487644D01*
X1086939D01*
X1087272Y1487561D01*
X1087564Y1487394D01*
X1087814Y1487144D01*
X1087980Y1486852D01*
X1088022Y1486519D01*
G01X1087355Y1486852D02*
X1088022Y1487352D01*
G01X1085939Y1488827D02*
X1085689Y1489077D01*
X1085564Y1489369D01*
X1085522Y1489702D01*
X1085605Y1490119D01*
X1085814Y1490411D01*
X1086064Y1490494D01*
X1086314Y1490452D01*
X1086522Y1490286D01*
X1086939Y1489452D01*
X1087230Y1489077D01*
X1087647Y1488827D01*
X1088022Y1488744D01*
Y1490494D01*
G01X1085939Y1491927D02*
X1085689Y1492177D01*
X1085564Y1492469D01*
X1085522Y1492802D01*
X1085605Y1493219D01*
X1085814Y1493511D01*
X1086064Y1493594D01*
X1086314Y1493552D01*
X1086522Y1493386D01*
X1086939Y1492552D01*
X1087230Y1492177D01*
X1087647Y1491927D01*
X1088022Y1491844D01*
Y1493594D01*
G01Y1495736D02*
X1087480Y1495819D01*
X1087022Y1495944D01*
X1086605Y1496111D01*
X1086147Y1496319D01*
X1085522Y1496652D01*
Y1494986D01*
G01X1084322Y1486519D02*
X1084280Y1486186D01*
X1084114Y1485894D01*
X1083864Y1485644D01*
X1083572Y1485477D01*
X1083239Y1485394D01*
X1082905D01*
X1082572Y1485477D01*
X1082280Y1485644D01*
X1082030Y1485894D01*
X1081864Y1486186D01*
X1081822Y1486519D01*
X1081864Y1486852D01*
X1082030Y1487144D01*
X1082280Y1487394D01*
X1082572Y1487561D01*
X1082905Y1487644D01*
X1083239D01*
X1083572Y1487561D01*
X1083864Y1487394D01*
X1084114Y1487144D01*
X1084280Y1486852D01*
X1084322Y1486519D01*
G01X1083655Y1486852D02*
X1084322Y1487352D01*
G01X1082239Y1488827D02*
X1081989Y1489077D01*
X1081864Y1489369D01*
X1081822Y1489702D01*
X1081905Y1490119D01*
X1082114Y1490411D01*
X1082364Y1490494D01*
X1082614Y1490452D01*
X1082822Y1490286D01*
X1083239Y1489452D01*
X1083530Y1489077D01*
X1083947Y1488827D01*
X1084322Y1488744D01*
Y1490494D01*
G01X1082239Y1491927D02*
X1081989Y1492177D01*
X1081864Y1492469D01*
X1081822Y1492802D01*
X1081905Y1493219D01*
X1082114Y1493511D01*
X1082364Y1493594D01*
X1082614Y1493552D01*
X1082822Y1493386D01*
X1083239Y1492552D01*
X1083530Y1492177D01*
X1083947Y1491927D01*
X1084322Y1491844D01*
Y1493594D01*
G01Y1495819D02*
X1084280Y1496111D01*
X1084155Y1496444D01*
X1083947Y1496652D01*
X1083655Y1496736D01*
X1083364Y1496652D01*
X1083114Y1496402D01*
X1082989Y1496027D01*
Y1495611D01*
X1082905Y1495361D01*
X1082697Y1495152D01*
X1082405Y1495069D01*
X1082114Y1495194D01*
X1081905Y1495486D01*
X1081822Y1495819D01*
X1081905Y1496152D01*
X1082114Y1496444D01*
X1082405Y1496569D01*
X1082697Y1496486D01*
X1082905Y1496277D01*
X1082989Y1496027D01*
Y1495611D01*
X1083114Y1495236D01*
X1083364Y1494986D01*
X1083655Y1494902D01*
X1083947Y1494986D01*
X1084155Y1495194D01*
X1084280Y1495527D01*
X1084322Y1495819D01*
G01X1082865Y1521508D02*
Y1524008D01*
X1083699D01*
X1084032Y1523883D01*
X1084282Y1523716D01*
X1084490Y1523466D01*
X1084657Y1523175D01*
X1084699Y1522758D01*
X1084657Y1522341D01*
X1084490Y1522050D01*
X1084282Y1521800D01*
X1084032Y1521633D01*
X1083699Y1521508D01*
X1082865D01*
G01X1087382D02*
Y1524008D01*
X1085840Y1522216D01*
X1087924D01*
G01X1089982Y1524008D02*
X1089649Y1523925D01*
X1089399Y1523716D01*
X1089232Y1523466D01*
X1089107Y1523133D01*
X1089065Y1522758D01*
X1089107Y1522383D01*
X1089232Y1522050D01*
X1089399Y1521800D01*
X1089649Y1521591D01*
X1089982Y1521508D01*
X1090315Y1521591D01*
X1090565Y1521800D01*
X1090732Y1522050D01*
X1090857Y1522383D01*
X1090899Y1522758D01*
X1090857Y1523133D01*
X1090732Y1523466D01*
X1090565Y1523716D01*
X1090315Y1523925D01*
X1089982Y1524008D01*
G01X1060708Y1559020D02*
Y1533820D01*
X1099008D01*
Y1559020D01*
X1060708D01*
G01X1083862Y1528985D02*
X1083612Y1529110D01*
X1083320Y1529193D01*
X1082987D01*
X1082612Y1529068D01*
X1082320Y1528860D01*
X1082112Y1528610D01*
X1081945Y1528193D01*
X1081903Y1527818D01*
X1081987Y1527443D01*
X1082112Y1527193D01*
X1082362Y1526943D01*
X1082653Y1526776D01*
X1082945Y1526693D01*
X1083237D01*
X1083528Y1526776D01*
X1083778Y1526901D01*
X1083987Y1527068D01*
G01X1085128D02*
X1085378Y1526860D01*
X1085670Y1526735D01*
X1086045Y1526693D01*
X1086420Y1526776D01*
X1086712Y1526943D01*
X1086920Y1527235D01*
X1086962Y1527568D01*
X1086878Y1527901D01*
X1086670Y1528110D01*
X1086378Y1528276D01*
X1086087Y1528318D01*
X1085795Y1528276D01*
X1085420Y1528110D01*
X1085545Y1529193D01*
X1086670D01*
G01X1088437Y1526985D02*
X1088728Y1526776D01*
X1089062Y1526693D01*
X1089395Y1526776D01*
X1089687Y1527026D01*
X1089895Y1527401D01*
X1089978Y1527776D01*
Y1528235D01*
X1089895Y1528610D01*
X1089687Y1528943D01*
X1089437Y1529110D01*
X1089145Y1529193D01*
X1088812Y1529110D01*
X1088562Y1528943D01*
X1088395Y1528693D01*
X1088312Y1528360D01*
X1088395Y1528068D01*
X1088603Y1527776D01*
X1088853Y1527610D01*
X1089145Y1527568D01*
X1089478Y1527651D01*
X1089728Y1527860D01*
X1089978Y1528235D01*
G01X1091328Y1527193D02*
X1091578Y1526901D01*
X1091912Y1526735D01*
X1092287Y1526693D01*
X1092620Y1526735D01*
X1092953Y1526943D01*
X1093162Y1527193D01*
X1093203Y1527443D01*
X1093120Y1527735D01*
X1092828Y1527943D01*
X1092537Y1528026D01*
X1092162D01*
G01X1092537D02*
X1092787Y1528151D01*
X1092995Y1528360D01*
X1093078Y1528610D01*
X1092995Y1528860D01*
X1092787Y1529068D01*
X1092412Y1529193D01*
X1092037Y1529151D01*
X1091662Y1528985D01*
G01X1073722Y1627645D02*
Y1630145D01*
X1074556D01*
X1074889Y1630020D01*
X1075139Y1629853D01*
X1075347Y1629603D01*
X1075514Y1629312D01*
X1075556Y1628895D01*
X1075514Y1628478D01*
X1075347Y1628187D01*
X1075139Y1627937D01*
X1074889Y1627770D01*
X1074556Y1627645D01*
X1073722D01*
G01X1076906D02*
Y1630145D01*
X1077906D01*
X1078239Y1630020D01*
X1078489Y1629728D01*
X1078572Y1629395D01*
X1078489Y1629062D01*
X1078281Y1628812D01*
X1077906Y1628687D01*
X1076906D01*
G01X1081172Y1628978D02*
X1081339Y1629103D01*
X1081464Y1629312D01*
X1081547Y1629603D01*
X1081464Y1629853D01*
X1081297Y1630020D01*
X1081006Y1630145D01*
X1079881D01*
Y1627645D01*
X1081256D01*
X1081547Y1627812D01*
X1081714Y1628062D01*
X1081797Y1628353D01*
X1081714Y1628645D01*
X1081464Y1628895D01*
X1081172Y1628978D01*
X1079881D01*
G01X1083147Y1629728D02*
X1083397Y1629978D01*
X1083689Y1630103D01*
X1084022Y1630145D01*
X1084439Y1630062D01*
X1084731Y1629853D01*
X1084814Y1629603D01*
X1084772Y1629353D01*
X1084606Y1629145D01*
X1083772Y1628728D01*
X1083397Y1628437D01*
X1083147Y1628020D01*
X1083064Y1627645D01*
X1084814D01*
G01X1118845Y-79172D02*
Y-76672D01*
X1119886D01*
X1120220Y-76797D01*
X1120428Y-76964D01*
X1120511Y-77297D01*
X1120428Y-77630D01*
X1120178Y-77839D01*
X1119886Y-77964D01*
X1118845D01*
G01X1119886D02*
X1120511Y-79172D01*
G01X1122778D02*
Y-76672D01*
X1122278Y-77172D01*
G01Y-79172D02*
X1123278D01*
G01X1124961Y-78797D02*
X1125211Y-79005D01*
X1125503Y-79130D01*
X1125878Y-79172D01*
X1126253Y-79089D01*
X1126545Y-78922D01*
X1126753Y-78630D01*
X1126795Y-78297D01*
X1126711Y-77964D01*
X1126503Y-77755D01*
X1126211Y-77589D01*
X1125920Y-77547D01*
X1125628Y-77589D01*
X1125253Y-77755D01*
X1125378Y-76672D01*
X1126503D01*
G01X1098900Y-76400D02*
Y-80400D01*
X1106300D01*
G01X1135292Y-89192D02*
Y-86692D01*
X1136333D01*
X1136667Y-86817D01*
X1136875Y-86984D01*
X1136958Y-87317D01*
X1136875Y-87650D01*
X1136625Y-87859D01*
X1136333Y-87984D01*
X1135292D01*
G01X1136333D02*
X1136958Y-89192D01*
G01X1139225D02*
Y-86692D01*
X1138725Y-87192D01*
G01Y-89192D02*
X1139725D01*
G01X1141533Y-88150D02*
X1141825Y-87859D01*
X1142075Y-87692D01*
X1142408Y-87609D01*
X1142700Y-87692D01*
X1142908Y-87859D01*
X1143075Y-88109D01*
X1143117Y-88400D01*
X1143075Y-88650D01*
X1142908Y-88900D01*
X1142658Y-89109D01*
X1142367Y-89192D01*
X1142033Y-89109D01*
X1141742Y-88859D01*
X1141575Y-88484D01*
X1141533Y-88067D01*
X1141617Y-87525D01*
X1141742Y-87234D01*
X1141950Y-86942D01*
X1142242Y-86734D01*
X1142533Y-86692D01*
X1142825Y-86775D01*
X1143033Y-86984D01*
G01X1115300Y-91600D02*
Y-87600D01*
X1107900D01*
G01X1135292Y-81792D02*
Y-79292D01*
X1136333D01*
X1136667Y-79417D01*
X1136875Y-79584D01*
X1136958Y-79917D01*
X1136875Y-80250D01*
X1136625Y-80459D01*
X1136333Y-80584D01*
X1135292D01*
G01X1136333D02*
X1136958Y-81792D01*
G01X1139225D02*
Y-79292D01*
X1138725Y-79792D01*
G01Y-81792D02*
X1139725D01*
G01X1142325D02*
Y-79292D01*
X1141825Y-79792D01*
G01Y-81792D02*
X1142825D01*
G01X1144508Y-81292D02*
X1144758Y-81584D01*
X1145092Y-81750D01*
X1145467Y-81792D01*
X1145800Y-81750D01*
X1146133Y-81542D01*
X1146342Y-81292D01*
X1146383Y-81042D01*
X1146300Y-80750D01*
X1146008Y-80542D01*
X1145717Y-80459D01*
X1145342D01*
G01X1145717D02*
X1145967Y-80334D01*
X1146175Y-80125D01*
X1146258Y-79875D01*
X1146175Y-79625D01*
X1145967Y-79417D01*
X1145592Y-79292D01*
X1145217Y-79334D01*
X1144842Y-79500D01*
G01X1148442Y-81792D02*
X1148525Y-81250D01*
X1148650Y-80792D01*
X1148817Y-80375D01*
X1149025Y-79917D01*
X1149358Y-79292D01*
X1147692D01*
G01X1107921Y-78838D02*
Y-82838D01*
X1115321D01*
G01X1135292Y-85492D02*
Y-82992D01*
X1136333D01*
X1136667Y-83117D01*
X1136875Y-83284D01*
X1136958Y-83617D01*
X1136875Y-83950D01*
X1136625Y-84159D01*
X1136333Y-84284D01*
X1135292D01*
G01X1136333D02*
X1136958Y-85492D01*
G01X1139225D02*
Y-82992D01*
X1138725Y-83492D01*
G01Y-85492D02*
X1139725D01*
G01X1142325D02*
Y-82992D01*
X1141825Y-83492D01*
G01Y-85492D02*
X1142825D01*
G01X1144508Y-84992D02*
X1144758Y-85284D01*
X1145092Y-85450D01*
X1145467Y-85492D01*
X1145800Y-85450D01*
X1146133Y-85242D01*
X1146342Y-84992D01*
X1146383Y-84742D01*
X1146300Y-84450D01*
X1146008Y-84242D01*
X1145717Y-84159D01*
X1145342D01*
G01X1145717D02*
X1145967Y-84034D01*
X1146175Y-83825D01*
X1146258Y-83575D01*
X1146175Y-83325D01*
X1145967Y-83117D01*
X1145592Y-82992D01*
X1145217Y-83034D01*
X1144842Y-83200D01*
G01X1147733Y-84450D02*
X1148025Y-84159D01*
X1148275Y-83992D01*
X1148608Y-83909D01*
X1148900Y-83992D01*
X1149108Y-84159D01*
X1149275Y-84409D01*
X1149317Y-84700D01*
X1149275Y-84950D01*
X1149108Y-85200D01*
X1148858Y-85409D01*
X1148567Y-85492D01*
X1148233Y-85409D01*
X1147942Y-85159D01*
X1147775Y-84784D01*
X1147733Y-84367D01*
X1147817Y-83825D01*
X1147942Y-83534D01*
X1148150Y-83242D01*
X1148442Y-83034D01*
X1148733Y-82992D01*
X1149025Y-83075D01*
X1149233Y-83284D01*
G01X1115321Y-87538D02*
Y-83538D01*
X1107921D01*
G01X1118845Y-82872D02*
Y-80372D01*
X1119886D01*
X1120220Y-80497D01*
X1120428Y-80664D01*
X1120511Y-80997D01*
X1120428Y-81330D01*
X1120178Y-81539D01*
X1119886Y-81664D01*
X1118845D01*
G01X1119886D02*
X1120511Y-82872D01*
G01X1122778D02*
Y-80372D01*
X1122278Y-80872D01*
G01Y-82872D02*
X1123278D01*
G01X1125878D02*
Y-80372D01*
X1125378Y-80872D01*
G01Y-82872D02*
X1126378D01*
G01X1128061Y-82372D02*
X1128311Y-82664D01*
X1128645Y-82830D01*
X1129020Y-82872D01*
X1129353Y-82830D01*
X1129686Y-82622D01*
X1129895Y-82372D01*
X1129936Y-82122D01*
X1129853Y-81830D01*
X1129561Y-81622D01*
X1129270Y-81539D01*
X1128895D01*
G01X1129270D02*
X1129520Y-81414D01*
X1129728Y-81205D01*
X1129811Y-80955D01*
X1129728Y-80705D01*
X1129520Y-80497D01*
X1129145Y-80372D01*
X1128770Y-80414D01*
X1128395Y-80580D01*
G01X1131161Y-82497D02*
X1131411Y-82705D01*
X1131703Y-82830D01*
X1132078Y-82872D01*
X1132453Y-82789D01*
X1132745Y-82622D01*
X1132953Y-82330D01*
X1132995Y-81997D01*
X1132911Y-81664D01*
X1132703Y-81455D01*
X1132411Y-81289D01*
X1132120Y-81247D01*
X1131828Y-81289D01*
X1131453Y-81455D01*
X1131578Y-80372D01*
X1132703D01*
G01X1106279Y-84462D02*
Y-80462D01*
X1098879D01*
G01X1118845Y-86572D02*
Y-84072D01*
X1119886D01*
X1120220Y-84197D01*
X1120428Y-84364D01*
X1120511Y-84697D01*
X1120428Y-85030D01*
X1120178Y-85239D01*
X1119886Y-85364D01*
X1118845D01*
G01X1119886D02*
X1120511Y-86572D01*
G01X1122778D02*
Y-84072D01*
X1122278Y-84572D01*
G01Y-86572D02*
X1123278D01*
G01X1125878D02*
Y-84072D01*
X1125378Y-84572D01*
G01Y-86572D02*
X1126378D01*
G01X1128061Y-86072D02*
X1128311Y-86364D01*
X1128645Y-86530D01*
X1129020Y-86572D01*
X1129353Y-86530D01*
X1129686Y-86322D01*
X1129895Y-86072D01*
X1129936Y-85822D01*
X1129853Y-85530D01*
X1129561Y-85322D01*
X1129270Y-85239D01*
X1128895D01*
G01X1129270D02*
X1129520Y-85114D01*
X1129728Y-84905D01*
X1129811Y-84655D01*
X1129728Y-84405D01*
X1129520Y-84197D01*
X1129145Y-84072D01*
X1128770Y-84114D01*
X1128395Y-84280D01*
G01X1132578Y-86572D02*
Y-84072D01*
X1131036Y-85864D01*
X1133120D01*
G01X1098979Y-84862D02*
Y-88862D01*
X1106379D01*
G01X1095000Y-80432D02*
Y-67032D01*
G01X1092193Y-58265D02*
Y-55765D01*
X1093234D01*
X1093568Y-55890D01*
X1093776Y-56057D01*
X1093859Y-56390D01*
X1093776Y-56723D01*
X1093526Y-56932D01*
X1093234Y-57057D01*
X1092193D01*
G01X1093234D02*
X1093859Y-58265D01*
G01X1095334Y-57223D02*
X1095626Y-56932D01*
X1095876Y-56765D01*
X1096209Y-56682D01*
X1096501Y-56765D01*
X1096709Y-56932D01*
X1096876Y-57182D01*
X1096918Y-57473D01*
X1096876Y-57723D01*
X1096709Y-57973D01*
X1096459Y-58182D01*
X1096168Y-58265D01*
X1095834Y-58182D01*
X1095543Y-57932D01*
X1095376Y-57557D01*
X1095334Y-57140D01*
X1095418Y-56598D01*
X1095543Y-56307D01*
X1095751Y-56015D01*
X1096043Y-55807D01*
X1096334Y-55765D01*
X1096626Y-55848D01*
X1096834Y-56057D01*
G01X1098309Y-57765D02*
X1098559Y-58057D01*
X1098893Y-58223D01*
X1099268Y-58265D01*
X1099601Y-58223D01*
X1099934Y-58015D01*
X1100143Y-57765D01*
X1100184Y-57515D01*
X1100101Y-57223D01*
X1099809Y-57015D01*
X1099518Y-56932D01*
X1099143D01*
G01X1099518D02*
X1099768Y-56807D01*
X1099976Y-56598D01*
X1100059Y-56348D01*
X1099976Y-56098D01*
X1099768Y-55890D01*
X1099393Y-55765D01*
X1099018Y-55807D01*
X1098643Y-55973D01*
G01X1101534Y-56182D02*
X1101784Y-55932D01*
X1102076Y-55807D01*
X1102409Y-55765D01*
X1102826Y-55848D01*
X1103118Y-56057D01*
X1103201Y-56307D01*
X1103159Y-56557D01*
X1102993Y-56765D01*
X1102159Y-57182D01*
X1101784Y-57473D01*
X1101534Y-57890D01*
X1101451Y-58265D01*
X1103201D01*
G01X1103814Y-36858D02*
X1103772Y-37191D01*
X1103606Y-37483D01*
X1103356Y-37733D01*
X1103064Y-37900D01*
X1102731Y-37983D01*
X1102397D01*
X1102064Y-37900D01*
X1101772Y-37733D01*
X1101522Y-37483D01*
X1101356Y-37191D01*
X1101314Y-36858D01*
X1101356Y-36525D01*
X1101522Y-36233D01*
X1101772Y-35983D01*
X1102064Y-35816D01*
X1102397Y-35733D01*
X1102731D01*
X1103064Y-35816D01*
X1103356Y-35983D01*
X1103606Y-36233D01*
X1103772Y-36525D01*
X1103814Y-36858D01*
G01X1103147Y-36525D02*
X1103814Y-36025D01*
G01Y-33758D02*
X1101314D01*
X1101814Y-34258D01*
G01X1103814D02*
Y-33258D01*
G01Y-30658D02*
X1101314D01*
X1101814Y-31158D01*
G01X1103814D02*
Y-30158D01*
G01X1097000Y-51000D02*
X1104600D01*
G01X1097000Y-40200D02*
Y-51000D01*
G01X1104600Y-40200D02*
X1097000D01*
G01X1104600Y-51000D02*
Y-40200D01*
G01X1114483Y-66334D02*
Y-68126D01*
X1114650Y-68501D01*
X1114983Y-68751D01*
X1115400Y-68834D01*
X1115817Y-68751D01*
X1116150Y-68501D01*
X1116317Y-68126D01*
Y-66334D01*
G01X1119000Y-68834D02*
Y-66334D01*
X1117458Y-68126D01*
X1119542D01*
G01X1122100Y-68834D02*
Y-66334D01*
X1120558Y-68126D01*
X1122642D01*
G01X1101662Y-75521D02*
X1113062D01*
G01X1101662Y-62121D02*
Y-75521D01*
G01X1113062Y-62121D02*
X1101662D01*
G01X1113062Y-75521D02*
Y-62121D01*
G01X1100114Y-37691D02*
X1097614D01*
Y-36650D01*
X1097739Y-36316D01*
X1097906Y-36108D01*
X1098239Y-36025D01*
X1098572Y-36108D01*
X1098781Y-36358D01*
X1098906Y-36650D01*
Y-37691D01*
G01Y-36650D02*
X1100114Y-36025D01*
G01Y-33758D02*
X1097614D01*
X1098114Y-34258D01*
G01X1100114D02*
Y-33258D01*
G01X1098031Y-31450D02*
X1097781Y-31200D01*
X1097656Y-30908D01*
X1097614Y-30575D01*
X1097697Y-30158D01*
X1097906Y-29866D01*
X1098156Y-29783D01*
X1098406Y-29825D01*
X1098614Y-29991D01*
X1099031Y-30825D01*
X1099322Y-31200D01*
X1099739Y-31450D01*
X1100114Y-31533D01*
Y-29783D01*
G01X1099822Y-28266D02*
X1100031Y-27975D01*
X1100114Y-27641D01*
X1100031Y-27308D01*
X1099781Y-27016D01*
X1099406Y-26808D01*
X1099031Y-26725D01*
X1098572D01*
X1098197Y-26808D01*
X1097864Y-27016D01*
X1097697Y-27266D01*
X1097614Y-27558D01*
X1097697Y-27891D01*
X1097864Y-28141D01*
X1098114Y-28308D01*
X1098447Y-28391D01*
X1098739Y-28308D01*
X1099031Y-28100D01*
X1099197Y-27850D01*
X1099239Y-27558D01*
X1099156Y-27225D01*
X1098947Y-26975D01*
X1098572Y-26725D01*
G01X1099072Y-25250D02*
X1098781Y-24958D01*
X1098614Y-24708D01*
X1098531Y-24375D01*
X1098614Y-24083D01*
X1098781Y-23875D01*
X1099031Y-23708D01*
X1099322Y-23666D01*
X1099572Y-23708D01*
X1099822Y-23875D01*
X1100031Y-24125D01*
X1100114Y-24416D01*
X1100031Y-24750D01*
X1099781Y-25041D01*
X1099406Y-25208D01*
X1098989Y-25250D01*
X1098447Y-25166D01*
X1098156Y-25041D01*
X1097864Y-24833D01*
X1097656Y-24541D01*
X1097614Y-24250D01*
X1097697Y-23958D01*
X1097906Y-23750D01*
G01X1107682Y-35711D02*
X1107432Y-35586D01*
X1107140Y-35503D01*
X1106807D01*
X1106432Y-35628D01*
X1106140Y-35836D01*
X1105932Y-36086D01*
X1105765Y-36503D01*
X1105723Y-36878D01*
X1105807Y-37253D01*
X1105932Y-37503D01*
X1106182Y-37753D01*
X1106473Y-37920D01*
X1106765Y-38003D01*
X1107057D01*
X1107348Y-37920D01*
X1107598Y-37795D01*
X1107807Y-37628D01*
G01X1109865Y-38003D02*
Y-35503D01*
X1109365Y-36003D01*
G01Y-38003D02*
X1110365D01*
G01X1112965Y-35503D02*
X1112632Y-35586D01*
X1112382Y-35795D01*
X1112215Y-36045D01*
X1112090Y-36378D01*
X1112048Y-36753D01*
X1112090Y-37128D01*
X1112215Y-37461D01*
X1112382Y-37711D01*
X1112632Y-37920D01*
X1112965Y-38003D01*
X1113298Y-37920D01*
X1113548Y-37711D01*
X1113715Y-37461D01*
X1113840Y-37128D01*
X1113882Y-36753D01*
X1113840Y-36378D01*
X1113715Y-36045D01*
X1113548Y-35795D01*
X1113298Y-35586D01*
X1112965Y-35503D01*
G01X1116065Y-38003D02*
X1116357Y-37961D01*
X1116690Y-37836D01*
X1116898Y-37628D01*
X1116982Y-37336D01*
X1116898Y-37045D01*
X1116648Y-36795D01*
X1116273Y-36670D01*
X1115857D01*
X1115607Y-36586D01*
X1115398Y-36378D01*
X1115315Y-36086D01*
X1115440Y-35795D01*
X1115732Y-35586D01*
X1116065Y-35503D01*
X1116398Y-35586D01*
X1116690Y-35795D01*
X1116815Y-36086D01*
X1116732Y-36378D01*
X1116523Y-36586D01*
X1116273Y-36670D01*
X1115857D01*
X1115482Y-36795D01*
X1115232Y-37045D01*
X1115148Y-37336D01*
X1115232Y-37628D01*
X1115440Y-37836D01*
X1115773Y-37961D01*
X1116065Y-38003D01*
G01X1118767Y-54542D02*
X1118517Y-54417D01*
X1118225Y-54334D01*
X1117892D01*
X1117517Y-54459D01*
X1117225Y-54667D01*
X1117017Y-54917D01*
X1116850Y-55334D01*
X1116808Y-55709D01*
X1116892Y-56084D01*
X1117017Y-56334D01*
X1117267Y-56584D01*
X1117558Y-56751D01*
X1117850Y-56834D01*
X1118142D01*
X1118433Y-56751D01*
X1118683Y-56626D01*
X1118892Y-56459D01*
G01X1120950Y-56834D02*
Y-54334D01*
X1120450Y-54834D01*
G01Y-56834D02*
X1121450D01*
G01X1124050Y-54334D02*
X1123717Y-54417D01*
X1123467Y-54626D01*
X1123300Y-54876D01*
X1123175Y-55209D01*
X1123133Y-55584D01*
X1123175Y-55959D01*
X1123300Y-56292D01*
X1123467Y-56542D01*
X1123717Y-56751D01*
X1124050Y-56834D01*
X1124383Y-56751D01*
X1124633Y-56542D01*
X1124800Y-56292D01*
X1124925Y-55959D01*
X1124967Y-55584D01*
X1124925Y-55209D01*
X1124800Y-54876D01*
X1124633Y-54626D01*
X1124383Y-54417D01*
X1124050Y-54334D01*
G01X1127067Y-56834D02*
X1127150Y-56292D01*
X1127275Y-55834D01*
X1127442Y-55417D01*
X1127650Y-54959D01*
X1127983Y-54334D01*
X1126317D01*
G01X1091200Y-39100D02*
Y-55200D01*
G01X1131536Y-235D02*
X1093836D01*
Y352165D01*
X1131536D01*
Y-235D01*
G01X1130336Y151632D02*
X1126336D01*
Y153232D01*
X1126536Y153765D01*
X1127003Y154165D01*
X1127536Y154298D01*
X1128069Y154165D01*
X1128469Y153832D01*
X1128669Y153232D01*
Y151632D01*
G01X1130336Y156632D02*
X1127669D01*
G01X1128203D02*
X1127936Y156965D01*
X1127736Y157298D01*
X1127669Y157765D01*
X1127736Y158098D01*
X1127936Y158498D01*
G01X1128536Y161165D02*
Y163298D01*
X1128069Y163098D01*
X1127803Y162765D01*
X1127669Y162298D01*
X1127736Y161832D01*
X1127936Y161432D01*
X1128403Y161165D01*
X1128803Y161032D01*
X1129203D01*
X1129603Y161165D01*
X1130003Y161498D01*
X1130269Y161898D01*
X1130336Y162365D01*
X1130203Y162832D01*
X1129803Y163298D01*
G01X1129869Y165765D02*
X1130136Y166098D01*
X1130336Y166565D01*
Y166965D01*
X1130203Y167365D01*
X1130003Y167632D01*
X1129736Y167765D01*
X1129336Y167698D01*
X1129136Y167432D01*
X1128736Y166232D01*
X1128269Y165965D01*
X1127936Y166098D01*
X1127736Y166365D01*
X1127669Y166765D01*
X1127736Y167165D01*
X1127936Y167565D01*
G01X1129869Y170365D02*
X1130136Y170698D01*
X1130336Y171165D01*
Y171565D01*
X1130203Y171965D01*
X1130003Y172232D01*
X1129736Y172365D01*
X1129336Y172298D01*
X1129136Y172032D01*
X1128736Y170832D01*
X1128269Y170565D01*
X1127936Y170698D01*
X1127736Y170965D01*
X1127669Y171365D01*
X1127736Y171765D01*
X1127936Y172165D01*
G01X1130336Y179298D02*
X1126336D01*
Y181832D01*
G01X1128269Y180898D02*
Y179298D01*
G01X1127669Y185165D02*
X1130336D01*
G01X1126603D02*
X1126536Y185032D01*
X1126403D01*
X1126336Y185165D01*
X1126403Y185298D01*
X1126536D01*
X1126603Y185165D01*
G01X1126336Y189765D02*
X1130336D01*
G01X1127669Y188832D02*
Y190698D01*
G01X1131536Y378898D02*
X1093836D01*
Y731298D01*
X1131536D01*
Y378898D01*
G01X1130336Y530765D02*
X1126336D01*
Y532365D01*
X1126536Y532898D01*
X1127003Y533298D01*
X1127536Y533431D01*
X1128069Y533298D01*
X1128469Y532965D01*
X1128669Y532365D01*
Y530765D01*
G01X1130336Y535765D02*
X1127669D01*
G01X1128203D02*
X1127936Y536098D01*
X1127736Y536431D01*
X1127669Y536898D01*
X1127736Y537231D01*
X1127936Y537631D01*
G01X1128536Y540298D02*
Y542431D01*
X1128069Y542231D01*
X1127803Y541898D01*
X1127669Y541431D01*
X1127736Y540965D01*
X1127936Y540565D01*
X1128403Y540298D01*
X1128803Y540165D01*
X1129203D01*
X1129603Y540298D01*
X1130003Y540631D01*
X1130269Y541031D01*
X1130336Y541498D01*
X1130203Y541965D01*
X1129803Y542431D01*
G01X1129869Y544898D02*
X1130136Y545231D01*
X1130336Y545698D01*
Y546098D01*
X1130203Y546498D01*
X1130003Y546765D01*
X1129736Y546898D01*
X1129336Y546831D01*
X1129136Y546565D01*
X1128736Y545365D01*
X1128269Y545098D01*
X1127936Y545231D01*
X1127736Y545498D01*
X1127669Y545898D01*
X1127736Y546298D01*
X1127936Y546698D01*
G01X1129869Y549498D02*
X1130136Y549831D01*
X1130336Y550298D01*
Y550698D01*
X1130203Y551098D01*
X1130003Y551365D01*
X1129736Y551498D01*
X1129336Y551431D01*
X1129136Y551165D01*
X1128736Y549965D01*
X1128269Y549698D01*
X1127936Y549831D01*
X1127736Y550098D01*
X1127669Y550498D01*
X1127736Y550898D01*
X1127936Y551298D01*
G01X1130336Y558431D02*
X1126336D01*
Y560965D01*
G01X1128269Y560031D02*
Y558431D01*
G01X1127669Y564298D02*
X1130336D01*
G01X1126603D02*
X1126536Y564165D01*
X1126403D01*
X1126336Y564298D01*
X1126403Y564431D01*
X1126536D01*
X1126603Y564298D01*
G01X1126336Y568898D02*
X1130336D01*
G01X1127669Y567965D02*
Y569831D01*
G01X1102217Y777500D02*
Y780000D01*
X1103300Y777917D01*
X1104383Y780000D01*
Y777500D01*
G01X1106400D02*
X1106067Y777542D01*
X1105775Y777708D01*
X1105525Y777958D01*
X1105358Y778250D01*
X1105275Y778583D01*
Y778917D01*
X1105358Y779250D01*
X1105525Y779542D01*
X1105775Y779792D01*
X1106067Y779958D01*
X1106400Y780000D01*
X1106733Y779958D01*
X1107025Y779792D01*
X1107275Y779542D01*
X1107442Y779250D01*
X1107525Y778917D01*
Y778583D01*
X1107442Y778250D01*
X1107275Y777958D01*
X1107025Y777708D01*
X1106733Y777542D01*
X1106400Y777500D01*
G01X1108542D02*
Y780000D01*
X1110458Y777500D01*
Y780000D01*
G01X1112600Y777500D02*
X1112267Y777542D01*
X1111975Y777708D01*
X1111725Y777958D01*
X1111558Y778250D01*
X1111475Y778583D01*
Y778917D01*
X1111558Y779250D01*
X1111725Y779542D01*
X1111975Y779792D01*
X1112267Y779958D01*
X1112600Y780000D01*
X1112933Y779958D01*
X1113225Y779792D01*
X1113475Y779542D01*
X1113642Y779250D01*
X1113725Y778917D01*
Y778583D01*
X1113642Y778250D01*
X1113475Y777958D01*
X1113225Y777708D01*
X1112933Y777542D01*
X1112600Y777500D01*
G01X1116200D02*
Y780000D01*
X1114658Y778208D01*
X1116742D01*
G01X1102217Y782000D02*
Y784500D01*
X1103300Y782417D01*
X1104383Y784500D01*
Y782000D01*
G01X1106400D02*
X1106067Y782042D01*
X1105775Y782208D01*
X1105525Y782458D01*
X1105358Y782750D01*
X1105275Y783083D01*
Y783417D01*
X1105358Y783750D01*
X1105525Y784042D01*
X1105775Y784292D01*
X1106067Y784458D01*
X1106400Y784500D01*
X1106733Y784458D01*
X1107025Y784292D01*
X1107275Y784042D01*
X1107442Y783750D01*
X1107525Y783417D01*
Y783083D01*
X1107442Y782750D01*
X1107275Y782458D01*
X1107025Y782208D01*
X1106733Y782042D01*
X1106400Y782000D01*
G01X1108542D02*
Y784500D01*
X1110458Y782000D01*
Y784500D01*
G01X1112600Y782000D02*
X1112267Y782042D01*
X1111975Y782208D01*
X1111725Y782458D01*
X1111558Y782750D01*
X1111475Y783083D01*
Y783417D01*
X1111558Y783750D01*
X1111725Y784042D01*
X1111975Y784292D01*
X1112267Y784458D01*
X1112600Y784500D01*
X1112933Y784458D01*
X1113225Y784292D01*
X1113475Y784042D01*
X1113642Y783750D01*
X1113725Y783417D01*
Y783083D01*
X1113642Y782750D01*
X1113475Y782458D01*
X1113225Y782208D01*
X1112933Y782042D01*
X1112600Y782000D01*
G01X1114783Y782500D02*
X1115033Y782208D01*
X1115367Y782042D01*
X1115742Y782000D01*
X1116075Y782042D01*
X1116408Y782250D01*
X1116617Y782500D01*
X1116658Y782750D01*
X1116575Y783042D01*
X1116283Y783250D01*
X1115992Y783333D01*
X1115617D01*
G01X1115992D02*
X1116242Y783458D01*
X1116450Y783667D01*
X1116533Y783917D01*
X1116450Y784167D01*
X1116242Y784375D01*
X1115867Y784500D01*
X1115492Y784458D01*
X1115117Y784292D01*
G01X1112047Y865254D02*
Y896854D01*
X1116747Y901554D01*
X1135347D01*
X1140047Y896854D01*
Y865254D01*
X1112047D01*
G01X1091647Y906767D02*
Y938367D01*
X1096347Y943067D01*
X1114947D01*
X1119647Y938367D01*
Y906767D01*
X1091647D01*
G01X1122550Y907000D02*
Y904500D01*
G01X1121592Y907000D02*
X1123508D01*
G01X1126567Y906792D02*
X1126317Y906917D01*
X1126025Y907000D01*
X1125692D01*
X1125317Y906875D01*
X1125025Y906667D01*
X1124817Y906417D01*
X1124650Y906000D01*
X1124608Y905625D01*
X1124692Y905250D01*
X1124817Y905000D01*
X1125067Y904750D01*
X1125358Y904583D01*
X1125650Y904500D01*
X1125942D01*
X1126233Y904583D01*
X1126483Y904708D01*
X1126692Y904875D01*
G01X1128750Y904500D02*
Y907000D01*
X1128250Y906500D01*
G01Y904500D02*
X1129250D01*
G01X1131058Y905542D02*
X1131350Y905833D01*
X1131600Y906000D01*
X1131933Y906083D01*
X1132225Y906000D01*
X1132433Y905833D01*
X1132600Y905583D01*
X1132642Y905292D01*
X1132600Y905042D01*
X1132433Y904792D01*
X1132183Y904583D01*
X1131892Y904500D01*
X1131558Y904583D01*
X1131267Y904833D01*
X1131100Y905208D01*
X1131058Y905625D01*
X1131142Y906167D01*
X1131267Y906458D01*
X1131475Y906750D01*
X1131767Y906958D01*
X1132058Y907000D01*
X1132350Y906917D01*
X1132558Y906708D01*
G01X1099997Y953417D02*
Y950917D01*
G01X1099039Y953417D02*
X1100955D01*
G01X1104014Y953209D02*
X1103764Y953334D01*
X1103472Y953417D01*
X1103139D01*
X1102764Y953292D01*
X1102472Y953084D01*
X1102264Y952834D01*
X1102097Y952417D01*
X1102055Y952042D01*
X1102139Y951667D01*
X1102264Y951417D01*
X1102514Y951167D01*
X1102805Y951000D01*
X1103097Y950917D01*
X1103389D01*
X1103680Y951000D01*
X1103930Y951125D01*
X1104139Y951292D01*
G01X1106197Y950917D02*
Y953417D01*
X1105697Y952917D01*
G01Y950917D02*
X1106697D01*
G01X1109797D02*
Y953417D01*
X1108255Y951625D01*
X1110339D01*
G01X1136365Y1026697D02*
X1140365D01*
Y1025097D01*
X1140165Y1024564D01*
X1139698Y1024164D01*
X1139165Y1024031D01*
X1138632Y1024164D01*
X1138232Y1024497D01*
X1138032Y1025097D01*
Y1026697D01*
G01X1136365Y1021697D02*
X1139032D01*
G01X1138498D02*
X1138765Y1021364D01*
X1138965Y1021031D01*
X1139032Y1020564D01*
X1138965Y1020231D01*
X1138765Y1019831D01*
G01X1138165Y1017164D02*
Y1015031D01*
X1138632Y1015231D01*
X1138898Y1015564D01*
X1139032Y1016031D01*
X1138965Y1016497D01*
X1138765Y1016897D01*
X1138298Y1017164D01*
X1137898Y1017297D01*
X1137498D01*
X1137098Y1017164D01*
X1136698Y1016831D01*
X1136432Y1016431D01*
X1136365Y1015964D01*
X1136498Y1015497D01*
X1136898Y1015031D01*
G01X1136832Y1012564D02*
X1136565Y1012231D01*
X1136365Y1011764D01*
Y1011364D01*
X1136498Y1010964D01*
X1136698Y1010697D01*
X1136965Y1010564D01*
X1137365Y1010631D01*
X1137565Y1010897D01*
X1137965Y1012097D01*
X1138432Y1012364D01*
X1138765Y1012231D01*
X1138965Y1011964D01*
X1139032Y1011564D01*
X1138965Y1011164D01*
X1138765Y1010764D01*
G01X1136832Y1007964D02*
X1136565Y1007631D01*
X1136365Y1007164D01*
Y1006764D01*
X1136498Y1006364D01*
X1136698Y1006097D01*
X1136965Y1005964D01*
X1137365Y1006031D01*
X1137565Y1006297D01*
X1137965Y1007497D01*
X1138432Y1007764D01*
X1138765Y1007631D01*
X1138965Y1007364D01*
X1139032Y1006964D01*
X1138965Y1006564D01*
X1138765Y1006164D01*
G01X1136365Y999031D02*
X1140365D01*
Y996497D01*
G01X1138432Y997431D02*
Y999031D01*
G01X1139032Y993164D02*
X1136365D01*
G01X1140098D02*
X1140165Y993297D01*
X1140298D01*
X1140365Y993164D01*
X1140298Y993031D01*
X1140165D01*
X1140098Y993164D01*
G01X1140365Y988564D02*
X1136365D01*
G01X1139032Y989497D02*
Y987631D01*
G01X1113200Y1068400D02*
X1117200D01*
Y1075800D01*
G01X1126900Y1068400D02*
X1130900D01*
Y1075800D01*
G01X1134500Y1065617D02*
X1132000D01*
Y1066658D01*
X1132125Y1066992D01*
X1132292Y1067200D01*
X1132625Y1067283D01*
X1132958Y1067200D01*
X1133167Y1066950D01*
X1133292Y1066658D01*
Y1065617D01*
G01Y1066658D02*
X1134500Y1067283D01*
G01Y1069550D02*
X1132000D01*
X1132500Y1069050D01*
G01X1134500D02*
Y1070050D01*
G01X1132417Y1071858D02*
X1132167Y1072108D01*
X1132042Y1072400D01*
X1132000Y1072733D01*
X1132083Y1073150D01*
X1132292Y1073442D01*
X1132542Y1073525D01*
X1132792Y1073483D01*
X1133000Y1073317D01*
X1133417Y1072483D01*
X1133708Y1072108D01*
X1134125Y1071858D01*
X1134500Y1071775D01*
Y1073525D01*
G01X1132417Y1074958D02*
X1132167Y1075208D01*
X1132042Y1075500D01*
X1132000Y1075833D01*
X1132083Y1076250D01*
X1132292Y1076542D01*
X1132542Y1076625D01*
X1132792Y1076583D01*
X1133000Y1076417D01*
X1133417Y1075583D01*
X1133708Y1075208D01*
X1134125Y1074958D01*
X1134500Y1074875D01*
Y1076625D01*
G01X1112500Y1075800D02*
X1108500D01*
Y1068400D01*
G01X1121700Y1075800D02*
X1117700D01*
Y1068400D01*
G01X1126500Y1075800D02*
X1122500D01*
Y1068400D01*
G01X1113850Y1080500D02*
Y1101500D01*
X1145500D01*
Y1090500D01*
X1113850D01*
G01X1111800Y1115717D02*
X1109300D01*
Y1116758D01*
X1109425Y1117092D01*
X1109592Y1117300D01*
X1109925Y1117383D01*
X1110258Y1117300D01*
X1110467Y1117050D01*
X1110592Y1116758D01*
Y1115717D01*
G01Y1116758D02*
X1111800Y1117383D01*
G01Y1119650D02*
X1109300D01*
X1109800Y1119150D01*
G01X1111800D02*
Y1120150D01*
G01Y1122750D02*
X1109300D01*
X1109800Y1122250D01*
G01X1111800D02*
Y1123250D01*
G01X1111508Y1125142D02*
X1111717Y1125433D01*
X1111800Y1125767D01*
X1111717Y1126100D01*
X1111467Y1126392D01*
X1111092Y1126600D01*
X1110717Y1126683D01*
X1110258D01*
X1109883Y1126600D01*
X1109550Y1126392D01*
X1109383Y1126142D01*
X1109300Y1125850D01*
X1109383Y1125517D01*
X1109550Y1125267D01*
X1109800Y1125100D01*
X1110133Y1125017D01*
X1110425Y1125100D01*
X1110717Y1125308D01*
X1110883Y1125558D01*
X1110925Y1125850D01*
X1110842Y1126183D01*
X1110633Y1126433D01*
X1110258Y1126683D01*
G01X1130800Y1123900D02*
X1126800D01*
Y1116500D01*
G01X1102500Y1115717D02*
X1100000D01*
Y1116758D01*
X1100125Y1117092D01*
X1100292Y1117300D01*
X1100625Y1117383D01*
X1100958Y1117300D01*
X1101167Y1117050D01*
X1101292Y1116758D01*
Y1115717D01*
G01Y1116758D02*
X1102500Y1117383D01*
G01Y1119650D02*
X1100000D01*
X1100500Y1119150D01*
G01X1102500D02*
Y1120150D01*
G01X1100417Y1121958D02*
X1100167Y1122208D01*
X1100042Y1122500D01*
X1100000Y1122833D01*
X1100083Y1123250D01*
X1100292Y1123542D01*
X1100542Y1123625D01*
X1100792Y1123583D01*
X1101000Y1123417D01*
X1101417Y1122583D01*
X1101708Y1122208D01*
X1102125Y1121958D01*
X1102500Y1121875D01*
Y1123625D01*
G01X1102000Y1124933D02*
X1102292Y1125183D01*
X1102458Y1125517D01*
X1102500Y1125892D01*
X1102458Y1126225D01*
X1102250Y1126558D01*
X1102000Y1126767D01*
X1101750Y1126808D01*
X1101458Y1126725D01*
X1101250Y1126433D01*
X1101167Y1126142D01*
Y1125767D01*
G01Y1126142D02*
X1101042Y1126392D01*
X1100833Y1126600D01*
X1100583Y1126683D01*
X1100333Y1126600D01*
X1100125Y1126392D01*
X1100000Y1126017D01*
X1100042Y1125642D01*
X1100208Y1125267D01*
G01X1117500Y1116500D02*
X1121500D01*
Y1123900D01*
G01X1107100Y1115717D02*
X1104600D01*
Y1116758D01*
X1104725Y1117092D01*
X1104892Y1117300D01*
X1105225Y1117383D01*
X1105558Y1117300D01*
X1105767Y1117050D01*
X1105892Y1116758D01*
Y1115717D01*
G01Y1116758D02*
X1107100Y1117383D01*
G01Y1119650D02*
X1104600D01*
X1105100Y1119150D01*
G01X1107100D02*
Y1120150D01*
G01X1105017Y1121958D02*
X1104767Y1122208D01*
X1104642Y1122500D01*
X1104600Y1122833D01*
X1104683Y1123250D01*
X1104892Y1123542D01*
X1105142Y1123625D01*
X1105392Y1123583D01*
X1105600Y1123417D01*
X1106017Y1122583D01*
X1106308Y1122208D01*
X1106725Y1121958D01*
X1107100Y1121875D01*
Y1123625D01*
G01Y1126350D02*
X1104600D01*
X1106392Y1124808D01*
Y1126892D01*
G01X1122100Y1116500D02*
X1126100D01*
Y1123900D01*
G01X1098000Y1115717D02*
X1095500D01*
Y1116758D01*
X1095625Y1117092D01*
X1095792Y1117300D01*
X1096125Y1117383D01*
X1096458Y1117300D01*
X1096667Y1117050D01*
X1096792Y1116758D01*
Y1115717D01*
G01Y1116758D02*
X1098000Y1117383D01*
G01Y1119650D02*
X1095500D01*
X1096000Y1119150D01*
G01X1098000D02*
Y1120150D01*
G01X1095917Y1121958D02*
X1095667Y1122208D01*
X1095542Y1122500D01*
X1095500Y1122833D01*
X1095583Y1123250D01*
X1095792Y1123542D01*
X1096042Y1123625D01*
X1096292Y1123583D01*
X1096500Y1123417D01*
X1096917Y1122583D01*
X1097208Y1122208D01*
X1097625Y1121958D01*
X1098000Y1121875D01*
Y1123625D01*
G01X1097625Y1124933D02*
X1097833Y1125183D01*
X1097958Y1125475D01*
X1098000Y1125850D01*
X1097917Y1126225D01*
X1097750Y1126517D01*
X1097458Y1126725D01*
X1097125Y1126767D01*
X1096792Y1126683D01*
X1096583Y1126475D01*
X1096417Y1126183D01*
X1096375Y1125892D01*
X1096417Y1125600D01*
X1096583Y1125225D01*
X1095500Y1125350D01*
Y1126475D01*
G01X1113000Y1116500D02*
X1117000D01*
Y1123900D01*
G01X1094200Y1124600D02*
X1090200D01*
Y1117200D01*
G01X1113850Y1099150D02*
X1117000Y1096000D01*
X1113850Y1092850D01*
G01X1105042Y1087817D02*
X1104917Y1087567D01*
X1104834Y1087275D01*
Y1086942D01*
X1104959Y1086567D01*
X1105167Y1086275D01*
X1105417Y1086067D01*
X1105834Y1085900D01*
X1106209Y1085858D01*
X1106584Y1085942D01*
X1106834Y1086067D01*
X1107084Y1086317D01*
X1107251Y1086608D01*
X1107334Y1086900D01*
Y1087192D01*
X1107251Y1087483D01*
X1107126Y1087733D01*
X1106959Y1087942D01*
G01X1106834Y1089083D02*
X1107126Y1089333D01*
X1107292Y1089667D01*
X1107334Y1090042D01*
X1107292Y1090375D01*
X1107084Y1090708D01*
X1106834Y1090917D01*
X1106584Y1090958D01*
X1106292Y1090875D01*
X1106084Y1090583D01*
X1106001Y1090292D01*
Y1089917D01*
G01Y1090292D02*
X1105876Y1090542D01*
X1105667Y1090750D01*
X1105417Y1090833D01*
X1105167Y1090750D01*
X1104959Y1090542D01*
X1104834Y1090167D01*
X1104876Y1089792D01*
X1105042Y1089417D01*
G01X1107334Y1093017D02*
X1106792Y1093100D01*
X1106334Y1093225D01*
X1105917Y1093392D01*
X1105459Y1093600D01*
X1104834Y1093933D01*
Y1092267D01*
G01X1109208Y1087817D02*
X1109083Y1087567D01*
X1109000Y1087275D01*
Y1086942D01*
X1109125Y1086567D01*
X1109333Y1086275D01*
X1109583Y1086067D01*
X1110000Y1085900D01*
X1110375Y1085858D01*
X1110750Y1085942D01*
X1111000Y1086067D01*
X1111250Y1086317D01*
X1111417Y1086608D01*
X1111500Y1086900D01*
Y1087192D01*
X1111417Y1087483D01*
X1111292Y1087733D01*
X1111125Y1087942D01*
G01X1111000Y1089083D02*
X1111292Y1089333D01*
X1111458Y1089667D01*
X1111500Y1090042D01*
X1111458Y1090375D01*
X1111250Y1090708D01*
X1111000Y1090917D01*
X1110750Y1090958D01*
X1110458Y1090875D01*
X1110250Y1090583D01*
X1110167Y1090292D01*
Y1089917D01*
G01Y1090292D02*
X1110042Y1090542D01*
X1109833Y1090750D01*
X1109583Y1090833D01*
X1109333Y1090750D01*
X1109125Y1090542D01*
X1109000Y1090167D01*
X1109042Y1089792D01*
X1109208Y1089417D01*
G01X1111500Y1093100D02*
X1111458Y1093392D01*
X1111333Y1093725D01*
X1111125Y1093933D01*
X1110833Y1094017D01*
X1110542Y1093933D01*
X1110292Y1093683D01*
X1110167Y1093308D01*
Y1092892D01*
X1110083Y1092642D01*
X1109875Y1092433D01*
X1109583Y1092350D01*
X1109292Y1092475D01*
X1109083Y1092767D01*
X1109000Y1093100D01*
X1109083Y1093433D01*
X1109292Y1093725D01*
X1109583Y1093850D01*
X1109875Y1093767D01*
X1110083Y1093558D01*
X1110167Y1093308D01*
Y1092892D01*
X1110292Y1092517D01*
X1110542Y1092267D01*
X1110833Y1092183D01*
X1111125Y1092267D01*
X1111333Y1092475D01*
X1111458Y1092808D01*
X1111500Y1093100D01*
G01X1091722Y1486519D02*
X1091680Y1486186D01*
X1091514Y1485894D01*
X1091264Y1485644D01*
X1090972Y1485477D01*
X1090639Y1485394D01*
X1090305D01*
X1089972Y1485477D01*
X1089680Y1485644D01*
X1089430Y1485894D01*
X1089264Y1486186D01*
X1089222Y1486519D01*
X1089264Y1486852D01*
X1089430Y1487144D01*
X1089680Y1487394D01*
X1089972Y1487561D01*
X1090305Y1487644D01*
X1090639D01*
X1090972Y1487561D01*
X1091264Y1487394D01*
X1091514Y1487144D01*
X1091680Y1486852D01*
X1091722Y1486519D01*
G01X1091055Y1486852D02*
X1091722Y1487352D01*
G01X1089639Y1488827D02*
X1089389Y1489077D01*
X1089264Y1489369D01*
X1089222Y1489702D01*
X1089305Y1490119D01*
X1089514Y1490411D01*
X1089764Y1490494D01*
X1090014Y1490452D01*
X1090222Y1490286D01*
X1090639Y1489452D01*
X1090930Y1489077D01*
X1091347Y1488827D01*
X1091722Y1488744D01*
Y1490494D01*
G01X1089639Y1491927D02*
X1089389Y1492177D01*
X1089264Y1492469D01*
X1089222Y1492802D01*
X1089305Y1493219D01*
X1089514Y1493511D01*
X1089764Y1493594D01*
X1090014Y1493552D01*
X1090222Y1493386D01*
X1090639Y1492552D01*
X1090930Y1492177D01*
X1091347Y1491927D01*
X1091722Y1491844D01*
Y1493594D01*
G01X1090680Y1495027D02*
X1090389Y1495319D01*
X1090222Y1495569D01*
X1090139Y1495902D01*
X1090222Y1496194D01*
X1090389Y1496402D01*
X1090639Y1496569D01*
X1090930Y1496611D01*
X1091180Y1496569D01*
X1091430Y1496402D01*
X1091639Y1496152D01*
X1091722Y1495861D01*
X1091639Y1495527D01*
X1091389Y1495236D01*
X1091014Y1495069D01*
X1090597Y1495027D01*
X1090055Y1495111D01*
X1089764Y1495236D01*
X1089472Y1495444D01*
X1089264Y1495736D01*
X1089222Y1496027D01*
X1089305Y1496319D01*
X1089514Y1496527D01*
G01X1112633Y1558919D02*
Y1561419D01*
X1113633D01*
X1113966Y1561294D01*
X1114216Y1561002D01*
X1114299Y1560669D01*
X1114216Y1560336D01*
X1114008Y1560086D01*
X1113633Y1559961D01*
X1112633D01*
G01X1115316Y1561419D02*
X1115899Y1558919D01*
X1116566Y1561419D01*
X1117233Y1558919D01*
X1117816Y1561419D01*
G01X1118833Y1558919D02*
Y1561419D01*
X1119874D01*
X1120208Y1561294D01*
X1120416Y1561127D01*
X1120499Y1560794D01*
X1120416Y1560461D01*
X1120166Y1560252D01*
X1119874Y1560127D01*
X1118833D01*
G01X1119874D02*
X1120499Y1558919D01*
G01X1122766D02*
Y1561419D01*
X1122266Y1560919D01*
G01Y1558919D02*
X1123266D01*
G01X1129878Y1607514D02*
X1133878D01*
Y1605914D01*
X1133678Y1605381D01*
X1133211Y1604981D01*
X1132678Y1604848D01*
X1132145Y1604981D01*
X1131745Y1605314D01*
X1131545Y1605914D01*
Y1607514D01*
G01X1129878Y1602514D02*
X1132545D01*
G01X1132011D02*
X1132278Y1602181D01*
X1132478Y1601848D01*
X1132545Y1601381D01*
X1132478Y1601048D01*
X1132278Y1600648D01*
G01X1131678Y1597981D02*
Y1595848D01*
X1132145Y1596048D01*
X1132411Y1596381D01*
X1132545Y1596848D01*
X1132478Y1597314D01*
X1132278Y1597714D01*
X1131811Y1597981D01*
X1131411Y1598114D01*
X1131011D01*
X1130611Y1597981D01*
X1130211Y1597648D01*
X1129945Y1597248D01*
X1129878Y1596781D01*
X1130011Y1596314D01*
X1130411Y1595848D01*
G01X1129878Y1589048D02*
X1133878D01*
Y1586514D01*
G01X1131945Y1587448D02*
Y1589048D01*
G01X1132545Y1583181D02*
X1129878D01*
G01X1133611D02*
X1133678Y1583314D01*
X1133811D01*
X1133878Y1583181D01*
X1133811Y1583048D01*
X1133678D01*
X1133611Y1583181D01*
G01X1133878Y1578581D02*
X1129878D01*
G01X1132545Y1579514D02*
Y1577648D01*
G01X1093778Y1606881D02*
X1134078D01*
Y1582881D01*
X1093778D01*
Y1606881D01*
G01X1202618Y42818D02*
X1183918D01*
Y53118D01*
X1202618D01*
Y42818D01*
G01X1175002Y98794D02*
Y94794D01*
X1182402D01*
G01X1174849Y103360D02*
Y99360D01*
X1182249D01*
G01X1174768Y68168D02*
X1185968D01*
G01X1174768Y86168D02*
Y68168D01*
G01X1185968Y86168D02*
X1174768D01*
G01X1165020Y235887D02*
Y238387D01*
X1166061D01*
X1166395Y238262D01*
X1166603Y238095D01*
X1166686Y237762D01*
X1166603Y237429D01*
X1166353Y237220D01*
X1166061Y237095D01*
X1165020D01*
G01X1166061D02*
X1166686Y235887D01*
G01X1168036Y236387D02*
X1168286Y236095D01*
X1168620Y235929D01*
X1168995Y235887D01*
X1169328Y235929D01*
X1169661Y236137D01*
X1169870Y236387D01*
X1169911Y236637D01*
X1169828Y236929D01*
X1169536Y237137D01*
X1169245Y237220D01*
X1168870D01*
G01X1169245D02*
X1169495Y237345D01*
X1169703Y237554D01*
X1169786Y237804D01*
X1169703Y238054D01*
X1169495Y238262D01*
X1169120Y238387D01*
X1168745Y238345D01*
X1168370Y238179D01*
G01X1171261Y236929D02*
X1171553Y237220D01*
X1171803Y237387D01*
X1172136Y237470D01*
X1172428Y237387D01*
X1172636Y237220D01*
X1172803Y236970D01*
X1172845Y236679D01*
X1172803Y236429D01*
X1172636Y236179D01*
X1172386Y235970D01*
X1172095Y235887D01*
X1171761Y235970D01*
X1171470Y236220D01*
X1171303Y236595D01*
X1171261Y237012D01*
X1171345Y237554D01*
X1171470Y237845D01*
X1171678Y238137D01*
X1171970Y238345D01*
X1172261Y238387D01*
X1172553Y238304D01*
X1172761Y238095D01*
G01X1174236Y236262D02*
X1174486Y236054D01*
X1174778Y235929D01*
X1175153Y235887D01*
X1175528Y235970D01*
X1175820Y236137D01*
X1176028Y236429D01*
X1176070Y236762D01*
X1175986Y237095D01*
X1175778Y237304D01*
X1175486Y237470D01*
X1175195Y237512D01*
X1174903Y237470D01*
X1174528Y237304D01*
X1174653Y238387D01*
X1175778D01*
G01X1177600Y251800D02*
Y247800D01*
X1185000D01*
G01X1156600Y253717D02*
X1154100D01*
Y254758D01*
X1154225Y255092D01*
X1154392Y255300D01*
X1154725Y255383D01*
X1155058Y255300D01*
X1155267Y255050D01*
X1155392Y254758D01*
Y253717D01*
G01Y254758D02*
X1156600Y255383D01*
G01X1155558Y256858D02*
X1155267Y257150D01*
X1155100Y257400D01*
X1155017Y257733D01*
X1155100Y258025D01*
X1155267Y258233D01*
X1155517Y258400D01*
X1155808Y258442D01*
X1156058Y258400D01*
X1156308Y258233D01*
X1156517Y257983D01*
X1156600Y257692D01*
X1156517Y257358D01*
X1156267Y257067D01*
X1155892Y256900D01*
X1155475Y256858D01*
X1154933Y256942D01*
X1154642Y257067D01*
X1154350Y257275D01*
X1154142Y257567D01*
X1154100Y257858D01*
X1154183Y258150D01*
X1154392Y258358D01*
G01X1156100Y259833D02*
X1156392Y260083D01*
X1156558Y260417D01*
X1156600Y260792D01*
X1156558Y261125D01*
X1156350Y261458D01*
X1156100Y261667D01*
X1155850Y261708D01*
X1155558Y261625D01*
X1155350Y261333D01*
X1155267Y261042D01*
Y260667D01*
G01Y261042D02*
X1155142Y261292D01*
X1154933Y261500D01*
X1154683Y261583D01*
X1154433Y261500D01*
X1154225Y261292D01*
X1154100Y260917D01*
X1154142Y260542D01*
X1154308Y260167D01*
G01X1156600Y263850D02*
X1154100D01*
X1154600Y263350D01*
G01X1156600D02*
Y264350D01*
G01X1174100Y260800D02*
X1178100D01*
Y268200D01*
G01X1179469Y236292D02*
Y238792D01*
X1180510D01*
X1180844Y238667D01*
X1181052Y238500D01*
X1181135Y238167D01*
X1181052Y237834D01*
X1180802Y237625D01*
X1180510Y237500D01*
X1179469D01*
G01X1180510D02*
X1181135Y236292D01*
G01X1182610Y237334D02*
X1182902Y237625D01*
X1183152Y237792D01*
X1183485Y237875D01*
X1183777Y237792D01*
X1183985Y237625D01*
X1184152Y237375D01*
X1184194Y237084D01*
X1184152Y236834D01*
X1183985Y236584D01*
X1183735Y236375D01*
X1183444Y236292D01*
X1183110Y236375D01*
X1182819Y236625D01*
X1182652Y237000D01*
X1182610Y237417D01*
X1182694Y237959D01*
X1182819Y238250D01*
X1183027Y238542D01*
X1183319Y238750D01*
X1183610Y238792D01*
X1183902Y238709D01*
X1184110Y238500D01*
G01X1187002Y236292D02*
Y238792D01*
X1185460Y237000D01*
X1187544D01*
G01X1188810Y238375D02*
X1189060Y238625D01*
X1189352Y238750D01*
X1189685Y238792D01*
X1190102Y238709D01*
X1190394Y238500D01*
X1190477Y238250D01*
X1190435Y238000D01*
X1190269Y237792D01*
X1189435Y237375D01*
X1189060Y237084D01*
X1188810Y236667D01*
X1188727Y236292D01*
X1190477D01*
G01X1178289Y243290D02*
X1178039Y243415D01*
X1177747Y243498D01*
X1177414D01*
X1177039Y243373D01*
X1176747Y243165D01*
X1176539Y242915D01*
X1176372Y242498D01*
X1176330Y242123D01*
X1176414Y241748D01*
X1176539Y241498D01*
X1176789Y241248D01*
X1177080Y241081D01*
X1177372Y240998D01*
X1177664D01*
X1177955Y241081D01*
X1178205Y241206D01*
X1178414Y241373D01*
G01X1179680Y242040D02*
X1179972Y242331D01*
X1180222Y242498D01*
X1180555Y242581D01*
X1180847Y242498D01*
X1181055Y242331D01*
X1181222Y242081D01*
X1181264Y241790D01*
X1181222Y241540D01*
X1181055Y241290D01*
X1180805Y241081D01*
X1180514Y240998D01*
X1180180Y241081D01*
X1179889Y241331D01*
X1179722Y241706D01*
X1179680Y242123D01*
X1179764Y242665D01*
X1179889Y242956D01*
X1180097Y243248D01*
X1180389Y243456D01*
X1180680Y243498D01*
X1180972Y243415D01*
X1181180Y243206D01*
G01X1160669Y286058D02*
Y288558D01*
X1161710D01*
X1162044Y288433D01*
X1162252Y288266D01*
X1162335Y287933D01*
X1162252Y287600D01*
X1162002Y287391D01*
X1161710Y287266D01*
X1160669D01*
G01X1161710D02*
X1162335Y286058D01*
G01X1163685Y286558D02*
X1163935Y286266D01*
X1164269Y286100D01*
X1164644Y286058D01*
X1164977Y286100D01*
X1165310Y286308D01*
X1165519Y286558D01*
X1165560Y286808D01*
X1165477Y287100D01*
X1165185Y287308D01*
X1164894Y287391D01*
X1164519D01*
G01X1164894D02*
X1165144Y287516D01*
X1165352Y287725D01*
X1165435Y287975D01*
X1165352Y288225D01*
X1165144Y288433D01*
X1164769Y288558D01*
X1164394Y288516D01*
X1164019Y288350D01*
G01X1168202Y286058D02*
Y288558D01*
X1166660Y286766D01*
X1168744D01*
G01X1170719Y286058D02*
X1170802Y286600D01*
X1170927Y287058D01*
X1171094Y287475D01*
X1171302Y287933D01*
X1171635Y288558D01*
X1169969D01*
G01X1154053Y291054D02*
X1151553D01*
Y292095D01*
X1151678Y292429D01*
X1151845Y292637D01*
X1152178Y292720D01*
X1152511Y292637D01*
X1152720Y292387D01*
X1152845Y292095D01*
Y291054D01*
G01Y292095D02*
X1154053Y292720D01*
G01X1153553Y294070D02*
X1153845Y294320D01*
X1154011Y294654D01*
X1154053Y295029D01*
X1154011Y295362D01*
X1153803Y295695D01*
X1153553Y295904D01*
X1153303Y295945D01*
X1153011Y295862D01*
X1152803Y295570D01*
X1152720Y295279D01*
Y294904D01*
G01Y295279D02*
X1152595Y295529D01*
X1152386Y295737D01*
X1152136Y295820D01*
X1151886Y295737D01*
X1151678Y295529D01*
X1151553Y295154D01*
X1151595Y294779D01*
X1151761Y294404D01*
G01X1154053Y298004D02*
X1153511Y298087D01*
X1153053Y298212D01*
X1152636Y298379D01*
X1152178Y298587D01*
X1151553Y298920D01*
Y297254D01*
G01Y301187D02*
X1151636Y300854D01*
X1151845Y300604D01*
X1152095Y300437D01*
X1152428Y300312D01*
X1152803Y300270D01*
X1153178Y300312D01*
X1153511Y300437D01*
X1153761Y300604D01*
X1153970Y300854D01*
X1154053Y301187D01*
X1153970Y301520D01*
X1153761Y301770D01*
X1153511Y301937D01*
X1153178Y302062D01*
X1152803Y302104D01*
X1152428Y302062D01*
X1152095Y301937D01*
X1151845Y301770D01*
X1151636Y301520D01*
X1151553Y301187D01*
G01X1178300Y298100D02*
X1174300D01*
Y290700D01*
G01X1168853Y291054D02*
X1166353D01*
Y292095D01*
X1166478Y292429D01*
X1166645Y292637D01*
X1166978Y292720D01*
X1167311Y292637D01*
X1167520Y292387D01*
X1167645Y292095D01*
Y291054D01*
G01Y292095D02*
X1168853Y292720D01*
G01X1168561Y294279D02*
X1168770Y294570D01*
X1168853Y294904D01*
X1168770Y295237D01*
X1168520Y295529D01*
X1168145Y295737D01*
X1167770Y295820D01*
X1167311D01*
X1166936Y295737D01*
X1166603Y295529D01*
X1166436Y295279D01*
X1166353Y294987D01*
X1166436Y294654D01*
X1166603Y294404D01*
X1166853Y294237D01*
X1167186Y294154D01*
X1167478Y294237D01*
X1167770Y294445D01*
X1167936Y294695D01*
X1167978Y294987D01*
X1167895Y295320D01*
X1167686Y295570D01*
X1167311Y295820D01*
G01X1168853Y298087D02*
X1168811Y298379D01*
X1168686Y298712D01*
X1168478Y298920D01*
X1168186Y299004D01*
X1167895Y298920D01*
X1167645Y298670D01*
X1167520Y298295D01*
Y297879D01*
X1167436Y297629D01*
X1167228Y297420D01*
X1166936Y297337D01*
X1166645Y297462D01*
X1166436Y297754D01*
X1166353Y298087D01*
X1166436Y298420D01*
X1166645Y298712D01*
X1166936Y298837D01*
X1167228Y298754D01*
X1167436Y298545D01*
X1167520Y298295D01*
Y297879D01*
X1167645Y297504D01*
X1167895Y297254D01*
X1168186Y297170D01*
X1168478Y297254D01*
X1168686Y297462D01*
X1168811Y297795D01*
X1168853Y298087D01*
G01Y301104D02*
X1168311Y301187D01*
X1167853Y301312D01*
X1167436Y301479D01*
X1166978Y301687D01*
X1166353Y302020D01*
Y300354D01*
G01X1161453Y291054D02*
X1158953D01*
Y292095D01*
X1159078Y292429D01*
X1159245Y292637D01*
X1159578Y292720D01*
X1159911Y292637D01*
X1160120Y292387D01*
X1160245Y292095D01*
Y291054D01*
G01Y292095D02*
X1161453Y292720D01*
G01X1160953Y294070D02*
X1161245Y294320D01*
X1161411Y294654D01*
X1161453Y295029D01*
X1161411Y295362D01*
X1161203Y295695D01*
X1160953Y295904D01*
X1160703Y295945D01*
X1160411Y295862D01*
X1160203Y295570D01*
X1160120Y295279D01*
Y294904D01*
G01Y295279D02*
X1159995Y295529D01*
X1159786Y295737D01*
X1159536Y295820D01*
X1159286Y295737D01*
X1159078Y295529D01*
X1158953Y295154D01*
X1158995Y294779D01*
X1159161Y294404D01*
G01X1161078Y297170D02*
X1161286Y297420D01*
X1161411Y297712D01*
X1161453Y298087D01*
X1161370Y298462D01*
X1161203Y298754D01*
X1160911Y298962D01*
X1160578Y299004D01*
X1160245Y298920D01*
X1160036Y298712D01*
X1159870Y298420D01*
X1159828Y298129D01*
X1159870Y297837D01*
X1160036Y297462D01*
X1158953Y297587D01*
Y298712D01*
G01X1161453Y301187D02*
X1161411Y301479D01*
X1161286Y301812D01*
X1161078Y302020D01*
X1160786Y302104D01*
X1160495Y302020D01*
X1160245Y301770D01*
X1160120Y301395D01*
Y300979D01*
X1160036Y300729D01*
X1159828Y300520D01*
X1159536Y300437D01*
X1159245Y300562D01*
X1159036Y300854D01*
X1158953Y301187D01*
X1159036Y301520D01*
X1159245Y301812D01*
X1159536Y301937D01*
X1159828Y301854D01*
X1160036Y301645D01*
X1160120Y301395D01*
Y300979D01*
X1160245Y300604D01*
X1160495Y300354D01*
X1160786Y300270D01*
X1161078Y300354D01*
X1161286Y300562D01*
X1161411Y300895D01*
X1161453Y301187D01*
G01X1187588Y298150D02*
X1183588D01*
Y290750D01*
G01X1165153Y291054D02*
X1162653D01*
Y292095D01*
X1162778Y292429D01*
X1162945Y292637D01*
X1163278Y292720D01*
X1163611Y292637D01*
X1163820Y292387D01*
X1163945Y292095D01*
Y291054D01*
G01Y292095D02*
X1165153Y292720D01*
G01X1164653Y294070D02*
X1164945Y294320D01*
X1165111Y294654D01*
X1165153Y295029D01*
X1165111Y295362D01*
X1164903Y295695D01*
X1164653Y295904D01*
X1164403Y295945D01*
X1164111Y295862D01*
X1163903Y295570D01*
X1163820Y295279D01*
Y294904D01*
G01Y295279D02*
X1163695Y295529D01*
X1163486Y295737D01*
X1163236Y295820D01*
X1162986Y295737D01*
X1162778Y295529D01*
X1162653Y295154D01*
X1162695Y294779D01*
X1162861Y294404D01*
G01X1164778Y297170D02*
X1164986Y297420D01*
X1165111Y297712D01*
X1165153Y298087D01*
X1165070Y298462D01*
X1164903Y298754D01*
X1164611Y298962D01*
X1164278Y299004D01*
X1163945Y298920D01*
X1163736Y298712D01*
X1163570Y298420D01*
X1163528Y298129D01*
X1163570Y297837D01*
X1163736Y297462D01*
X1162653Y297587D01*
Y298712D01*
G01X1165153Y301104D02*
X1164611Y301187D01*
X1164153Y301312D01*
X1163736Y301479D01*
X1163278Y301687D01*
X1162653Y302020D01*
Y300354D01*
G01X1157753Y291054D02*
X1155253D01*
Y292095D01*
X1155378Y292429D01*
X1155545Y292637D01*
X1155878Y292720D01*
X1156211Y292637D01*
X1156420Y292387D01*
X1156545Y292095D01*
Y291054D01*
G01Y292095D02*
X1157753Y292720D01*
G01X1155670Y294195D02*
X1155420Y294445D01*
X1155295Y294737D01*
X1155253Y295070D01*
X1155336Y295487D01*
X1155545Y295779D01*
X1155795Y295862D01*
X1156045Y295820D01*
X1156253Y295654D01*
X1156670Y294820D01*
X1156961Y294445D01*
X1157378Y294195D01*
X1157753Y294112D01*
Y295862D01*
G01X1155253Y298087D02*
X1155336Y297754D01*
X1155545Y297504D01*
X1155795Y297337D01*
X1156128Y297212D01*
X1156503Y297170D01*
X1156878Y297212D01*
X1157211Y297337D01*
X1157461Y297504D01*
X1157670Y297754D01*
X1157753Y298087D01*
X1157670Y298420D01*
X1157461Y298670D01*
X1157211Y298837D01*
X1156878Y298962D01*
X1156503Y299004D01*
X1156128Y298962D01*
X1155795Y298837D01*
X1155545Y298670D01*
X1155336Y298420D01*
X1155253Y298087D01*
G01X1157753Y301687D02*
X1155253D01*
X1157045Y300145D01*
Y302229D01*
G01X1182953Y298185D02*
X1178953D01*
Y290785D01*
G01X1156600Y268117D02*
X1154100D01*
Y269158D01*
X1154225Y269492D01*
X1154392Y269700D01*
X1154725Y269783D01*
X1155058Y269700D01*
X1155267Y269450D01*
X1155392Y269158D01*
Y268117D01*
G01Y269158D02*
X1156600Y269783D01*
G01X1155558Y271258D02*
X1155267Y271550D01*
X1155100Y271800D01*
X1155017Y272133D01*
X1155100Y272425D01*
X1155267Y272633D01*
X1155517Y272800D01*
X1155808Y272842D01*
X1156058Y272800D01*
X1156308Y272633D01*
X1156517Y272383D01*
X1156600Y272092D01*
X1156517Y271758D01*
X1156267Y271467D01*
X1155892Y271300D01*
X1155475Y271258D01*
X1154933Y271342D01*
X1154642Y271467D01*
X1154350Y271675D01*
X1154142Y271967D01*
X1154100Y272258D01*
X1154183Y272550D01*
X1154392Y272758D01*
G01X1154517Y274358D02*
X1154267Y274608D01*
X1154142Y274900D01*
X1154100Y275233D01*
X1154183Y275650D01*
X1154392Y275942D01*
X1154642Y276025D01*
X1154892Y275983D01*
X1155100Y275817D01*
X1155517Y274983D01*
X1155808Y274608D01*
X1156225Y274358D01*
X1156600Y274275D01*
Y276025D01*
G01X1155558Y277458D02*
X1155267Y277750D01*
X1155100Y278000D01*
X1155017Y278333D01*
X1155100Y278625D01*
X1155267Y278833D01*
X1155517Y279000D01*
X1155808Y279042D01*
X1156058Y279000D01*
X1156308Y278833D01*
X1156517Y278583D01*
X1156600Y278292D01*
X1156517Y277958D01*
X1156267Y277667D01*
X1155892Y277500D01*
X1155475Y277458D01*
X1154933Y277542D01*
X1154642Y277667D01*
X1154350Y277875D01*
X1154142Y278167D01*
X1154100Y278458D01*
X1154183Y278750D01*
X1154392Y278958D01*
G01X1178100Y279600D02*
X1174100D01*
Y272200D01*
G01X1172553Y291054D02*
X1170053D01*
Y292095D01*
X1170178Y292429D01*
X1170345Y292637D01*
X1170678Y292720D01*
X1171011Y292637D01*
X1171220Y292387D01*
X1171345Y292095D01*
Y291054D01*
G01Y292095D02*
X1172553Y292720D01*
G01Y295487D02*
X1170053D01*
X1171845Y293945D01*
Y296029D01*
G01X1172553Y298587D02*
X1170053D01*
X1171845Y297045D01*
Y299129D01*
G01X1172261Y300479D02*
X1172470Y300770D01*
X1172553Y301104D01*
X1172470Y301437D01*
X1172220Y301729D01*
X1171845Y301937D01*
X1171470Y302020D01*
X1171011D01*
X1170636Y301937D01*
X1170303Y301729D01*
X1170136Y301479D01*
X1170053Y301187D01*
X1170136Y300854D01*
X1170303Y300604D01*
X1170553Y300437D01*
X1170886Y300354D01*
X1171178Y300437D01*
X1171470Y300645D01*
X1171636Y300895D01*
X1171678Y301187D01*
X1171595Y301520D01*
X1171386Y301770D01*
X1171011Y302020D01*
G01X1170576Y264469D02*
X1168076D01*
Y265510D01*
X1168201Y265844D01*
X1168368Y266052D01*
X1168701Y266135D01*
X1169034Y266052D01*
X1169243Y265802D01*
X1169368Y265510D01*
Y264469D01*
G01Y265510D02*
X1170576Y266135D01*
G01X1169534Y267610D02*
X1169243Y267902D01*
X1169076Y268152D01*
X1168993Y268485D01*
X1169076Y268777D01*
X1169243Y268985D01*
X1169493Y269152D01*
X1169784Y269194D01*
X1170034Y269152D01*
X1170284Y268985D01*
X1170493Y268735D01*
X1170576Y268444D01*
X1170493Y268110D01*
X1170243Y267819D01*
X1169868Y267652D01*
X1169451Y267610D01*
X1168909Y267694D01*
X1168618Y267819D01*
X1168326Y268027D01*
X1168118Y268319D01*
X1168076Y268610D01*
X1168159Y268902D01*
X1168368Y269110D01*
G01X1170576Y272002D02*
X1168076D01*
X1169868Y270460D01*
Y272544D01*
G01X1170576Y274602D02*
X1168076D01*
X1168576Y274102D01*
G01X1170576D02*
Y275102D01*
G01X1155317Y284292D02*
X1155067Y284417D01*
X1154775Y284500D01*
X1154442D01*
X1154067Y284375D01*
X1153775Y284167D01*
X1153567Y283917D01*
X1153400Y283500D01*
X1153358Y283125D01*
X1153442Y282750D01*
X1153567Y282500D01*
X1153817Y282250D01*
X1154108Y282083D01*
X1154400Y282000D01*
X1154692D01*
X1154983Y282083D01*
X1155233Y282208D01*
X1155442Y282375D01*
G01X1156708Y284083D02*
X1156958Y284333D01*
X1157250Y284458D01*
X1157583Y284500D01*
X1158000Y284417D01*
X1158292Y284208D01*
X1158375Y283958D01*
X1158333Y283708D01*
X1158167Y283500D01*
X1157333Y283083D01*
X1156958Y282792D01*
X1156708Y282375D01*
X1156625Y282000D01*
X1158375D01*
G01X1160600D02*
X1160892Y282042D01*
X1161225Y282167D01*
X1161433Y282375D01*
X1161517Y282667D01*
X1161433Y282958D01*
X1161183Y283208D01*
X1160808Y283333D01*
X1160392D01*
X1160142Y283417D01*
X1159933Y283625D01*
X1159850Y283917D01*
X1159975Y284208D01*
X1160267Y284417D01*
X1160600Y284500D01*
X1160933Y284417D01*
X1161225Y284208D01*
X1161350Y283917D01*
X1161267Y283625D01*
X1161058Y283417D01*
X1160808Y283333D01*
X1160392D01*
X1160017Y283208D01*
X1159767Y282958D01*
X1159683Y282667D01*
X1159767Y282375D01*
X1159975Y282167D01*
X1160308Y282042D01*
X1160600Y282000D01*
G01X1159202Y262505D02*
X1160994D01*
X1161369Y262672D01*
X1161619Y263005D01*
X1161702Y263422D01*
X1161619Y263839D01*
X1161369Y264172D01*
X1160994Y264339D01*
X1159202D01*
G01X1161327Y265605D02*
X1161535Y265855D01*
X1161660Y266147D01*
X1161702Y266522D01*
X1161619Y266897D01*
X1161452Y267189D01*
X1161160Y267397D01*
X1160827Y267439D01*
X1160494Y267355D01*
X1160285Y267147D01*
X1160119Y266855D01*
X1160077Y266564D01*
X1160119Y266272D01*
X1160285Y265897D01*
X1159202Y266022D01*
Y267147D01*
G01Y269622D02*
X1159285Y269289D01*
X1159494Y269039D01*
X1159744Y268872D01*
X1160077Y268747D01*
X1160452Y268705D01*
X1160827Y268747D01*
X1161160Y268872D01*
X1161410Y269039D01*
X1161619Y269289D01*
X1161702Y269622D01*
X1161619Y269955D01*
X1161410Y270205D01*
X1161160Y270372D01*
X1160827Y270497D01*
X1160452Y270539D01*
X1160077Y270497D01*
X1159744Y270372D01*
X1159494Y270205D01*
X1159285Y269955D01*
X1159202Y269622D01*
G01X1179150Y270900D02*
X1179300D01*
X1180550Y269650D01*
X1179350Y268450D01*
X1179100D01*
G01X1179150Y260900D02*
Y278100D01*
X1189050D01*
Y260900D01*
X1179150D01*
G01X1183144Y606783D02*
X1180644D01*
Y607824D01*
X1180769Y608158D01*
X1180936Y608366D01*
X1181269Y608449D01*
X1181602Y608366D01*
X1181811Y608116D01*
X1181936Y607824D01*
Y606783D01*
G01Y607824D02*
X1183144Y608449D01*
G01X1182852Y610008D02*
X1183061Y610299D01*
X1183144Y610633D01*
X1183061Y610966D01*
X1182811Y611258D01*
X1182436Y611466D01*
X1182061Y611549D01*
X1181602D01*
X1181227Y611466D01*
X1180894Y611258D01*
X1180727Y611008D01*
X1180644Y610716D01*
X1180727Y610383D01*
X1180894Y610133D01*
X1181144Y609966D01*
X1181477Y609883D01*
X1181769Y609966D01*
X1182061Y610174D01*
X1182227Y610424D01*
X1182269Y610716D01*
X1182186Y611049D01*
X1181977Y611299D01*
X1181602Y611549D01*
G01X1182852Y613108D02*
X1183061Y613399D01*
X1183144Y613733D01*
X1183061Y614066D01*
X1182811Y614358D01*
X1182436Y614566D01*
X1182061Y614649D01*
X1181602D01*
X1181227Y614566D01*
X1180894Y614358D01*
X1180727Y614108D01*
X1180644Y613816D01*
X1180727Y613483D01*
X1180894Y613233D01*
X1181144Y613066D01*
X1181477Y612983D01*
X1181769Y613066D01*
X1182061Y613274D01*
X1182227Y613524D01*
X1182269Y613816D01*
X1182186Y614149D01*
X1181977Y614399D01*
X1181602Y614649D01*
G01X1183144Y617416D02*
X1180644D01*
X1182436Y615874D01*
Y617958D01*
G01X1174835Y609232D02*
X1178835D01*
Y616632D01*
G01X1193168Y721600D02*
X1174468D01*
Y731900D01*
X1193168D01*
Y721600D01*
G01X1143515Y1033798D02*
Y1037998D01*
G01X1139200Y1065617D02*
X1136700D01*
Y1066658D01*
X1136825Y1066992D01*
X1136992Y1067200D01*
X1137325Y1067283D01*
X1137658Y1067200D01*
X1137867Y1066950D01*
X1137992Y1066658D01*
Y1065617D01*
G01Y1066658D02*
X1139200Y1067283D01*
G01Y1069550D02*
X1136700D01*
X1137200Y1069050D01*
G01X1139200D02*
Y1070050D01*
G01X1137117Y1071858D02*
X1136867Y1072108D01*
X1136742Y1072400D01*
X1136700Y1072733D01*
X1136783Y1073150D01*
X1136992Y1073442D01*
X1137242Y1073525D01*
X1137492Y1073483D01*
X1137700Y1073317D01*
X1138117Y1072483D01*
X1138408Y1072108D01*
X1138825Y1071858D01*
X1139200Y1071775D01*
Y1073525D01*
G01X1136700Y1075750D02*
X1136783Y1075417D01*
X1136992Y1075167D01*
X1137242Y1075000D01*
X1137575Y1074875D01*
X1137950Y1074833D01*
X1138325Y1074875D01*
X1138658Y1075000D01*
X1138908Y1075167D01*
X1139117Y1075417D01*
X1139200Y1075750D01*
X1139117Y1076083D01*
X1138908Y1076333D01*
X1138658Y1076500D01*
X1138325Y1076625D01*
X1137950Y1076667D01*
X1137575Y1076625D01*
X1137242Y1076500D01*
X1136992Y1076333D01*
X1136783Y1076083D01*
X1136700Y1075750D01*
G01X1152900Y1065617D02*
X1150400D01*
Y1066658D01*
X1150525Y1066992D01*
X1150692Y1067200D01*
X1151025Y1067283D01*
X1151358Y1067200D01*
X1151567Y1066950D01*
X1151692Y1066658D01*
Y1065617D01*
G01Y1066658D02*
X1152900Y1067283D01*
G01Y1069550D02*
X1150400D01*
X1150900Y1069050D01*
G01X1152900D02*
Y1070050D01*
G01X1150817Y1071858D02*
X1150567Y1072108D01*
X1150442Y1072400D01*
X1150400Y1072733D01*
X1150483Y1073150D01*
X1150692Y1073442D01*
X1150942Y1073525D01*
X1151192Y1073483D01*
X1151400Y1073317D01*
X1151817Y1072483D01*
X1152108Y1072108D01*
X1152525Y1071858D01*
X1152900Y1071775D01*
Y1073525D01*
G01Y1075750D02*
X1150400D01*
X1150900Y1075250D01*
G01X1152900D02*
Y1076250D01*
G01X1143700Y1065617D02*
X1141200D01*
Y1066658D01*
X1141325Y1066992D01*
X1141492Y1067200D01*
X1141825Y1067283D01*
X1142158Y1067200D01*
X1142367Y1066950D01*
X1142492Y1066658D01*
Y1065617D01*
G01Y1066658D02*
X1143700Y1067283D01*
G01Y1069550D02*
X1141200D01*
X1141700Y1069050D01*
G01X1143700D02*
Y1070050D01*
G01X1141617Y1071858D02*
X1141367Y1072108D01*
X1141242Y1072400D01*
X1141200Y1072733D01*
X1141283Y1073150D01*
X1141492Y1073442D01*
X1141742Y1073525D01*
X1141992Y1073483D01*
X1142200Y1073317D01*
X1142617Y1072483D01*
X1142908Y1072108D01*
X1143325Y1071858D01*
X1143700Y1071775D01*
Y1073525D01*
G01X1142658Y1074958D02*
X1142367Y1075250D01*
X1142200Y1075500D01*
X1142117Y1075833D01*
X1142200Y1076125D01*
X1142367Y1076333D01*
X1142617Y1076500D01*
X1142908Y1076542D01*
X1143158Y1076500D01*
X1143408Y1076333D01*
X1143617Y1076083D01*
X1143700Y1075792D01*
X1143617Y1075458D01*
X1143367Y1075167D01*
X1142992Y1075000D01*
X1142575Y1074958D01*
X1142033Y1075042D01*
X1141742Y1075167D01*
X1141450Y1075375D01*
X1141242Y1075667D01*
X1141200Y1075958D01*
X1141283Y1076250D01*
X1141492Y1076458D01*
G01X1148500Y1065617D02*
X1146000D01*
Y1066658D01*
X1146125Y1066992D01*
X1146292Y1067200D01*
X1146625Y1067283D01*
X1146958Y1067200D01*
X1147167Y1066950D01*
X1147292Y1066658D01*
Y1065617D01*
G01Y1066658D02*
X1148500Y1067283D01*
G01Y1069550D02*
X1146000D01*
X1146500Y1069050D01*
G01X1148500D02*
Y1070050D01*
G01X1146417Y1071858D02*
X1146167Y1072108D01*
X1146042Y1072400D01*
X1146000Y1072733D01*
X1146083Y1073150D01*
X1146292Y1073442D01*
X1146542Y1073525D01*
X1146792Y1073483D01*
X1147000Y1073317D01*
X1147417Y1072483D01*
X1147708Y1072108D01*
X1148125Y1071858D01*
X1148500Y1071775D01*
Y1073525D01*
G01Y1075667D02*
X1147958Y1075750D01*
X1147500Y1075875D01*
X1147083Y1076042D01*
X1146625Y1076250D01*
X1146000Y1076583D01*
Y1074917D01*
G01X1186254Y1065213D02*
X1183754D01*
Y1066213D01*
X1183879Y1066546D01*
X1184171Y1066796D01*
X1184504Y1066879D01*
X1184837Y1066796D01*
X1185087Y1066588D01*
X1185212Y1066213D01*
Y1065213D01*
G01X1183962Y1070063D02*
X1183837Y1069813D01*
X1183754Y1069521D01*
Y1069188D01*
X1183879Y1068813D01*
X1184087Y1068521D01*
X1184337Y1068313D01*
X1184754Y1068146D01*
X1185129Y1068104D01*
X1185504Y1068188D01*
X1185754Y1068313D01*
X1186004Y1068563D01*
X1186171Y1068854D01*
X1186254Y1069146D01*
Y1069438D01*
X1186171Y1069729D01*
X1186046Y1069979D01*
X1185879Y1070188D01*
G01X1183754Y1071746D02*
Y1072746D01*
G01Y1072246D02*
X1186254D01*
G01Y1071746D02*
Y1072746D01*
G01Y1076179D02*
Y1074513D01*
X1183754D01*
Y1076179D01*
G01X1184962Y1075513D02*
Y1074513D01*
G01X1186254Y1078446D02*
X1183754D01*
X1184254Y1077946D01*
G01X1186254D02*
Y1078946D01*
G01X1186887Y1114582D02*
X1184387D01*
Y1115623D01*
X1184512Y1115957D01*
X1184679Y1116165D01*
X1185012Y1116248D01*
X1185345Y1116165D01*
X1185554Y1115915D01*
X1185679Y1115623D01*
Y1114582D01*
G01Y1115623D02*
X1186887Y1116248D01*
G01Y1118515D02*
X1184387D01*
X1184887Y1118015D01*
G01X1186887D02*
Y1119015D01*
G01X1184387Y1121615D02*
X1184470Y1121282D01*
X1184679Y1121032D01*
X1184929Y1120865D01*
X1185262Y1120740D01*
X1185637Y1120698D01*
X1186012Y1120740D01*
X1186345Y1120865D01*
X1186595Y1121032D01*
X1186804Y1121282D01*
X1186887Y1121615D01*
X1186804Y1121948D01*
X1186595Y1122198D01*
X1186345Y1122365D01*
X1186012Y1122490D01*
X1185637Y1122532D01*
X1185262Y1122490D01*
X1184929Y1122365D01*
X1184679Y1122198D01*
X1184470Y1121948D01*
X1184387Y1121615D01*
G01X1178500Y1122200D02*
X1174500D01*
Y1114800D01*
G01X1149500Y1101483D02*
X1151292D01*
X1151667Y1101650D01*
X1151917Y1101983D01*
X1152000Y1102400D01*
X1151917Y1102817D01*
X1151667Y1103150D01*
X1151292Y1103317D01*
X1149500D01*
G01X1152000Y1105500D02*
X1149500D01*
X1150000Y1105000D01*
G01X1152000D02*
Y1106000D01*
G01X1149917Y1107808D02*
X1149667Y1108058D01*
X1149542Y1108350D01*
X1149500Y1108683D01*
X1149583Y1109100D01*
X1149792Y1109392D01*
X1150042Y1109475D01*
X1150292Y1109433D01*
X1150500Y1109267D01*
X1150917Y1108433D01*
X1151208Y1108058D01*
X1151625Y1107808D01*
X1152000Y1107725D01*
Y1109475D01*
G01X1150834Y1173333D02*
X1149667Y1174500D01*
X1149000Y1175500D01*
X1148667Y1176833D01*
X1149000Y1178000D01*
X1149667Y1178833D01*
X1150667Y1179500D01*
X1151833Y1179667D01*
X1152833Y1179500D01*
X1153834Y1178833D01*
X1154667Y1177833D01*
X1155000Y1176667D01*
X1154667Y1175333D01*
X1153667Y1174167D01*
X1152167Y1173500D01*
X1150500Y1173333D01*
X1148334Y1173667D01*
X1147167Y1174167D01*
X1146000Y1175000D01*
X1145167Y1176167D01*
X1145000Y1177333D01*
X1145333Y1178500D01*
X1146167Y1179333D01*
G01X1150834Y1214333D02*
X1149667Y1215500D01*
X1149000Y1216500D01*
X1148667Y1217833D01*
X1149000Y1219000D01*
X1149667Y1219833D01*
X1150667Y1220500D01*
X1151833Y1220667D01*
X1152833Y1220500D01*
X1153834Y1219833D01*
X1154667Y1218833D01*
X1155000Y1217667D01*
X1154667Y1216333D01*
X1153667Y1215167D01*
X1152167Y1214500D01*
X1150500Y1214333D01*
X1148334Y1214667D01*
X1147167Y1215167D01*
X1146000Y1216000D01*
X1145167Y1217167D01*
X1145000Y1218333D01*
X1145333Y1219500D01*
X1146167Y1220333D01*
G01X1155000Y1271500D02*
X1154833Y1272667D01*
X1154333Y1274000D01*
X1153500Y1274833D01*
X1152333Y1275167D01*
X1151167Y1274833D01*
X1150167Y1273833D01*
X1149667Y1272333D01*
Y1270667D01*
X1149333Y1269667D01*
X1148500Y1268833D01*
X1147333Y1268500D01*
X1146167Y1269000D01*
X1145333Y1270166D01*
X1145000Y1271500D01*
X1145333Y1272833D01*
X1146167Y1274000D01*
X1147333Y1274500D01*
X1148500Y1274167D01*
X1149333Y1273333D01*
X1149667Y1272333D01*
Y1270667D01*
X1150167Y1269167D01*
X1151167Y1268167D01*
X1152333Y1267833D01*
X1153500Y1268167D01*
X1154333Y1269000D01*
X1154833Y1270333D01*
X1155000Y1271500D01*
G01X1137715Y1303621D02*
X1141715D01*
Y1302021D01*
X1141515Y1301488D01*
X1141048Y1301088D01*
X1140515Y1300955D01*
X1139982Y1301088D01*
X1139582Y1301421D01*
X1139382Y1302021D01*
Y1303621D01*
G01X1137715Y1298621D02*
X1140382D01*
G01X1139848D02*
X1140115Y1298288D01*
X1140315Y1297955D01*
X1140382Y1297488D01*
X1140315Y1297155D01*
X1140115Y1296755D01*
G01X1139515Y1294088D02*
Y1291955D01*
X1139982Y1292155D01*
X1140248Y1292488D01*
X1140382Y1292955D01*
X1140315Y1293421D01*
X1140115Y1293821D01*
X1139648Y1294088D01*
X1139248Y1294221D01*
X1138848D01*
X1138448Y1294088D01*
X1138048Y1293755D01*
X1137782Y1293355D01*
X1137715Y1292888D01*
X1137848Y1292421D01*
X1138248Y1291955D01*
G01X1138182Y1289488D02*
X1137915Y1289155D01*
X1137715Y1288688D01*
Y1288288D01*
X1137848Y1287888D01*
X1138048Y1287621D01*
X1138315Y1287488D01*
X1138715Y1287555D01*
X1138915Y1287821D01*
X1139315Y1289021D01*
X1139782Y1289288D01*
X1140115Y1289155D01*
X1140315Y1288888D01*
X1140382Y1288488D01*
X1140315Y1288088D01*
X1140115Y1287688D01*
G01X1138182Y1284888D02*
X1137915Y1284555D01*
X1137715Y1284088D01*
Y1283688D01*
X1137848Y1283288D01*
X1138048Y1283021D01*
X1138315Y1282888D01*
X1138715Y1282955D01*
X1138915Y1283221D01*
X1139315Y1284421D01*
X1139782Y1284688D01*
X1140115Y1284555D01*
X1140315Y1284288D01*
X1140382Y1283888D01*
X1140315Y1283488D01*
X1140115Y1283088D01*
G01X1137715Y1275955D02*
X1141715D01*
Y1273421D01*
G01X1139782Y1274355D02*
Y1275955D01*
G01X1140382Y1270088D02*
X1137715D01*
G01X1141448D02*
X1141515Y1270221D01*
X1141648D01*
X1141715Y1270088D01*
X1141648Y1269955D01*
X1141515D01*
X1141448Y1270088D01*
G01X1141715Y1265488D02*
X1137715D01*
G01X1140382Y1266421D02*
Y1264555D01*
G01X1155000Y1326000D02*
X1154833Y1327167D01*
X1154333Y1328500D01*
X1153500Y1329333D01*
X1152333Y1329667D01*
X1151167Y1329333D01*
X1150167Y1328333D01*
X1149667Y1326833D01*
Y1325167D01*
X1149333Y1324167D01*
X1148500Y1323333D01*
X1147333Y1323000D01*
X1146167Y1323500D01*
X1145333Y1324666D01*
X1145000Y1326000D01*
X1145333Y1327333D01*
X1146167Y1328500D01*
X1147333Y1329000D01*
X1148500Y1328667D01*
X1149333Y1327833D01*
X1149667Y1326833D01*
Y1325167D01*
X1150167Y1323667D01*
X1151167Y1322667D01*
X1152333Y1322333D01*
X1153500Y1322667D01*
X1154333Y1323500D01*
X1154833Y1324833D01*
X1155000Y1326000D01*
G01Y1384000D02*
X1154833Y1385167D01*
X1154333Y1386500D01*
X1153500Y1387333D01*
X1152333Y1387667D01*
X1151167Y1387333D01*
X1150167Y1386333D01*
X1149667Y1384833D01*
Y1383167D01*
X1149333Y1382167D01*
X1148500Y1381333D01*
X1147333Y1381000D01*
X1146167Y1381500D01*
X1145333Y1382666D01*
X1145000Y1384000D01*
X1145333Y1385333D01*
X1146167Y1386500D01*
X1147333Y1387000D01*
X1148500Y1386667D01*
X1149333Y1385833D01*
X1149667Y1384833D01*
Y1383167D01*
X1150167Y1381667D01*
X1151167Y1380667D01*
X1152333Y1380333D01*
X1153500Y1380667D01*
X1154333Y1381500D01*
X1154833Y1382833D01*
X1155000Y1384000D01*
G01X1212817Y49959D02*
X1212567Y50084D01*
X1212275Y50167D01*
X1211942D01*
X1211567Y50042D01*
X1211275Y49834D01*
X1211067Y49584D01*
X1210900Y49167D01*
X1210858Y48792D01*
X1210942Y48417D01*
X1211067Y48167D01*
X1211317Y47917D01*
X1211608Y47750D01*
X1211900Y47667D01*
X1212192D01*
X1212483Y47750D01*
X1212733Y47875D01*
X1212942Y48042D01*
G01X1215500Y47667D02*
Y50167D01*
X1213958Y48375D01*
X1216042D01*
G01X1218100Y47667D02*
Y50167D01*
X1217600Y49667D01*
G01Y47667D02*
X1218600D01*
G01X1210767Y58459D02*
X1210517Y58584D01*
X1210225Y58667D01*
X1209892D01*
X1209517Y58542D01*
X1209225Y58334D01*
X1209017Y58084D01*
X1208850Y57667D01*
X1208808Y57292D01*
X1208892Y56917D01*
X1209017Y56667D01*
X1209267Y56417D01*
X1209558Y56250D01*
X1209850Y56167D01*
X1210142D01*
X1210433Y56250D01*
X1210683Y56375D01*
X1210892Y56542D01*
G01X1212033D02*
X1212283Y56334D01*
X1212575Y56209D01*
X1212950Y56167D01*
X1213325Y56250D01*
X1213617Y56417D01*
X1213825Y56709D01*
X1213867Y57042D01*
X1213783Y57375D01*
X1213575Y57584D01*
X1213283Y57750D01*
X1212992Y57792D01*
X1212700Y57750D01*
X1212325Y57584D01*
X1212450Y58667D01*
X1213575D01*
G01X1215258Y58250D02*
X1215508Y58500D01*
X1215800Y58625D01*
X1216133Y58667D01*
X1216550Y58584D01*
X1216842Y58375D01*
X1216925Y58125D01*
X1216883Y57875D01*
X1216717Y57667D01*
X1215883Y57250D01*
X1215508Y56959D01*
X1215258Y56542D01*
X1215175Y56167D01*
X1216925D01*
G01X1218233Y56667D02*
X1218483Y56375D01*
X1218817Y56209D01*
X1219192Y56167D01*
X1219525Y56209D01*
X1219858Y56417D01*
X1220067Y56667D01*
X1220108Y56917D01*
X1220025Y57209D01*
X1219733Y57417D01*
X1219442Y57500D01*
X1219067D01*
G01X1219442D02*
X1219692Y57625D01*
X1219900Y57834D01*
X1219983Y58084D01*
X1219900Y58334D01*
X1219692Y58542D01*
X1219317Y58667D01*
X1218942Y58625D01*
X1218567Y58459D01*
G01X1187669Y95494D02*
Y97994D01*
X1188710D01*
X1189044Y97869D01*
X1189252Y97702D01*
X1189335Y97369D01*
X1189252Y97036D01*
X1189002Y96827D01*
X1188710Y96702D01*
X1187669D01*
G01X1188710D02*
X1189335Y95494D01*
G01X1191602D02*
Y97994D01*
X1191102Y97494D01*
G01Y95494D02*
X1192102D01*
G01X1194702D02*
Y97994D01*
X1194202Y97494D01*
G01Y95494D02*
X1195202D01*
G01X1197010Y97577D02*
X1197260Y97827D01*
X1197552Y97952D01*
X1197885Y97994D01*
X1198302Y97911D01*
X1198594Y97702D01*
X1198677Y97452D01*
X1198635Y97202D01*
X1198469Y96994D01*
X1197635Y96577D01*
X1197260Y96286D01*
X1197010Y95869D01*
X1196927Y95494D01*
X1198677D01*
G01X1200194Y95786D02*
X1200485Y95577D01*
X1200819Y95494D01*
X1201152Y95577D01*
X1201444Y95827D01*
X1201652Y96202D01*
X1201735Y96577D01*
Y97036D01*
X1201652Y97411D01*
X1201444Y97744D01*
X1201194Y97911D01*
X1200902Y97994D01*
X1200569Y97911D01*
X1200319Y97744D01*
X1200152Y97494D01*
X1200069Y97161D01*
X1200152Y96869D01*
X1200360Y96577D01*
X1200610Y96411D01*
X1200902Y96369D01*
X1201235Y96452D01*
X1201485Y96661D01*
X1201735Y97036D01*
G01X1187520Y100658D02*
Y103158D01*
X1188561D01*
X1188895Y103033D01*
X1189103Y102866D01*
X1189186Y102533D01*
X1189103Y102200D01*
X1188853Y101991D01*
X1188561Y101866D01*
X1187520D01*
G01X1188561D02*
X1189186Y100658D01*
G01X1191453D02*
Y103158D01*
X1190953Y102658D01*
G01Y100658D02*
X1191953D01*
G01X1194553D02*
Y103158D01*
X1194053Y102658D01*
G01Y100658D02*
X1195053D01*
G01X1196861Y102741D02*
X1197111Y102991D01*
X1197403Y103116D01*
X1197736Y103158D01*
X1198153Y103075D01*
X1198445Y102866D01*
X1198528Y102616D01*
X1198486Y102366D01*
X1198320Y102158D01*
X1197486Y101741D01*
X1197111Y101450D01*
X1196861Y101033D01*
X1196778Y100658D01*
X1198528D01*
G01X1200753D02*
X1201045Y100700D01*
X1201378Y100825D01*
X1201586Y101033D01*
X1201670Y101325D01*
X1201586Y101616D01*
X1201336Y101866D01*
X1200961Y101991D01*
X1200545D01*
X1200295Y102075D01*
X1200086Y102283D01*
X1200003Y102575D01*
X1200128Y102866D01*
X1200420Y103075D01*
X1200753Y103158D01*
X1201086Y103075D01*
X1201378Y102866D01*
X1201503Y102575D01*
X1201420Y102283D01*
X1201211Y102075D01*
X1200961Y101991D01*
X1200545D01*
X1200170Y101866D01*
X1199920Y101616D01*
X1199836Y101325D01*
X1199920Y101033D01*
X1200128Y100825D01*
X1200461Y100700D01*
X1200753Y100658D01*
G01X1216900Y79667D02*
Y77167D01*
G01X1215942Y79667D02*
X1217858D01*
G01X1220917Y79459D02*
X1220667Y79584D01*
X1220375Y79667D01*
X1220042D01*
X1219667Y79542D01*
X1219375Y79334D01*
X1219167Y79084D01*
X1219000Y78667D01*
X1218958Y78292D01*
X1219042Y77917D01*
X1219167Y77667D01*
X1219417Y77417D01*
X1219708Y77250D01*
X1220000Y77167D01*
X1220292D01*
X1220583Y77250D01*
X1220833Y77375D01*
X1221042Y77542D01*
G01X1223100Y77167D02*
Y79667D01*
X1222600Y79167D01*
G01Y77167D02*
X1223600D01*
G01X1213168Y68168D02*
X1201968D01*
G01X1213168Y86168D02*
Y68168D01*
G01X1201968Y86168D02*
X1213168D01*
G01X1195128Y230506D02*
X1192628D01*
Y231547D01*
X1192753Y231881D01*
X1192920Y232089D01*
X1193253Y232172D01*
X1193586Y232089D01*
X1193795Y231839D01*
X1193920Y231547D01*
Y230506D01*
G01Y231547D02*
X1195128Y232172D01*
G01X1194628Y233522D02*
X1194920Y233772D01*
X1195086Y234106D01*
X1195128Y234481D01*
X1195086Y234814D01*
X1194878Y235147D01*
X1194628Y235356D01*
X1194378Y235397D01*
X1194086Y235314D01*
X1193878Y235022D01*
X1193795Y234731D01*
Y234356D01*
G01Y234731D02*
X1193670Y234981D01*
X1193461Y235189D01*
X1193211Y235272D01*
X1192961Y235189D01*
X1192753Y234981D01*
X1192628Y234606D01*
X1192670Y234231D01*
X1192836Y233856D01*
G01X1194753Y236622D02*
X1194961Y236872D01*
X1195086Y237164D01*
X1195128Y237539D01*
X1195045Y237914D01*
X1194878Y238206D01*
X1194586Y238414D01*
X1194253Y238456D01*
X1193920Y238372D01*
X1193711Y238164D01*
X1193545Y237872D01*
X1193503Y237581D01*
X1193545Y237289D01*
X1193711Y236914D01*
X1192628Y237039D01*
Y238164D01*
G01X1194086Y239847D02*
X1193795Y240139D01*
X1193628Y240389D01*
X1193545Y240722D01*
X1193628Y241014D01*
X1193795Y241222D01*
X1194045Y241389D01*
X1194336Y241431D01*
X1194586Y241389D01*
X1194836Y241222D01*
X1195045Y240972D01*
X1195128Y240681D01*
X1195045Y240347D01*
X1194795Y240056D01*
X1194420Y239889D01*
X1194003Y239847D01*
X1193461Y239931D01*
X1193170Y240056D01*
X1192878Y240264D01*
X1192670Y240556D01*
X1192628Y240847D01*
X1192711Y241139D01*
X1192920Y241347D01*
G01X1219517Y246167D02*
Y248667D01*
X1220558D01*
X1220892Y248542D01*
X1221100Y248375D01*
X1221183Y248042D01*
X1221100Y247709D01*
X1220850Y247500D01*
X1220558Y247375D01*
X1219517D01*
G01X1220558D02*
X1221183Y246167D01*
G01X1222533Y246667D02*
X1222783Y246375D01*
X1223117Y246209D01*
X1223492Y246167D01*
X1223825Y246209D01*
X1224158Y246417D01*
X1224367Y246667D01*
X1224408Y246917D01*
X1224325Y247209D01*
X1224033Y247417D01*
X1223742Y247500D01*
X1223367D01*
G01X1223742D02*
X1223992Y247625D01*
X1224200Y247834D01*
X1224283Y248084D01*
X1224200Y248334D01*
X1223992Y248542D01*
X1223617Y248667D01*
X1223242Y248625D01*
X1222867Y248459D01*
G01X1225842Y246459D02*
X1226133Y246250D01*
X1226467Y246167D01*
X1226800Y246250D01*
X1227092Y246500D01*
X1227300Y246875D01*
X1227383Y247250D01*
Y247709D01*
X1227300Y248084D01*
X1227092Y248417D01*
X1226842Y248584D01*
X1226550Y248667D01*
X1226217Y248584D01*
X1225967Y248417D01*
X1225800Y248167D01*
X1225717Y247834D01*
X1225800Y247542D01*
X1226008Y247250D01*
X1226258Y247084D01*
X1226550Y247042D01*
X1226883Y247125D01*
X1227133Y247334D01*
X1227383Y247709D01*
G01X1228858Y247209D02*
X1229150Y247500D01*
X1229400Y247667D01*
X1229733Y247750D01*
X1230025Y247667D01*
X1230233Y247500D01*
X1230400Y247250D01*
X1230442Y246959D01*
X1230400Y246709D01*
X1230233Y246459D01*
X1229983Y246250D01*
X1229692Y246167D01*
X1229358Y246250D01*
X1229067Y246500D01*
X1228900Y246875D01*
X1228858Y247292D01*
X1228942Y247834D01*
X1229067Y248125D01*
X1229275Y248417D01*
X1229567Y248625D01*
X1229858Y248667D01*
X1230150Y248584D01*
X1230358Y248375D01*
G01X1226910Y234291D02*
Y238291D01*
X1219510D01*
G01X1221564Y251322D02*
X1219064D01*
Y252363D01*
X1219189Y252697D01*
X1219356Y252905D01*
X1219689Y252988D01*
X1220022Y252905D01*
X1220231Y252655D01*
X1220356Y252363D01*
Y251322D01*
G01Y252363D02*
X1221564Y252988D01*
G01X1221064Y254338D02*
X1221356Y254588D01*
X1221522Y254922D01*
X1221564Y255297D01*
X1221522Y255630D01*
X1221314Y255963D01*
X1221064Y256172D01*
X1220814Y256213D01*
X1220522Y256130D01*
X1220314Y255838D01*
X1220231Y255547D01*
Y255172D01*
G01Y255547D02*
X1220106Y255797D01*
X1219897Y256005D01*
X1219647Y256088D01*
X1219397Y256005D01*
X1219189Y255797D01*
X1219064Y255422D01*
X1219106Y255047D01*
X1219272Y254672D01*
G01X1220522Y257563D02*
X1220231Y257855D01*
X1220064Y258105D01*
X1219981Y258438D01*
X1220064Y258730D01*
X1220231Y258938D01*
X1220481Y259105D01*
X1220772Y259147D01*
X1221022Y259105D01*
X1221272Y258938D01*
X1221481Y258688D01*
X1221564Y258397D01*
X1221481Y258063D01*
X1221231Y257772D01*
X1220856Y257605D01*
X1220439Y257563D01*
X1219897Y257647D01*
X1219606Y257772D01*
X1219314Y257980D01*
X1219106Y258272D01*
X1219064Y258563D01*
X1219147Y258855D01*
X1219356Y259063D01*
G01X1219481Y260663D02*
X1219231Y260913D01*
X1219106Y261205D01*
X1219064Y261538D01*
X1219147Y261955D01*
X1219356Y262247D01*
X1219606Y262330D01*
X1219856Y262288D01*
X1220064Y262122D01*
X1220481Y261288D01*
X1220772Y260913D01*
X1221189Y260663D01*
X1221564Y260580D01*
Y262330D01*
G01X1217547Y258715D02*
X1213547D01*
Y251315D01*
G01X1185432Y251800D02*
Y247800D01*
X1192832D01*
G01X1230450Y238300D02*
X1243850D01*
G01X1230450Y228300D02*
Y238300D01*
G01X1243850Y228300D02*
X1230450D01*
G01X1190300Y263168D02*
X1194300D01*
Y270568D01*
G01X1200050Y282750D02*
Y286750D01*
X1192650D01*
G01X1192600Y290700D02*
X1196600D01*
Y298100D01*
G01X1192200D02*
X1188200D01*
Y290700D01*
G01X1201000Y297700D02*
X1197000D01*
Y290300D01*
G01X1195100Y270500D02*
X1199100D01*
Y277900D01*
G01X1233100Y275166D02*
Y272666D01*
G01X1232142Y275166D02*
X1234058D01*
G01X1235367Y272666D02*
Y275166D01*
X1236367D01*
X1236700Y275041D01*
X1236950Y274749D01*
X1237033Y274416D01*
X1236950Y274083D01*
X1236742Y273833D01*
X1236367Y273708D01*
X1235367D01*
G01X1239300Y272666D02*
Y275166D01*
X1238800Y274666D01*
G01Y272666D02*
X1239800D01*
G01X1241483Y273041D02*
X1241733Y272833D01*
X1242025Y272708D01*
X1242400Y272666D01*
X1242775Y272749D01*
X1243067Y272916D01*
X1243275Y273208D01*
X1243317Y273541D01*
X1243233Y273874D01*
X1243025Y274083D01*
X1242733Y274249D01*
X1242442Y274291D01*
X1242150Y274249D01*
X1241775Y274083D01*
X1241900Y275166D01*
X1243025D01*
G01X1244708Y274749D02*
X1244958Y274999D01*
X1245250Y275124D01*
X1245583Y275166D01*
X1246000Y275083D01*
X1246292Y274874D01*
X1246375Y274624D01*
X1246333Y274374D01*
X1246167Y274166D01*
X1245333Y273749D01*
X1244958Y273458D01*
X1244708Y273041D01*
X1244625Y272666D01*
X1246375D01*
G01X1232706Y382654D02*
Y385154D01*
X1234290D01*
G01X1233706Y383946D02*
X1232706D01*
G01X1235765Y385154D02*
Y382654D01*
X1237431D01*
G01X1240531D02*
X1238865D01*
Y385154D01*
X1240531D01*
G01X1239865Y383946D02*
X1238865D01*
G01X1241881Y382654D02*
Y385154D01*
X1242715D01*
X1243048Y385029D01*
X1243298Y384862D01*
X1243506Y384612D01*
X1243673Y384321D01*
X1243715Y383904D01*
X1243673Y383487D01*
X1243506Y383196D01*
X1243298Y382946D01*
X1243048Y382779D01*
X1242715Y382654D01*
X1241881D01*
G01X1245898D02*
Y385154D01*
X1245398Y384654D01*
G01Y382654D02*
X1246398D01*
G01X1248290Y382946D02*
X1248581Y382737D01*
X1248915Y382654D01*
X1249248Y382737D01*
X1249540Y382987D01*
X1249748Y383362D01*
X1249831Y383737D01*
Y384196D01*
X1249748Y384571D01*
X1249540Y384904D01*
X1249290Y385071D01*
X1248998Y385154D01*
X1248665Y385071D01*
X1248415Y384904D01*
X1248248Y384654D01*
X1248165Y384321D01*
X1248248Y384029D01*
X1248456Y383737D01*
X1248706Y383571D01*
X1248998Y383529D01*
X1249331Y383612D01*
X1249581Y383821D01*
X1249831Y384196D01*
G01X1232641Y519932D02*
Y522432D01*
X1233682D01*
X1234016Y522307D01*
X1234224Y522140D01*
X1234307Y521807D01*
X1234224Y521474D01*
X1233974Y521265D01*
X1233682Y521140D01*
X1232641D01*
G01X1233682D02*
X1234307Y519932D01*
G01X1235657Y520307D02*
X1235907Y520099D01*
X1236199Y519974D01*
X1236574Y519932D01*
X1236949Y520015D01*
X1237241Y520182D01*
X1237449Y520474D01*
X1237491Y520807D01*
X1237407Y521140D01*
X1237199Y521349D01*
X1236907Y521515D01*
X1236616Y521557D01*
X1236324Y521515D01*
X1235949Y521349D01*
X1236074Y522432D01*
X1237199D01*
G01X1238882Y522015D02*
X1239132Y522265D01*
X1239424Y522390D01*
X1239757Y522432D01*
X1240174Y522349D01*
X1240466Y522140D01*
X1240549Y521890D01*
X1240507Y521640D01*
X1240341Y521432D01*
X1239507Y521015D01*
X1239132Y520724D01*
X1238882Y520307D01*
X1238799Y519932D01*
X1240549D01*
G01X1241982Y520974D02*
X1242274Y521265D01*
X1242524Y521432D01*
X1242857Y521515D01*
X1243149Y521432D01*
X1243357Y521265D01*
X1243524Y521015D01*
X1243566Y520724D01*
X1243524Y520474D01*
X1243357Y520224D01*
X1243107Y520015D01*
X1242816Y519932D01*
X1242482Y520015D01*
X1242191Y520265D01*
X1242024Y520640D01*
X1241982Y521057D01*
X1242066Y521599D01*
X1242191Y521890D01*
X1242399Y522182D01*
X1242691Y522390D01*
X1242982Y522432D01*
X1243274Y522349D01*
X1243482Y522140D01*
G01X1202797Y729070D02*
X1202547Y729195D01*
X1202255Y729278D01*
X1201922D01*
X1201547Y729153D01*
X1201255Y728945D01*
X1201047Y728695D01*
X1200880Y728278D01*
X1200838Y727903D01*
X1200922Y727528D01*
X1201047Y727278D01*
X1201297Y727028D01*
X1201588Y726861D01*
X1201880Y726778D01*
X1202172D01*
X1202463Y726861D01*
X1202713Y726986D01*
X1202922Y727153D01*
G01X1204980Y726778D02*
Y729278D01*
X1204480Y728778D01*
G01Y726778D02*
X1205480D01*
G01X1207288Y728861D02*
X1207538Y729111D01*
X1207830Y729236D01*
X1208163Y729278D01*
X1208580Y729195D01*
X1208872Y728986D01*
X1208955Y728736D01*
X1208913Y728486D01*
X1208747Y728278D01*
X1207913Y727861D01*
X1207538Y727570D01*
X1207288Y727153D01*
X1207205Y726778D01*
X1208955D01*
G01X1211180D02*
Y729278D01*
X1210680Y728778D01*
G01Y726778D02*
X1211680D01*
G01X1200318Y718942D02*
X1200068Y719067D01*
X1199776Y719150D01*
X1199443D01*
X1199068Y719025D01*
X1198776Y718817D01*
X1198568Y718567D01*
X1198401Y718150D01*
X1198359Y717775D01*
X1198443Y717400D01*
X1198568Y717150D01*
X1198818Y716900D01*
X1199109Y716733D01*
X1199401Y716650D01*
X1199693D01*
X1199984Y716733D01*
X1200234Y716858D01*
X1200443Y717025D01*
G01X1202501Y716650D02*
Y719150D01*
X1202001Y718650D01*
G01Y716650D02*
X1203001D01*
G01X1204809Y718733D02*
X1205059Y718983D01*
X1205351Y719108D01*
X1205684Y719150D01*
X1206101Y719067D01*
X1206393Y718858D01*
X1206476Y718608D01*
X1206434Y718358D01*
X1206268Y718150D01*
X1205434Y717733D01*
X1205059Y717442D01*
X1204809Y717025D01*
X1204726Y716650D01*
X1206476D01*
G01X1208701Y719150D02*
X1208368Y719067D01*
X1208118Y718858D01*
X1207951Y718608D01*
X1207826Y718275D01*
X1207784Y717900D01*
X1207826Y717525D01*
X1207951Y717192D01*
X1208118Y716942D01*
X1208368Y716733D01*
X1208701Y716650D01*
X1209034Y716733D01*
X1209284Y716942D01*
X1209451Y717192D01*
X1209576Y717525D01*
X1209618Y717900D01*
X1209576Y718275D01*
X1209451Y718608D01*
X1209284Y718858D01*
X1209034Y719067D01*
X1208701Y719150D01*
G01X1233017Y970167D02*
Y972667D01*
X1234058D01*
X1234392Y972542D01*
X1234600Y972375D01*
X1234683Y972042D01*
X1234600Y971709D01*
X1234350Y971500D01*
X1234058Y971375D01*
X1233017D01*
G01X1234058D02*
X1234683Y970167D01*
G01X1237450D02*
Y972667D01*
X1235908Y970875D01*
X1237992D01*
G01X1239967Y970167D02*
X1240050Y970709D01*
X1240175Y971167D01*
X1240342Y971584D01*
X1240550Y972042D01*
X1240883Y972667D01*
X1239217D01*
G01X1243067Y970167D02*
X1243150Y970709D01*
X1243275Y971167D01*
X1243442Y971584D01*
X1243650Y972042D01*
X1243983Y972667D01*
X1242317D01*
G01X1201646Y1032231D02*
Y1034731D01*
X1202687D01*
X1203021Y1034606D01*
X1203229Y1034439D01*
X1203312Y1034106D01*
X1203229Y1033773D01*
X1202979Y1033564D01*
X1202687Y1033439D01*
X1201646D01*
G01X1202687D02*
X1203312Y1032231D01*
G01X1206079D02*
Y1034731D01*
X1204537Y1032939D01*
X1206621D01*
G01X1209179Y1032231D02*
Y1034731D01*
X1207637Y1032939D01*
X1209721D01*
G01X1211696Y1032231D02*
X1211779Y1032773D01*
X1211904Y1033231D01*
X1212071Y1033648D01*
X1212279Y1034106D01*
X1212612Y1034731D01*
X1210946D01*
G01X1199829Y1031731D02*
Y1035731D01*
X1192429D01*
G01X1201646Y1027531D02*
Y1030031D01*
X1202687D01*
X1203021Y1029906D01*
X1203229Y1029739D01*
X1203312Y1029406D01*
X1203229Y1029073D01*
X1202979Y1028864D01*
X1202687Y1028739D01*
X1201646D01*
G01X1202687D02*
X1203312Y1027531D01*
G01X1206079D02*
Y1030031D01*
X1204537Y1028239D01*
X1206621D01*
G01X1209179Y1027531D02*
Y1030031D01*
X1207637Y1028239D01*
X1209721D01*
G01X1211779Y1027531D02*
X1212071Y1027573D01*
X1212404Y1027698D01*
X1212612Y1027906D01*
X1212696Y1028198D01*
X1212612Y1028489D01*
X1212362Y1028739D01*
X1211987Y1028864D01*
X1211571D01*
X1211321Y1028948D01*
X1211112Y1029156D01*
X1211029Y1029448D01*
X1211154Y1029739D01*
X1211446Y1029948D01*
X1211779Y1030031D01*
X1212112Y1029948D01*
X1212404Y1029739D01*
X1212529Y1029448D01*
X1212446Y1029156D01*
X1212237Y1028948D01*
X1211987Y1028864D01*
X1211571D01*
X1211196Y1028739D01*
X1210946Y1028489D01*
X1210862Y1028198D01*
X1210946Y1027906D01*
X1211154Y1027698D01*
X1211487Y1027573D01*
X1211779Y1027531D01*
G01X1199829Y1027031D02*
Y1031031D01*
X1192429D01*
G01X1221964Y1135325D02*
Y1137825D01*
X1223005D01*
X1223339Y1137700D01*
X1223547Y1137533D01*
X1223630Y1137200D01*
X1223547Y1136867D01*
X1223297Y1136658D01*
X1223005Y1136533D01*
X1221964D01*
G01X1223005D02*
X1223630Y1135325D01*
G01X1224980Y1135700D02*
X1225230Y1135492D01*
X1225522Y1135367D01*
X1225897Y1135325D01*
X1226272Y1135408D01*
X1226564Y1135575D01*
X1226772Y1135867D01*
X1226814Y1136200D01*
X1226730Y1136533D01*
X1226522Y1136742D01*
X1226230Y1136908D01*
X1225939Y1136950D01*
X1225647Y1136908D01*
X1225272Y1136742D01*
X1225397Y1137825D01*
X1226522D01*
G01X1228997Y1135325D02*
X1229289Y1135367D01*
X1229622Y1135492D01*
X1229830Y1135700D01*
X1229914Y1135992D01*
X1229830Y1136283D01*
X1229580Y1136533D01*
X1229205Y1136658D01*
X1228789D01*
X1228539Y1136742D01*
X1228330Y1136950D01*
X1228247Y1137242D01*
X1228372Y1137533D01*
X1228664Y1137742D01*
X1228997Y1137825D01*
X1229330Y1137742D01*
X1229622Y1137533D01*
X1229747Y1137242D01*
X1229664Y1136950D01*
X1229455Y1136742D01*
X1229205Y1136658D01*
X1228789D01*
X1228414Y1136533D01*
X1228164Y1136283D01*
X1228080Y1135992D01*
X1228164Y1135700D01*
X1228372Y1135492D01*
X1228705Y1135367D01*
X1228997Y1135325D01*
G01X1232014D02*
X1232097Y1135867D01*
X1232222Y1136325D01*
X1232389Y1136742D01*
X1232597Y1137200D01*
X1232930Y1137825D01*
X1231264D01*
G01X1224247Y1147325D02*
Y1143325D01*
X1231647D01*
G01X1221195Y1166141D02*
X1220862Y1166183D01*
X1220570Y1166349D01*
X1220320Y1166599D01*
X1220153Y1166891D01*
X1220070Y1167224D01*
Y1167558D01*
X1220153Y1167891D01*
X1220320Y1168183D01*
X1220570Y1168433D01*
X1220862Y1168599D01*
X1221195Y1168641D01*
X1221528Y1168599D01*
X1221820Y1168433D01*
X1222070Y1168183D01*
X1222237Y1167891D01*
X1222320Y1167558D01*
Y1167224D01*
X1222237Y1166891D01*
X1222070Y1166599D01*
X1221820Y1166349D01*
X1221528Y1166183D01*
X1221195Y1166141D01*
G01X1221528Y1166808D02*
X1222028Y1166141D01*
G01X1223503Y1168224D02*
X1223753Y1168474D01*
X1224045Y1168599D01*
X1224378Y1168641D01*
X1224795Y1168558D01*
X1225087Y1168349D01*
X1225170Y1168099D01*
X1225128Y1167849D01*
X1224962Y1167641D01*
X1224128Y1167224D01*
X1223753Y1166933D01*
X1223503Y1166516D01*
X1223420Y1166141D01*
X1225170D01*
G01X1226478Y1166516D02*
X1226728Y1166308D01*
X1227020Y1166183D01*
X1227395Y1166141D01*
X1227770Y1166224D01*
X1228062Y1166391D01*
X1228270Y1166683D01*
X1228312Y1167016D01*
X1228228Y1167349D01*
X1228020Y1167558D01*
X1227728Y1167724D01*
X1227437Y1167766D01*
X1227145Y1167724D01*
X1226770Y1167558D01*
X1226895Y1168641D01*
X1228020D01*
G01X1230412Y1166141D02*
X1230495Y1166683D01*
X1230620Y1167141D01*
X1230787Y1167558D01*
X1230995Y1168016D01*
X1231328Y1168641D01*
X1229662D01*
G01X1219345Y1164141D02*
Y1150141D01*
G01X1232345Y1164141D02*
X1219345D01*
G01X1232345Y1150141D02*
Y1164141D01*
G01X1219345Y1150141D02*
X1232345D01*
G01X1201705Y1153211D02*
X1199205D01*
Y1154252D01*
X1199330Y1154586D01*
X1199497Y1154794D01*
X1199830Y1154877D01*
X1200163Y1154794D01*
X1200372Y1154544D01*
X1200497Y1154252D01*
Y1153211D01*
G01Y1154252D02*
X1201705Y1154877D01*
G01X1199622Y1156352D02*
X1199372Y1156602D01*
X1199247Y1156894D01*
X1199205Y1157227D01*
X1199288Y1157644D01*
X1199497Y1157936D01*
X1199747Y1158019D01*
X1199997Y1157977D01*
X1200205Y1157811D01*
X1200622Y1156977D01*
X1200913Y1156602D01*
X1201330Y1156352D01*
X1201705Y1156269D01*
Y1158019D01*
G01Y1160161D02*
X1201163Y1160244D01*
X1200705Y1160369D01*
X1200288Y1160536D01*
X1199830Y1160744D01*
X1199205Y1161077D01*
Y1159411D01*
G01X1201705Y1163344D02*
X1201663Y1163636D01*
X1201538Y1163969D01*
X1201330Y1164177D01*
X1201038Y1164261D01*
X1200747Y1164177D01*
X1200497Y1163927D01*
X1200372Y1163552D01*
Y1163136D01*
X1200288Y1162886D01*
X1200080Y1162677D01*
X1199788Y1162594D01*
X1199497Y1162719D01*
X1199288Y1163011D01*
X1199205Y1163344D01*
X1199288Y1163677D01*
X1199497Y1163969D01*
X1199788Y1164094D01*
X1200080Y1164011D01*
X1200288Y1163802D01*
X1200372Y1163552D01*
Y1163136D01*
X1200497Y1162761D01*
X1200747Y1162511D01*
X1201038Y1162427D01*
X1201330Y1162511D01*
X1201538Y1162719D01*
X1201663Y1163052D01*
X1201705Y1163344D01*
G01X1206705Y1153211D02*
X1204205D01*
Y1154252D01*
X1204330Y1154586D01*
X1204497Y1154794D01*
X1204830Y1154877D01*
X1205163Y1154794D01*
X1205372Y1154544D01*
X1205497Y1154252D01*
Y1153211D01*
G01Y1154252D02*
X1206705Y1154877D01*
G01X1204622Y1156352D02*
X1204372Y1156602D01*
X1204247Y1156894D01*
X1204205Y1157227D01*
X1204288Y1157644D01*
X1204497Y1157936D01*
X1204747Y1158019D01*
X1204997Y1157977D01*
X1205205Y1157811D01*
X1205622Y1156977D01*
X1205913Y1156602D01*
X1206330Y1156352D01*
X1206705Y1156269D01*
Y1158019D01*
G01Y1160161D02*
X1206163Y1160244D01*
X1205705Y1160369D01*
X1205288Y1160536D01*
X1204830Y1160744D01*
X1204205Y1161077D01*
Y1159411D01*
G01X1206705Y1163844D02*
X1204205D01*
X1205997Y1162302D01*
Y1164386D01*
G01X1231665Y1285665D02*
Y1288165D01*
X1232706D01*
X1233040Y1288040D01*
X1233248Y1287873D01*
X1233331Y1287540D01*
X1233248Y1287207D01*
X1232998Y1286998D01*
X1232706Y1286873D01*
X1231665D01*
G01X1232706D02*
X1233331Y1285665D01*
G01X1234765Y1288165D02*
Y1285665D01*
X1236431D01*
G01X1239531D02*
X1237865D01*
Y1288165D01*
X1239531D01*
G01X1238865Y1286957D02*
X1237865D01*
G01X1240881Y1285665D02*
Y1288165D01*
X1241715D01*
X1242048Y1288040D01*
X1242298Y1287873D01*
X1242506Y1287623D01*
X1242673Y1287332D01*
X1242715Y1286915D01*
X1242673Y1286498D01*
X1242506Y1286207D01*
X1242298Y1285957D01*
X1242048Y1285790D01*
X1241715Y1285665D01*
X1240881D01*
G01X1243981Y1286165D02*
X1244231Y1285873D01*
X1244565Y1285707D01*
X1244940Y1285665D01*
X1245273Y1285707D01*
X1245606Y1285915D01*
X1245815Y1286165D01*
X1245856Y1286415D01*
X1245773Y1286707D01*
X1245481Y1286915D01*
X1245190Y1286998D01*
X1244815D01*
G01X1245190D02*
X1245440Y1287123D01*
X1245648Y1287332D01*
X1245731Y1287582D01*
X1245648Y1287832D01*
X1245440Y1288040D01*
X1245065Y1288165D01*
X1244690Y1288123D01*
X1244315Y1287957D01*
G01X1247998Y1285665D02*
Y1288165D01*
X1247498Y1287665D01*
G01Y1285665D02*
X1248498D01*
G01X1279784Y107800D02*
X1277284D01*
Y108841D01*
X1277409Y109175D01*
X1277576Y109383D01*
X1277909Y109466D01*
X1278242Y109383D01*
X1278451Y109133D01*
X1278576Y108841D01*
Y107800D01*
G01Y108841D02*
X1279784Y109466D01*
G01Y111733D02*
X1277284D01*
X1277784Y111233D01*
G01X1279784D02*
Y112233D01*
G01X1277701Y114041D02*
X1277451Y114291D01*
X1277326Y114583D01*
X1277284Y114916D01*
X1277367Y115333D01*
X1277576Y115625D01*
X1277826Y115708D01*
X1278076Y115666D01*
X1278284Y115500D01*
X1278701Y114666D01*
X1278992Y114291D01*
X1279409Y114041D01*
X1279784Y113958D01*
Y115708D01*
G01X1279492Y117225D02*
X1279701Y117516D01*
X1279784Y117850D01*
X1279701Y118183D01*
X1279451Y118475D01*
X1279076Y118683D01*
X1278701Y118766D01*
X1278242D01*
X1277867Y118683D01*
X1277534Y118475D01*
X1277367Y118225D01*
X1277284Y117933D01*
X1277367Y117600D01*
X1277534Y117350D01*
X1277784Y117183D01*
X1278117Y117100D01*
X1278409Y117183D01*
X1278701Y117391D01*
X1278867Y117641D01*
X1278909Y117933D01*
X1278826Y118266D01*
X1278617Y118516D01*
X1278242Y118766D01*
G01X1279492Y120325D02*
X1279701Y120616D01*
X1279784Y120950D01*
X1279701Y121283D01*
X1279451Y121575D01*
X1279076Y121783D01*
X1278701Y121866D01*
X1278242D01*
X1277867Y121783D01*
X1277534Y121575D01*
X1277367Y121325D01*
X1277284Y121033D01*
X1277367Y120700D01*
X1277534Y120450D01*
X1277784Y120283D01*
X1278117Y120200D01*
X1278409Y120283D01*
X1278701Y120491D01*
X1278867Y120741D01*
X1278909Y121033D01*
X1278826Y121366D01*
X1278617Y121616D01*
X1278242Y121866D01*
G01X1283784Y107800D02*
X1281284D01*
Y108841D01*
X1281409Y109175D01*
X1281576Y109383D01*
X1281909Y109466D01*
X1282242Y109383D01*
X1282451Y109133D01*
X1282576Y108841D01*
Y107800D01*
G01Y108841D02*
X1283784Y109466D01*
G01Y111733D02*
X1281284D01*
X1281784Y111233D01*
G01X1283784D02*
Y112233D01*
G01X1281284Y114833D02*
X1281367Y114500D01*
X1281576Y114250D01*
X1281826Y114083D01*
X1282159Y113958D01*
X1282534Y113916D01*
X1282909Y113958D01*
X1283242Y114083D01*
X1283492Y114250D01*
X1283701Y114500D01*
X1283784Y114833D01*
X1283701Y115166D01*
X1283492Y115416D01*
X1283242Y115583D01*
X1282909Y115708D01*
X1282534Y115750D01*
X1282159Y115708D01*
X1281826Y115583D01*
X1281576Y115416D01*
X1281367Y115166D01*
X1281284Y114833D01*
G01Y117933D02*
X1281367Y117600D01*
X1281576Y117350D01*
X1281826Y117183D01*
X1282159Y117058D01*
X1282534Y117016D01*
X1282909Y117058D01*
X1283242Y117183D01*
X1283492Y117350D01*
X1283701Y117600D01*
X1283784Y117933D01*
X1283701Y118266D01*
X1283492Y118516D01*
X1283242Y118683D01*
X1282909Y118808D01*
X1282534Y118850D01*
X1282159Y118808D01*
X1281826Y118683D01*
X1281576Y118516D01*
X1281367Y118266D01*
X1281284Y117933D01*
G01X1277334Y84467D02*
X1274834D01*
Y85508D01*
X1274959Y85842D01*
X1275126Y86050D01*
X1275459Y86133D01*
X1275792Y86050D01*
X1276001Y85800D01*
X1276126Y85508D01*
Y84467D01*
G01Y85508D02*
X1277334Y86133D01*
G01Y88400D02*
X1274834D01*
X1275334Y87900D01*
G01X1277334D02*
Y88900D01*
G01X1274834Y91500D02*
X1274917Y91167D01*
X1275126Y90917D01*
X1275376Y90750D01*
X1275709Y90625D01*
X1276084Y90583D01*
X1276459Y90625D01*
X1276792Y90750D01*
X1277042Y90917D01*
X1277251Y91167D01*
X1277334Y91500D01*
X1277251Y91833D01*
X1277042Y92083D01*
X1276792Y92250D01*
X1276459Y92375D01*
X1276084Y92417D01*
X1275709Y92375D01*
X1275376Y92250D01*
X1275126Y92083D01*
X1274917Y91833D01*
X1274834Y91500D01*
G01X1277334Y94600D02*
X1274834D01*
X1275334Y94100D01*
G01X1277334D02*
Y95100D01*
G01X1274834Y97700D02*
X1274917Y97367D01*
X1275126Y97117D01*
X1275376Y96950D01*
X1275709Y96825D01*
X1276084Y96783D01*
X1276459Y96825D01*
X1276792Y96950D01*
X1277042Y97117D01*
X1277251Y97367D01*
X1277334Y97700D01*
X1277251Y98033D01*
X1277042Y98283D01*
X1276792Y98450D01*
X1276459Y98575D01*
X1276084Y98617D01*
X1275709Y98575D01*
X1275376Y98450D01*
X1275126Y98283D01*
X1274917Y98033D01*
X1274834Y97700D01*
G01X1282000Y84428D02*
X1279500D01*
Y85469D01*
X1279625Y85803D01*
X1279792Y86011D01*
X1280125Y86094D01*
X1280458Y86011D01*
X1280667Y85761D01*
X1280792Y85469D01*
Y84428D01*
G01Y85469D02*
X1282000Y86094D01*
G01X1281708Y87653D02*
X1281917Y87944D01*
X1282000Y88278D01*
X1281917Y88611D01*
X1281667Y88903D01*
X1281292Y89111D01*
X1280917Y89194D01*
X1280458D01*
X1280083Y89111D01*
X1279750Y88903D01*
X1279583Y88653D01*
X1279500Y88361D01*
X1279583Y88028D01*
X1279750Y87778D01*
X1280000Y87611D01*
X1280333Y87528D01*
X1280625Y87611D01*
X1280917Y87819D01*
X1281083Y88069D01*
X1281125Y88361D01*
X1281042Y88694D01*
X1280833Y88944D01*
X1280458Y89194D01*
G01X1282000Y91461D02*
X1281958Y91753D01*
X1281833Y92086D01*
X1281625Y92294D01*
X1281333Y92378D01*
X1281042Y92294D01*
X1280792Y92044D01*
X1280667Y91669D01*
Y91253D01*
X1280583Y91003D01*
X1280375Y90794D01*
X1280083Y90711D01*
X1279792Y90836D01*
X1279583Y91128D01*
X1279500Y91461D01*
X1279583Y91794D01*
X1279792Y92086D01*
X1280083Y92211D01*
X1280375Y92128D01*
X1280583Y91919D01*
X1280667Y91669D01*
Y91253D01*
X1280792Y90878D01*
X1281042Y90628D01*
X1281333Y90544D01*
X1281625Y90628D01*
X1281833Y90836D01*
X1281958Y91169D01*
X1282000Y91461D01*
G01X1280958Y93769D02*
X1280667Y94061D01*
X1280500Y94311D01*
X1280417Y94644D01*
X1280500Y94936D01*
X1280667Y95144D01*
X1280917Y95311D01*
X1281208Y95353D01*
X1281458Y95311D01*
X1281708Y95144D01*
X1281917Y94894D01*
X1282000Y94603D01*
X1281917Y94269D01*
X1281667Y93978D01*
X1281292Y93811D01*
X1280875Y93769D01*
X1280333Y93853D01*
X1280042Y93978D01*
X1279750Y94186D01*
X1279542Y94478D01*
X1279500Y94769D01*
X1279583Y95061D01*
X1279792Y95269D01*
G01X1264793Y221492D02*
X1269843D01*
Y320192D01*
X1294493D01*
Y135792D01*
X1269843D01*
Y194492D01*
X1264793D01*
Y221492D01*
G01X1247045Y173684D02*
X1246795Y173809D01*
X1246503Y173892D01*
X1246170D01*
X1245795Y173767D01*
X1245503Y173559D01*
X1245295Y173309D01*
X1245128Y172892D01*
X1245086Y172517D01*
X1245170Y172142D01*
X1245295Y171892D01*
X1245545Y171642D01*
X1245836Y171475D01*
X1246128Y171392D01*
X1246420D01*
X1246711Y171475D01*
X1246961Y171600D01*
X1247170Y171767D01*
G01X1249728Y171392D02*
Y173892D01*
X1248186Y172100D01*
X1250270D01*
G01X1251536Y173475D02*
X1251786Y173725D01*
X1252078Y173850D01*
X1252411Y173892D01*
X1252828Y173809D01*
X1253120Y173600D01*
X1253203Y173350D01*
X1253161Y173100D01*
X1252995Y172892D01*
X1252161Y172475D01*
X1251786Y172184D01*
X1251536Y171767D01*
X1251453Y171392D01*
X1253203D01*
G01X1254720Y171684D02*
X1255011Y171475D01*
X1255345Y171392D01*
X1255678Y171475D01*
X1255970Y171725D01*
X1256178Y172100D01*
X1256261Y172475D01*
Y172934D01*
X1256178Y173309D01*
X1255970Y173642D01*
X1255720Y173809D01*
X1255428Y173892D01*
X1255095Y173809D01*
X1254845Y173642D01*
X1254678Y173392D01*
X1254595Y173059D01*
X1254678Y172767D01*
X1254886Y172475D01*
X1255136Y172309D01*
X1255428Y172267D01*
X1255761Y172350D01*
X1256011Y172559D01*
X1256261Y172934D01*
G01X1247267Y177792D02*
X1247017Y177917D01*
X1246725Y178000D01*
X1246392D01*
X1246017Y177875D01*
X1245725Y177667D01*
X1245517Y177417D01*
X1245350Y177000D01*
X1245308Y176625D01*
X1245392Y176250D01*
X1245517Y176000D01*
X1245767Y175750D01*
X1246058Y175583D01*
X1246350Y175500D01*
X1246642D01*
X1246933Y175583D01*
X1247183Y175708D01*
X1247392Y175875D01*
G01X1249950Y175500D02*
Y178000D01*
X1248408Y176208D01*
X1250492D01*
G01X1251758Y177583D02*
X1252008Y177833D01*
X1252300Y177958D01*
X1252633Y178000D01*
X1253050Y177917D01*
X1253342Y177708D01*
X1253425Y177458D01*
X1253383Y177208D01*
X1253217Y177000D01*
X1252383Y176583D01*
X1252008Y176292D01*
X1251758Y175875D01*
X1251675Y175500D01*
X1253425D01*
G01X1255650D02*
X1255942Y175542D01*
X1256275Y175667D01*
X1256483Y175875D01*
X1256567Y176167D01*
X1256483Y176458D01*
X1256233Y176708D01*
X1255858Y176833D01*
X1255442D01*
X1255192Y176917D01*
X1254983Y177125D01*
X1254900Y177417D01*
X1255025Y177708D01*
X1255317Y177917D01*
X1255650Y178000D01*
X1255983Y177917D01*
X1256275Y177708D01*
X1256400Y177417D01*
X1256317Y177125D01*
X1256108Y176917D01*
X1255858Y176833D01*
X1255442D01*
X1255067Y176708D01*
X1254817Y176458D01*
X1254733Y176167D01*
X1254817Y175875D01*
X1255025Y175667D01*
X1255358Y175542D01*
X1255650Y175500D01*
G01X1251834Y213017D02*
X1249334D01*
Y214058D01*
X1249459Y214392D01*
X1249626Y214600D01*
X1249959Y214683D01*
X1250292Y214600D01*
X1250501Y214350D01*
X1250626Y214058D01*
Y213017D01*
G01Y214058D02*
X1251834Y214683D01*
G01X1251334Y216033D02*
X1251626Y216283D01*
X1251792Y216617D01*
X1251834Y216992D01*
X1251792Y217325D01*
X1251584Y217658D01*
X1251334Y217867D01*
X1251084Y217908D01*
X1250792Y217825D01*
X1250584Y217533D01*
X1250501Y217242D01*
Y216867D01*
G01Y217242D02*
X1250376Y217492D01*
X1250167Y217700D01*
X1249917Y217783D01*
X1249667Y217700D01*
X1249459Y217492D01*
X1249334Y217117D01*
X1249376Y216742D01*
X1249542Y216367D01*
G01X1251542Y219342D02*
X1251751Y219633D01*
X1251834Y219967D01*
X1251751Y220300D01*
X1251501Y220592D01*
X1251126Y220800D01*
X1250751Y220883D01*
X1250292D01*
X1249917Y220800D01*
X1249584Y220592D01*
X1249417Y220342D01*
X1249334Y220050D01*
X1249417Y219717D01*
X1249584Y219467D01*
X1249834Y219300D01*
X1250167Y219217D01*
X1250459Y219300D01*
X1250751Y219508D01*
X1250917Y219758D01*
X1250959Y220050D01*
X1250876Y220383D01*
X1250667Y220633D01*
X1250292Y220883D01*
G01X1251334Y222233D02*
X1251626Y222483D01*
X1251792Y222817D01*
X1251834Y223192D01*
X1251792Y223525D01*
X1251584Y223858D01*
X1251334Y224067D01*
X1251084Y224108D01*
X1250792Y224025D01*
X1250584Y223733D01*
X1250501Y223442D01*
Y223067D01*
G01Y223442D02*
X1250376Y223692D01*
X1250167Y223900D01*
X1249917Y223983D01*
X1249667Y223900D01*
X1249459Y223692D01*
X1249334Y223317D01*
X1249376Y222942D01*
X1249542Y222567D01*
G01X1248410Y231009D02*
X1252410D01*
Y238409D01*
G01X1255517Y232361D02*
Y234861D01*
X1256558D01*
X1256892Y234736D01*
X1257100Y234569D01*
X1257183Y234236D01*
X1257100Y233903D01*
X1256850Y233694D01*
X1256558Y233569D01*
X1255517D01*
G01X1256558D02*
X1257183Y232361D01*
G01X1259450D02*
X1259742Y232403D01*
X1260075Y232528D01*
X1260283Y232736D01*
X1260367Y233028D01*
X1260283Y233319D01*
X1260033Y233569D01*
X1259658Y233694D01*
X1259242D01*
X1258992Y233778D01*
X1258783Y233986D01*
X1258700Y234278D01*
X1258825Y234569D01*
X1259117Y234778D01*
X1259450Y234861D01*
X1259783Y234778D01*
X1260075Y234569D01*
X1260200Y234278D01*
X1260117Y233986D01*
X1259908Y233778D01*
X1259658Y233694D01*
X1259242D01*
X1258867Y233569D01*
X1258617Y233319D01*
X1258533Y233028D01*
X1258617Y232736D01*
X1258825Y232528D01*
X1259158Y232403D01*
X1259450Y232361D01*
G01X1261758Y234444D02*
X1262008Y234694D01*
X1262300Y234819D01*
X1262633Y234861D01*
X1263050Y234778D01*
X1263342Y234569D01*
X1263425Y234319D01*
X1263383Y234069D01*
X1263217Y233861D01*
X1262383Y233444D01*
X1262008Y233153D01*
X1261758Y232736D01*
X1261675Y232361D01*
X1263425D01*
G01X1265650Y234861D02*
X1265317Y234778D01*
X1265067Y234569D01*
X1264900Y234319D01*
X1264775Y233986D01*
X1264733Y233611D01*
X1264775Y233236D01*
X1264900Y232903D01*
X1265067Y232653D01*
X1265317Y232444D01*
X1265650Y232361D01*
X1265983Y232444D01*
X1266233Y232653D01*
X1266400Y232903D01*
X1266525Y233236D01*
X1266567Y233611D01*
X1266525Y233986D01*
X1266400Y234319D01*
X1266233Y234569D01*
X1265983Y234778D01*
X1265650Y234861D01*
G01X1251300Y246861D02*
Y242861D01*
X1258700D01*
G01X1233717Y242725D02*
Y240933D01*
X1233884Y240558D01*
X1234217Y240308D01*
X1234634Y240225D01*
X1235051Y240308D01*
X1235384Y240558D01*
X1235551Y240933D01*
Y242725D01*
G01X1238234Y240225D02*
Y242725D01*
X1236692Y240933D01*
X1238776D01*
G01X1240042Y242308D02*
X1240292Y242558D01*
X1240584Y242683D01*
X1240917Y242725D01*
X1241334Y242642D01*
X1241626Y242433D01*
X1241709Y242183D01*
X1241667Y241933D01*
X1241501Y241725D01*
X1240667Y241308D01*
X1240292Y241017D01*
X1240042Y240600D01*
X1239959Y240225D01*
X1241709D01*
G01X1243850Y238300D02*
Y228300D01*
G01X1254017Y260000D02*
Y262500D01*
X1255058D01*
X1255392Y262375D01*
X1255600Y262208D01*
X1255683Y261875D01*
X1255600Y261542D01*
X1255350Y261333D01*
X1255058Y261208D01*
X1254017D01*
G01X1255058D02*
X1255683Y260000D01*
G01X1257950D02*
X1258242Y260042D01*
X1258575Y260167D01*
X1258783Y260375D01*
X1258867Y260667D01*
X1258783Y260958D01*
X1258533Y261208D01*
X1258158Y261333D01*
X1257742D01*
X1257492Y261417D01*
X1257283Y261625D01*
X1257200Y261917D01*
X1257325Y262208D01*
X1257617Y262417D01*
X1257950Y262500D01*
X1258283Y262417D01*
X1258575Y262208D01*
X1258700Y261917D01*
X1258617Y261625D01*
X1258408Y261417D01*
X1258158Y261333D01*
X1257742D01*
X1257367Y261208D01*
X1257117Y260958D01*
X1257033Y260667D01*
X1257117Y260375D01*
X1257325Y260167D01*
X1257658Y260042D01*
X1257950Y260000D01*
G01X1260258Y262083D02*
X1260508Y262333D01*
X1260800Y262458D01*
X1261133Y262500D01*
X1261550Y262417D01*
X1261842Y262208D01*
X1261925Y261958D01*
X1261883Y261708D01*
X1261717Y261500D01*
X1260883Y261083D01*
X1260508Y260792D01*
X1260258Y260375D01*
X1260175Y260000D01*
X1261925D01*
G01X1264650D02*
Y262500D01*
X1263108Y260708D01*
X1265192D01*
G01X1237259Y225384D02*
X1237009Y225509D01*
X1236717Y225592D01*
X1236384D01*
X1236009Y225467D01*
X1235717Y225259D01*
X1235509Y225009D01*
X1235342Y224592D01*
X1235300Y224217D01*
X1235384Y223842D01*
X1235509Y223592D01*
X1235759Y223342D01*
X1236050Y223175D01*
X1236342Y223092D01*
X1236634D01*
X1236925Y223175D01*
X1237175Y223300D01*
X1237384Y223467D01*
G01X1239442Y223092D02*
X1239734Y223134D01*
X1240067Y223259D01*
X1240275Y223467D01*
X1240359Y223759D01*
X1240275Y224050D01*
X1240025Y224300D01*
X1239650Y224425D01*
X1239234D01*
X1238984Y224509D01*
X1238775Y224717D01*
X1238692Y225009D01*
X1238817Y225300D01*
X1239109Y225509D01*
X1239442Y225592D01*
X1239775Y225509D01*
X1240067Y225300D01*
X1240192Y225009D01*
X1240109Y224717D01*
X1239900Y224509D01*
X1239650Y224425D01*
X1239234D01*
X1238859Y224300D01*
X1238609Y224050D01*
X1238525Y223759D01*
X1238609Y223467D01*
X1238817Y223259D01*
X1239150Y223134D01*
X1239442Y223092D01*
G01X1241750Y225175D02*
X1242000Y225425D01*
X1242292Y225550D01*
X1242625Y225592D01*
X1243042Y225509D01*
X1243334Y225300D01*
X1243417Y225050D01*
X1243375Y224800D01*
X1243209Y224592D01*
X1242375Y224175D01*
X1242000Y223884D01*
X1241750Y223467D01*
X1241667Y223092D01*
X1243417D01*
G01X1257267Y230453D02*
X1257017Y230578D01*
X1256725Y230661D01*
X1256392D01*
X1256017Y230536D01*
X1255725Y230328D01*
X1255517Y230078D01*
X1255350Y229661D01*
X1255308Y229286D01*
X1255392Y228911D01*
X1255517Y228661D01*
X1255767Y228411D01*
X1256058Y228244D01*
X1256350Y228161D01*
X1256642D01*
X1256933Y228244D01*
X1257183Y228369D01*
X1257392Y228536D01*
G01X1259950Y228161D02*
Y230661D01*
X1258408Y228869D01*
X1260492D01*
G01X1261633Y228661D02*
X1261883Y228369D01*
X1262217Y228203D01*
X1262592Y228161D01*
X1262925Y228203D01*
X1263258Y228411D01*
X1263467Y228661D01*
X1263508Y228911D01*
X1263425Y229203D01*
X1263133Y229411D01*
X1262842Y229494D01*
X1262467D01*
G01X1262842D02*
X1263092Y229619D01*
X1263300Y229828D01*
X1263383Y230078D01*
X1263300Y230328D01*
X1263092Y230536D01*
X1262717Y230661D01*
X1262342Y230619D01*
X1261967Y230453D01*
G01X1264858Y230244D02*
X1265108Y230494D01*
X1265400Y230619D01*
X1265733Y230661D01*
X1266150Y230578D01*
X1266442Y230369D01*
X1266525Y230119D01*
X1266483Y229869D01*
X1266317Y229661D01*
X1265483Y229244D01*
X1265108Y228953D01*
X1264858Y228536D01*
X1264775Y228161D01*
X1266525D01*
G01X1269968Y329492D02*
Y331992D01*
G01X1271718D02*
Y329492D01*
G01Y330742D02*
X1269968D01*
G01X1273026Y329492D02*
Y331992D01*
X1273860D01*
X1274193Y331867D01*
X1274443Y331700D01*
X1274651Y331450D01*
X1274818Y331159D01*
X1274860Y330742D01*
X1274818Y330325D01*
X1274651Y330034D01*
X1274443Y329784D01*
X1274193Y329617D01*
X1273860Y329492D01*
X1273026D01*
G01X1276126D02*
Y331992D01*
X1276960D01*
X1277293Y331867D01*
X1277543Y331700D01*
X1277751Y331450D01*
X1277918Y331159D01*
X1277960Y330742D01*
X1277918Y330325D01*
X1277751Y330034D01*
X1277543Y329784D01*
X1277293Y329617D01*
X1276960Y329492D01*
X1276126D01*
G01X1279268Y329825D02*
X1279601Y329617D01*
X1279976Y329492D01*
X1280310D01*
X1280643Y329617D01*
X1280893Y329825D01*
X1281018Y330117D01*
X1280935Y330409D01*
X1280726Y330659D01*
X1280351Y330825D01*
X1279851Y330909D01*
X1279560Y331075D01*
X1279435Y331367D01*
X1279518Y331659D01*
X1279726Y331867D01*
X1280018Y331992D01*
X1280310D01*
X1280601Y331909D01*
X1280851Y331700D01*
G01X1282201Y329492D02*
X1283243Y331992D01*
X1284285Y329492D01*
G01X1283910Y330367D02*
X1282576D01*
G01X1285468Y329825D02*
X1285801Y329617D01*
X1286176Y329492D01*
X1286510D01*
X1286843Y329617D01*
X1287093Y329825D01*
X1287218Y330117D01*
X1287135Y330409D01*
X1286926Y330659D01*
X1286551Y330825D01*
X1286051Y330909D01*
X1285760Y331075D01*
X1285635Y331367D01*
X1285718Y331659D01*
X1285926Y331867D01*
X1286218Y331992D01*
X1286510D01*
X1286801Y331909D01*
X1287051Y331700D01*
G01X1288526Y329992D02*
X1288776Y329700D01*
X1289110Y329534D01*
X1289485Y329492D01*
X1289818Y329534D01*
X1290151Y329742D01*
X1290360Y329992D01*
X1290401Y330242D01*
X1290318Y330534D01*
X1290026Y330742D01*
X1289735Y330825D01*
X1289360D01*
G01X1289735D02*
X1289985Y330950D01*
X1290193Y331159D01*
X1290276Y331409D01*
X1290193Y331659D01*
X1289985Y331867D01*
X1289610Y331992D01*
X1289235Y331950D01*
X1288860Y331784D01*
G01X1292543Y331992D02*
X1292210Y331909D01*
X1291960Y331700D01*
X1291793Y331450D01*
X1291668Y331117D01*
X1291626Y330742D01*
X1291668Y330367D01*
X1291793Y330034D01*
X1291960Y329784D01*
X1292210Y329575D01*
X1292543Y329492D01*
X1292876Y329575D01*
X1293126Y329784D01*
X1293293Y330034D01*
X1293418Y330367D01*
X1293460Y330742D01*
X1293418Y331117D01*
X1293293Y331450D01*
X1293126Y331700D01*
X1292876Y331909D01*
X1292543Y331992D01*
G01X1236348Y366054D02*
Y377254D01*
X1245148D01*
Y366054D01*
X1236348D01*
G01X1235108Y492651D02*
X1234775Y492693D01*
X1234483Y492859D01*
X1234233Y493109D01*
X1234066Y493401D01*
X1233983Y493734D01*
Y494068D01*
X1234066Y494401D01*
X1234233Y494693D01*
X1234483Y494943D01*
X1234775Y495109D01*
X1235108Y495151D01*
X1235441Y495109D01*
X1235733Y494943D01*
X1235983Y494693D01*
X1236150Y494401D01*
X1236233Y494068D01*
Y493734D01*
X1236150Y493401D01*
X1235983Y493109D01*
X1235733Y492859D01*
X1235441Y492693D01*
X1235108Y492651D01*
G01X1235441Y493318D02*
X1235941Y492651D01*
G01X1237416Y494734D02*
X1237666Y494984D01*
X1237958Y495109D01*
X1238291Y495151D01*
X1238708Y495068D01*
X1239000Y494859D01*
X1239083Y494609D01*
X1239041Y494359D01*
X1238875Y494151D01*
X1238041Y493734D01*
X1237666Y493443D01*
X1237416Y493026D01*
X1237333Y492651D01*
X1239083D01*
G01X1241308D02*
X1241600Y492693D01*
X1241933Y492818D01*
X1242141Y493026D01*
X1242225Y493318D01*
X1242141Y493609D01*
X1241891Y493859D01*
X1241516Y493984D01*
X1241100D01*
X1240850Y494068D01*
X1240641Y494276D01*
X1240558Y494568D01*
X1240683Y494859D01*
X1240975Y495068D01*
X1241308Y495151D01*
X1241641Y495068D01*
X1241933Y494859D01*
X1242058Y494568D01*
X1241975Y494276D01*
X1241766Y494068D01*
X1241516Y493984D01*
X1241100D01*
X1240725Y493859D01*
X1240475Y493609D01*
X1240391Y493318D01*
X1240475Y493026D01*
X1240683Y492818D01*
X1241016Y492693D01*
X1241308Y492651D01*
G01X1244408D02*
Y495151D01*
X1243908Y494651D01*
G01Y492651D02*
X1244908D01*
G01X1246258Y496151D02*
Y510151D01*
G01X1233258Y496151D02*
X1246258D01*
G01X1233258Y510151D02*
Y496151D01*
G01X1249217Y492650D02*
X1248884Y492692D01*
X1248592Y492858D01*
X1248342Y493108D01*
X1248175Y493400D01*
X1248092Y493733D01*
Y494067D01*
X1248175Y494400D01*
X1248342Y494692D01*
X1248592Y494942D01*
X1248884Y495108D01*
X1249217Y495150D01*
X1249550Y495108D01*
X1249842Y494942D01*
X1250092Y494692D01*
X1250259Y494400D01*
X1250342Y494067D01*
Y493733D01*
X1250259Y493400D01*
X1250092Y493108D01*
X1249842Y492858D01*
X1249550Y492692D01*
X1249217Y492650D01*
G01X1249550Y493317D02*
X1250050Y492650D01*
G01X1251525Y494733D02*
X1251775Y494983D01*
X1252067Y495108D01*
X1252400Y495150D01*
X1252817Y495067D01*
X1253109Y494858D01*
X1253192Y494608D01*
X1253150Y494358D01*
X1252984Y494150D01*
X1252150Y493733D01*
X1251775Y493442D01*
X1251525Y493025D01*
X1251442Y492650D01*
X1253192D01*
G01X1255917D02*
Y495150D01*
X1254375Y493358D01*
X1256459D01*
G01X1257600Y493025D02*
X1257850Y492817D01*
X1258142Y492692D01*
X1258517Y492650D01*
X1258892Y492733D01*
X1259184Y492900D01*
X1259392Y493192D01*
X1259434Y493525D01*
X1259350Y493858D01*
X1259142Y494067D01*
X1258850Y494233D01*
X1258559Y494275D01*
X1258267Y494233D01*
X1257892Y494067D01*
X1258017Y495150D01*
X1259142D01*
G01X1260367Y496150D02*
Y510150D01*
G01X1247367Y496150D02*
X1260367D01*
G01X1247367Y510150D02*
Y496150D01*
G01X1281878Y496438D02*
X1279378D01*
Y497479D01*
X1279503Y497813D01*
X1279670Y498021D01*
X1280003Y498104D01*
X1280336Y498021D01*
X1280545Y497771D01*
X1280670Y497479D01*
Y496438D01*
G01Y497479D02*
X1281878Y498104D01*
G01X1281378Y499454D02*
X1281670Y499704D01*
X1281836Y500038D01*
X1281878Y500413D01*
X1281836Y500746D01*
X1281628Y501079D01*
X1281378Y501288D01*
X1281128Y501329D01*
X1280836Y501246D01*
X1280628Y500954D01*
X1280545Y500663D01*
Y500288D01*
G01Y500663D02*
X1280420Y500913D01*
X1280211Y501121D01*
X1279961Y501204D01*
X1279711Y501121D01*
X1279503Y500913D01*
X1279378Y500538D01*
X1279420Y500163D01*
X1279586Y499788D01*
G01X1281878Y503471D02*
X1279378D01*
X1279878Y502971D01*
G01X1281878D02*
Y503971D01*
G01X1280836Y505779D02*
X1280545Y506071D01*
X1280378Y506321D01*
X1280295Y506654D01*
X1280378Y506946D01*
X1280545Y507154D01*
X1280795Y507321D01*
X1281086Y507363D01*
X1281336Y507321D01*
X1281586Y507154D01*
X1281795Y506904D01*
X1281878Y506613D01*
X1281795Y506279D01*
X1281545Y505988D01*
X1281170Y505821D01*
X1280753Y505779D01*
X1280211Y505863D01*
X1279920Y505988D01*
X1279628Y506196D01*
X1279420Y506488D01*
X1279378Y506779D01*
X1279461Y507071D01*
X1279670Y507279D01*
G01X1276878Y496438D02*
X1274378D01*
Y497479D01*
X1274503Y497813D01*
X1274670Y498021D01*
X1275003Y498104D01*
X1275336Y498021D01*
X1275545Y497771D01*
X1275670Y497479D01*
Y496438D01*
G01Y497479D02*
X1276878Y498104D01*
G01X1276378Y499454D02*
X1276670Y499704D01*
X1276836Y500038D01*
X1276878Y500413D01*
X1276836Y500746D01*
X1276628Y501079D01*
X1276378Y501288D01*
X1276128Y501329D01*
X1275836Y501246D01*
X1275628Y500954D01*
X1275545Y500663D01*
Y500288D01*
G01Y500663D02*
X1275420Y500913D01*
X1275211Y501121D01*
X1274961Y501204D01*
X1274711Y501121D01*
X1274503Y500913D01*
X1274378Y500538D01*
X1274420Y500163D01*
X1274586Y499788D01*
G01X1276878Y503471D02*
X1274378D01*
X1274878Y502971D01*
G01X1276878D02*
Y503971D01*
G01X1276503Y505654D02*
X1276711Y505904D01*
X1276836Y506196D01*
X1276878Y506571D01*
X1276795Y506946D01*
X1276628Y507238D01*
X1276336Y507446D01*
X1276003Y507488D01*
X1275670Y507404D01*
X1275461Y507196D01*
X1275295Y506904D01*
X1275253Y506613D01*
X1275295Y506321D01*
X1275461Y505946D01*
X1274378Y506071D01*
Y507196D01*
G01X1246778Y519963D02*
Y522463D01*
X1247819D01*
X1248153Y522338D01*
X1248361Y522171D01*
X1248444Y521838D01*
X1248361Y521505D01*
X1248111Y521296D01*
X1247819Y521171D01*
X1246778D01*
G01X1247819D02*
X1248444Y519963D01*
G01X1249794Y520338D02*
X1250044Y520130D01*
X1250336Y520005D01*
X1250711Y519963D01*
X1251086Y520046D01*
X1251378Y520213D01*
X1251586Y520505D01*
X1251628Y520838D01*
X1251544Y521171D01*
X1251336Y521380D01*
X1251044Y521546D01*
X1250753Y521588D01*
X1250461Y521546D01*
X1250086Y521380D01*
X1250211Y522463D01*
X1251336D01*
G01X1253019Y522046D02*
X1253269Y522296D01*
X1253561Y522421D01*
X1253894Y522463D01*
X1254311Y522380D01*
X1254603Y522171D01*
X1254686Y521921D01*
X1254644Y521671D01*
X1254478Y521463D01*
X1253644Y521046D01*
X1253269Y520755D01*
X1253019Y520338D01*
X1252936Y519963D01*
X1254686D01*
G01X1256828D02*
X1256911Y520505D01*
X1257036Y520963D01*
X1257203Y521380D01*
X1257411Y521838D01*
X1257744Y522463D01*
X1256078D01*
G01X1255461Y511463D02*
Y515463D01*
X1248061D01*
G01X1241324Y511432D02*
Y515432D01*
X1233924D01*
G01X1246258Y510151D02*
X1233258D01*
G01X1260367Y510150D02*
X1247367D01*
G01X1264793Y674248D02*
X1269843D01*
Y772948D01*
X1294493D01*
Y588548D01*
X1269843D01*
Y647248D01*
X1264793D01*
Y674248D01*
G01X1246545Y624940D02*
X1246295Y625065D01*
X1246003Y625148D01*
X1245670D01*
X1245295Y625023D01*
X1245003Y624815D01*
X1244795Y624565D01*
X1244628Y624148D01*
X1244586Y623773D01*
X1244670Y623398D01*
X1244795Y623148D01*
X1245045Y622898D01*
X1245336Y622731D01*
X1245628Y622648D01*
X1245920D01*
X1246211Y622731D01*
X1246461Y622856D01*
X1246670Y623023D01*
G01X1247936Y624731D02*
X1248186Y624981D01*
X1248478Y625106D01*
X1248811Y625148D01*
X1249228Y625065D01*
X1249520Y624856D01*
X1249603Y624606D01*
X1249561Y624356D01*
X1249395Y624148D01*
X1248561Y623731D01*
X1248186Y623440D01*
X1247936Y623023D01*
X1247853Y622648D01*
X1249603D01*
G01X1251745D02*
X1251828Y623190D01*
X1251953Y623648D01*
X1252120Y624065D01*
X1252328Y624523D01*
X1252661Y625148D01*
X1250995D01*
G01X1254011Y623148D02*
X1254261Y622856D01*
X1254595Y622690D01*
X1254970Y622648D01*
X1255303Y622690D01*
X1255636Y622898D01*
X1255845Y623148D01*
X1255886Y623398D01*
X1255803Y623690D01*
X1255511Y623898D01*
X1255220Y623981D01*
X1254845D01*
G01X1255220D02*
X1255470Y624106D01*
X1255678Y624315D01*
X1255761Y624565D01*
X1255678Y624815D01*
X1255470Y625023D01*
X1255095Y625148D01*
X1254720Y625106D01*
X1254345Y624940D01*
G01X1246767Y628792D02*
X1246517Y628917D01*
X1246225Y629000D01*
X1245892D01*
X1245517Y628875D01*
X1245225Y628667D01*
X1245017Y628417D01*
X1244850Y628000D01*
X1244808Y627625D01*
X1244892Y627250D01*
X1245017Y627000D01*
X1245267Y626750D01*
X1245558Y626583D01*
X1245850Y626500D01*
X1246142D01*
X1246433Y626583D01*
X1246683Y626708D01*
X1246892Y626875D01*
G01X1248158Y628583D02*
X1248408Y628833D01*
X1248700Y628958D01*
X1249033Y629000D01*
X1249450Y628917D01*
X1249742Y628708D01*
X1249825Y628458D01*
X1249783Y628208D01*
X1249617Y628000D01*
X1248783Y627583D01*
X1248408Y627292D01*
X1248158Y626875D01*
X1248075Y626500D01*
X1249825D01*
G01X1251967D02*
X1252050Y627042D01*
X1252175Y627500D01*
X1252342Y627917D01*
X1252550Y628375D01*
X1252883Y629000D01*
X1251217D01*
G01X1254358Y628583D02*
X1254608Y628833D01*
X1254900Y628958D01*
X1255233Y629000D01*
X1255650Y628917D01*
X1255942Y628708D01*
X1256025Y628458D01*
X1255983Y628208D01*
X1255817Y628000D01*
X1254983Y627583D01*
X1254608Y627292D01*
X1254358Y626875D01*
X1254275Y626500D01*
X1256025D01*
G01X1260200Y695850D02*
Y699850D01*
X1252800D01*
G01X1237767Y694209D02*
X1237517Y694334D01*
X1237225Y694417D01*
X1236892D01*
X1236517Y694292D01*
X1236225Y694084D01*
X1236017Y693834D01*
X1235850Y693417D01*
X1235808Y693042D01*
X1235892Y692667D01*
X1236017Y692417D01*
X1236267Y692167D01*
X1236558Y692000D01*
X1236850Y691917D01*
X1237142D01*
X1237433Y692000D01*
X1237683Y692125D01*
X1237892Y692292D01*
G01X1239158Y694000D02*
X1239408Y694250D01*
X1239700Y694375D01*
X1240033Y694417D01*
X1240450Y694334D01*
X1240742Y694125D01*
X1240825Y693875D01*
X1240783Y693625D01*
X1240617Y693417D01*
X1239783Y693000D01*
X1239408Y692709D01*
X1239158Y692292D01*
X1239075Y691917D01*
X1240825D01*
G01X1242967D02*
X1243050Y692459D01*
X1243175Y692917D01*
X1243342Y693334D01*
X1243550Y693792D01*
X1243883Y694417D01*
X1242217D01*
G01X1245442Y692209D02*
X1245733Y692000D01*
X1246067Y691917D01*
X1246400Y692000D01*
X1246692Y692250D01*
X1246900Y692625D01*
X1246983Y693000D01*
Y693459D01*
X1246900Y693834D01*
X1246692Y694167D01*
X1246442Y694334D01*
X1246150Y694417D01*
X1245817Y694334D01*
X1245567Y694167D01*
X1245400Y693917D01*
X1245317Y693584D01*
X1245400Y693292D01*
X1245608Y693000D01*
X1245858Y692834D01*
X1246150Y692792D01*
X1246483Y692875D01*
X1246733Y693084D01*
X1246983Y693459D01*
G01X1236517Y697150D02*
Y699650D01*
X1237558D01*
X1237892Y699525D01*
X1238100Y699358D01*
X1238183Y699025D01*
X1238100Y698692D01*
X1237850Y698483D01*
X1237558Y698358D01*
X1236517D01*
G01X1237558D02*
X1238183Y697150D01*
G01X1239533Y697525D02*
X1239783Y697317D01*
X1240075Y697192D01*
X1240450Y697150D01*
X1240825Y697233D01*
X1241117Y697400D01*
X1241325Y697692D01*
X1241367Y698025D01*
X1241283Y698358D01*
X1241075Y698567D01*
X1240783Y698733D01*
X1240492Y698775D01*
X1240200Y698733D01*
X1239825Y698567D01*
X1239950Y699650D01*
X1241075D01*
G01X1244050Y697150D02*
Y699650D01*
X1242508Y697858D01*
X1244592D01*
G01X1247150Y697150D02*
Y699650D01*
X1245608Y697858D01*
X1247692D01*
G01X1239350Y724166D02*
Y721666D01*
G01X1238392Y724166D02*
X1240308D01*
G01X1241617Y721666D02*
Y724166D01*
X1242617D01*
X1242950Y724041D01*
X1243200Y723749D01*
X1243283Y723416D01*
X1243200Y723083D01*
X1242992Y722833D01*
X1242617Y722708D01*
X1241617D01*
G01X1244842Y721958D02*
X1245133Y721749D01*
X1245467Y721666D01*
X1245800Y721749D01*
X1246092Y721999D01*
X1246300Y722374D01*
X1246383Y722749D01*
Y723208D01*
X1246300Y723583D01*
X1246092Y723916D01*
X1245842Y724083D01*
X1245550Y724166D01*
X1245217Y724083D01*
X1244967Y723916D01*
X1244800Y723666D01*
X1244717Y723333D01*
X1244800Y723041D01*
X1245008Y722749D01*
X1245258Y722583D01*
X1245550Y722541D01*
X1245883Y722624D01*
X1246133Y722833D01*
X1246383Y723208D01*
G01X1247858Y723749D02*
X1248108Y723999D01*
X1248400Y724124D01*
X1248733Y724166D01*
X1249150Y724083D01*
X1249442Y723874D01*
X1249525Y723624D01*
X1249483Y723374D01*
X1249317Y723166D01*
X1248483Y722749D01*
X1248108Y722458D01*
X1247858Y722041D01*
X1247775Y721666D01*
X1249525D01*
G01X1234517Y707417D02*
Y709917D01*
X1235558D01*
X1235892Y709792D01*
X1236100Y709625D01*
X1236183Y709292D01*
X1236100Y708959D01*
X1235850Y708750D01*
X1235558Y708625D01*
X1234517D01*
G01X1235558D02*
X1236183Y707417D01*
G01X1237533Y707792D02*
X1237783Y707584D01*
X1238075Y707459D01*
X1238450Y707417D01*
X1238825Y707500D01*
X1239117Y707667D01*
X1239325Y707959D01*
X1239367Y708292D01*
X1239283Y708625D01*
X1239075Y708834D01*
X1238783Y709000D01*
X1238492Y709042D01*
X1238200Y709000D01*
X1237825Y708834D01*
X1237950Y709917D01*
X1239075D01*
G01X1242050Y707417D02*
Y709917D01*
X1240508Y708125D01*
X1242592D01*
G01X1244650Y707417D02*
X1244942Y707459D01*
X1245275Y707584D01*
X1245483Y707792D01*
X1245567Y708084D01*
X1245483Y708375D01*
X1245233Y708625D01*
X1244858Y708750D01*
X1244442D01*
X1244192Y708834D01*
X1243983Y709042D01*
X1243900Y709334D01*
X1244025Y709625D01*
X1244317Y709834D01*
X1244650Y709917D01*
X1244983Y709834D01*
X1245275Y709625D01*
X1245400Y709334D01*
X1245317Y709042D01*
X1245108Y708834D01*
X1244858Y708750D01*
X1244442D01*
X1244067Y708625D01*
X1243817Y708375D01*
X1243733Y708084D01*
X1243817Y707792D01*
X1244025Y707584D01*
X1244358Y707459D01*
X1244650Y707417D01*
G01X1272468Y779748D02*
Y782248D01*
G01X1274218D02*
Y779748D01*
G01Y780998D02*
X1272468D01*
G01X1275526Y779748D02*
Y782248D01*
X1276360D01*
X1276693Y782123D01*
X1276943Y781956D01*
X1277151Y781706D01*
X1277318Y781415D01*
X1277360Y780998D01*
X1277318Y780581D01*
X1277151Y780290D01*
X1276943Y780040D01*
X1276693Y779873D01*
X1276360Y779748D01*
X1275526D01*
G01X1278626D02*
Y782248D01*
X1279460D01*
X1279793Y782123D01*
X1280043Y781956D01*
X1280251Y781706D01*
X1280418Y781415D01*
X1280460Y780998D01*
X1280418Y780581D01*
X1280251Y780290D01*
X1280043Y780040D01*
X1279793Y779873D01*
X1279460Y779748D01*
X1278626D01*
G01X1281768Y780081D02*
X1282101Y779873D01*
X1282476Y779748D01*
X1282810D01*
X1283143Y779873D01*
X1283393Y780081D01*
X1283518Y780373D01*
X1283435Y780665D01*
X1283226Y780915D01*
X1282851Y781081D01*
X1282351Y781165D01*
X1282060Y781331D01*
X1281935Y781623D01*
X1282018Y781915D01*
X1282226Y782123D01*
X1282518Y782248D01*
X1282810D01*
X1283101Y782165D01*
X1283351Y781956D01*
G01X1284701Y779748D02*
X1285743Y782248D01*
X1286785Y779748D01*
G01X1286410Y780623D02*
X1285076D01*
G01X1287968Y780081D02*
X1288301Y779873D01*
X1288676Y779748D01*
X1289010D01*
X1289343Y779873D01*
X1289593Y780081D01*
X1289718Y780373D01*
X1289635Y780665D01*
X1289426Y780915D01*
X1289051Y781081D01*
X1288551Y781165D01*
X1288260Y781331D01*
X1288135Y781623D01*
X1288218Y781915D01*
X1288426Y782123D01*
X1288718Y782248D01*
X1289010D01*
X1289301Y782165D01*
X1289551Y781956D01*
G01X1291943Y779748D02*
Y782248D01*
X1291443Y781748D01*
G01Y779748D02*
X1292443D01*
G01X1295043D02*
X1295335Y779790D01*
X1295668Y779915D01*
X1295876Y780123D01*
X1295960Y780415D01*
X1295876Y780706D01*
X1295626Y780956D01*
X1295251Y781081D01*
X1294835D01*
X1294585Y781165D01*
X1294376Y781373D01*
X1294293Y781665D01*
X1294418Y781956D01*
X1294710Y782165D01*
X1295043Y782248D01*
X1295376Y782165D01*
X1295668Y781956D01*
X1295793Y781665D01*
X1295710Y781373D01*
X1295501Y781165D01*
X1295251Y781081D01*
X1294835D01*
X1294460Y780956D01*
X1294210Y780706D01*
X1294126Y780415D01*
X1294210Y780123D01*
X1294418Y779915D01*
X1294751Y779790D01*
X1295043Y779748D01*
G01X1233756Y837409D02*
Y839909D01*
X1235340D01*
G01X1234756Y838701D02*
X1233756D01*
G01X1236815Y839909D02*
Y837409D01*
X1238481D01*
G01X1241581D02*
X1239915D01*
Y839909D01*
X1241581D01*
G01X1240915Y838701D02*
X1239915D01*
G01X1242931Y837409D02*
Y839909D01*
X1243765D01*
X1244098Y839784D01*
X1244348Y839617D01*
X1244556Y839367D01*
X1244723Y839076D01*
X1244765Y838659D01*
X1244723Y838242D01*
X1244556Y837951D01*
X1244348Y837701D01*
X1244098Y837534D01*
X1243765Y837409D01*
X1242931D01*
G01X1246865D02*
X1246948Y837951D01*
X1247073Y838409D01*
X1247240Y838826D01*
X1247448Y839284D01*
X1247781Y839909D01*
X1246115D01*
G01X1236348Y818809D02*
Y830009D01*
X1245148D01*
Y818809D01*
X1236348D01*
G01X1247742Y972504D02*
Y975004D01*
X1248783D01*
X1249117Y974879D01*
X1249325Y974712D01*
X1249408Y974379D01*
X1249325Y974046D01*
X1249075Y973837D01*
X1248783Y973712D01*
X1247742D01*
G01X1248783D02*
X1249408Y972504D01*
G01X1252175D02*
Y975004D01*
X1250633Y973212D01*
X1252717D01*
G01X1254692Y972504D02*
X1254775Y973046D01*
X1254900Y973504D01*
X1255067Y973921D01*
X1255275Y974379D01*
X1255608Y975004D01*
X1253942D01*
G01X1257875Y972504D02*
X1258167Y972546D01*
X1258500Y972671D01*
X1258708Y972879D01*
X1258792Y973171D01*
X1258708Y973462D01*
X1258458Y973712D01*
X1258083Y973837D01*
X1257667D01*
X1257417Y973921D01*
X1257208Y974129D01*
X1257125Y974421D01*
X1257250Y974712D01*
X1257542Y974921D01*
X1257875Y975004D01*
X1258208Y974921D01*
X1258500Y974712D01*
X1258625Y974421D01*
X1258542Y974129D01*
X1258333Y973921D01*
X1258083Y973837D01*
X1257667D01*
X1257292Y973712D01*
X1257042Y973462D01*
X1256958Y973171D01*
X1257042Y972879D01*
X1257250Y972671D01*
X1257583Y972546D01*
X1257875Y972504D01*
G01X1255925Y964004D02*
Y968004D01*
X1248525D01*
G01X1241776Y963973D02*
Y967973D01*
X1234376D01*
G01X1234572Y944192D02*
X1234239Y944234D01*
X1233947Y944400D01*
X1233697Y944650D01*
X1233530Y944942D01*
X1233447Y945275D01*
Y945609D01*
X1233530Y945942D01*
X1233697Y946234D01*
X1233947Y946484D01*
X1234239Y946650D01*
X1234572Y946692D01*
X1234905Y946650D01*
X1235197Y946484D01*
X1235447Y946234D01*
X1235614Y945942D01*
X1235697Y945609D01*
Y945275D01*
X1235614Y944942D01*
X1235447Y944650D01*
X1235197Y944400D01*
X1234905Y944234D01*
X1234572Y944192D01*
G01X1234905Y944859D02*
X1235405Y944192D01*
G01X1236880Y946275D02*
X1237130Y946525D01*
X1237422Y946650D01*
X1237755Y946692D01*
X1238172Y946609D01*
X1238464Y946400D01*
X1238547Y946150D01*
X1238505Y945900D01*
X1238339Y945692D01*
X1237505Y945275D01*
X1237130Y944984D01*
X1236880Y944567D01*
X1236797Y944192D01*
X1238547D01*
G01X1239980Y945234D02*
X1240272Y945525D01*
X1240522Y945692D01*
X1240855Y945775D01*
X1241147Y945692D01*
X1241355Y945525D01*
X1241522Y945275D01*
X1241564Y944984D01*
X1241522Y944734D01*
X1241355Y944484D01*
X1241105Y944275D01*
X1240814Y944192D01*
X1240480Y944275D01*
X1240189Y944525D01*
X1240022Y944900D01*
X1239980Y945317D01*
X1240064Y945859D01*
X1240189Y946150D01*
X1240397Y946442D01*
X1240689Y946650D01*
X1240980Y946692D01*
X1241272Y946609D01*
X1241480Y946400D01*
G01X1243164Y944484D02*
X1243455Y944275D01*
X1243789Y944192D01*
X1244122Y944275D01*
X1244414Y944525D01*
X1244622Y944900D01*
X1244705Y945275D01*
Y945734D01*
X1244622Y946109D01*
X1244414Y946442D01*
X1244164Y946609D01*
X1243872Y946692D01*
X1243539Y946609D01*
X1243289Y946442D01*
X1243122Y946192D01*
X1243039Y945859D01*
X1243122Y945567D01*
X1243330Y945275D01*
X1243580Y945109D01*
X1243872Y945067D01*
X1244205Y945150D01*
X1244455Y945359D01*
X1244705Y945734D01*
G01X1246722Y948692D02*
Y962692D01*
G01X1233722Y948692D02*
X1246722D01*
G01X1233722Y962692D02*
Y948692D01*
G01X1246722Y962692D02*
X1233722D01*
G01X1248681Y944191D02*
X1248348Y944233D01*
X1248056Y944399D01*
X1247806Y944649D01*
X1247639Y944941D01*
X1247556Y945274D01*
Y945608D01*
X1247639Y945941D01*
X1247806Y946233D01*
X1248056Y946483D01*
X1248348Y946649D01*
X1248681Y946691D01*
X1249014Y946649D01*
X1249306Y946483D01*
X1249556Y946233D01*
X1249723Y945941D01*
X1249806Y945608D01*
Y945274D01*
X1249723Y944941D01*
X1249556Y944649D01*
X1249306Y944399D01*
X1249014Y944233D01*
X1248681Y944191D01*
G01X1249014Y944858D02*
X1249514Y944191D01*
G01X1250989Y946274D02*
X1251239Y946524D01*
X1251531Y946649D01*
X1251864Y946691D01*
X1252281Y946608D01*
X1252573Y946399D01*
X1252656Y946149D01*
X1252614Y945899D01*
X1252448Y945691D01*
X1251614Y945274D01*
X1251239Y944983D01*
X1250989Y944566D01*
X1250906Y944191D01*
X1252656D01*
G01X1253964Y944691D02*
X1254214Y944399D01*
X1254548Y944233D01*
X1254923Y944191D01*
X1255256Y944233D01*
X1255589Y944441D01*
X1255798Y944691D01*
X1255839Y944941D01*
X1255756Y945233D01*
X1255464Y945441D01*
X1255173Y945524D01*
X1254798D01*
G01X1255173D02*
X1255423Y945649D01*
X1255631Y945858D01*
X1255714Y946108D01*
X1255631Y946358D01*
X1255423Y946566D01*
X1255048Y946691D01*
X1254673Y946649D01*
X1254298Y946483D01*
G01X1257064Y944691D02*
X1257314Y944399D01*
X1257648Y944233D01*
X1258023Y944191D01*
X1258356Y944233D01*
X1258689Y944441D01*
X1258898Y944691D01*
X1258939Y944941D01*
X1258856Y945233D01*
X1258564Y945441D01*
X1258273Y945524D01*
X1257898D01*
G01X1258273D02*
X1258523Y945649D01*
X1258731Y945858D01*
X1258814Y946108D01*
X1258731Y946358D01*
X1258523Y946566D01*
X1258148Y946691D01*
X1257773Y946649D01*
X1257398Y946483D01*
G01X1260831Y948691D02*
Y962691D01*
G01X1247831Y948691D02*
X1260831D01*
G01X1247831Y962691D02*
Y948691D01*
G01X1260831Y962691D02*
X1247831D01*
G01X1281242Y948103D02*
X1278742D01*
Y949144D01*
X1278867Y949478D01*
X1279034Y949686D01*
X1279367Y949769D01*
X1279700Y949686D01*
X1279909Y949436D01*
X1280034Y949144D01*
Y948103D01*
G01Y949144D02*
X1281242Y949769D01*
G01X1279159Y951244D02*
X1278909Y951494D01*
X1278784Y951786D01*
X1278742Y952119D01*
X1278825Y952536D01*
X1279034Y952828D01*
X1279284Y952911D01*
X1279534Y952869D01*
X1279742Y952703D01*
X1280159Y951869D01*
X1280450Y951494D01*
X1280867Y951244D01*
X1281242Y951161D01*
Y952911D01*
G01Y955636D02*
X1278742D01*
X1280534Y954094D01*
Y956178D01*
G01X1279159Y957444D02*
X1278909Y957694D01*
X1278784Y957986D01*
X1278742Y958319D01*
X1278825Y958736D01*
X1279034Y959028D01*
X1279284Y959111D01*
X1279534Y959069D01*
X1279742Y958903D01*
X1280159Y958069D01*
X1280450Y957694D01*
X1280867Y957444D01*
X1281242Y957361D01*
Y959111D01*
G01X1276242Y948103D02*
X1273742D01*
Y949144D01*
X1273867Y949478D01*
X1274034Y949686D01*
X1274367Y949769D01*
X1274700Y949686D01*
X1274909Y949436D01*
X1275034Y949144D01*
Y948103D01*
G01Y949144D02*
X1276242Y949769D01*
G01X1274159Y951244D02*
X1273909Y951494D01*
X1273784Y951786D01*
X1273742Y952119D01*
X1273825Y952536D01*
X1274034Y952828D01*
X1274284Y952911D01*
X1274534Y952869D01*
X1274742Y952703D01*
X1275159Y951869D01*
X1275450Y951494D01*
X1275867Y951244D01*
X1276242Y951161D01*
Y952911D01*
G01Y955636D02*
X1273742D01*
X1275534Y954094D01*
Y956178D01*
G01X1276242Y958236D02*
X1273742D01*
X1274242Y957736D01*
G01X1276242D02*
Y958736D01*
G01X1264793Y1127004D02*
X1269843D01*
Y1225704D01*
X1294493D01*
Y1041304D01*
X1269843D01*
Y1100004D01*
X1264793D01*
Y1127004D01*
G01X1246045Y1077196D02*
X1245795Y1077321D01*
X1245503Y1077404D01*
X1245170D01*
X1244795Y1077279D01*
X1244503Y1077071D01*
X1244295Y1076821D01*
X1244128Y1076404D01*
X1244086Y1076029D01*
X1244170Y1075654D01*
X1244295Y1075404D01*
X1244545Y1075154D01*
X1244836Y1074987D01*
X1245128Y1074904D01*
X1245420D01*
X1245711Y1074987D01*
X1245961Y1075112D01*
X1246170Y1075279D01*
G01X1248228Y1074904D02*
Y1077404D01*
X1247728Y1076904D01*
G01Y1074904D02*
X1248728D01*
G01X1251328D02*
Y1077404D01*
X1250828Y1076904D01*
G01Y1074904D02*
X1251828D01*
G01X1254345D02*
X1254428Y1075446D01*
X1254553Y1075904D01*
X1254720Y1076321D01*
X1254928Y1076779D01*
X1255261Y1077404D01*
X1253595D01*
G01X1245767Y1081292D02*
X1245517Y1081417D01*
X1245225Y1081500D01*
X1244892D01*
X1244517Y1081375D01*
X1244225Y1081167D01*
X1244017Y1080917D01*
X1243850Y1080500D01*
X1243808Y1080125D01*
X1243892Y1079750D01*
X1244017Y1079500D01*
X1244267Y1079250D01*
X1244558Y1079083D01*
X1244850Y1079000D01*
X1245142D01*
X1245433Y1079083D01*
X1245683Y1079208D01*
X1245892Y1079375D01*
G01X1247950Y1079000D02*
Y1081500D01*
X1247450Y1081000D01*
G01Y1079000D02*
X1248450D01*
G01X1251050D02*
Y1081500D01*
X1250550Y1081000D01*
G01Y1079000D02*
X1251550D01*
G01X1253358Y1080042D02*
X1253650Y1080333D01*
X1253900Y1080500D01*
X1254233Y1080583D01*
X1254525Y1080500D01*
X1254733Y1080333D01*
X1254900Y1080083D01*
X1254942Y1079792D01*
X1254900Y1079542D01*
X1254733Y1079292D01*
X1254483Y1079083D01*
X1254192Y1079000D01*
X1253858Y1079083D01*
X1253567Y1079333D01*
X1253400Y1079708D01*
X1253358Y1080125D01*
X1253442Y1080667D01*
X1253567Y1080958D01*
X1253775Y1081250D01*
X1254067Y1081458D01*
X1254358Y1081500D01*
X1254650Y1081417D01*
X1254858Y1081208D01*
G01X1256017Y1140827D02*
Y1143327D01*
X1257058D01*
X1257392Y1143202D01*
X1257600Y1143035D01*
X1257683Y1142702D01*
X1257600Y1142369D01*
X1257350Y1142160D01*
X1257058Y1142035D01*
X1256017D01*
G01X1257058D02*
X1257683Y1140827D01*
G01X1259158Y1142910D02*
X1259408Y1143160D01*
X1259700Y1143285D01*
X1260033Y1143327D01*
X1260450Y1143244D01*
X1260742Y1143035D01*
X1260825Y1142785D01*
X1260783Y1142535D01*
X1260617Y1142327D01*
X1259783Y1141910D01*
X1259408Y1141619D01*
X1259158Y1141202D01*
X1259075Y1140827D01*
X1260825D01*
G01X1262967D02*
X1263050Y1141369D01*
X1263175Y1141827D01*
X1263342Y1142244D01*
X1263550Y1142702D01*
X1263883Y1143327D01*
X1262217D01*
G01X1266150D02*
X1265817Y1143244D01*
X1265567Y1143035D01*
X1265400Y1142785D01*
X1265275Y1142452D01*
X1265233Y1142077D01*
X1265275Y1141702D01*
X1265400Y1141369D01*
X1265567Y1141119D01*
X1265817Y1140910D01*
X1266150Y1140827D01*
X1266483Y1140910D01*
X1266733Y1141119D01*
X1266900Y1141369D01*
X1267025Y1141702D01*
X1267067Y1142077D01*
X1267025Y1142452D01*
X1266900Y1142785D01*
X1266733Y1143035D01*
X1266483Y1143244D01*
X1266150Y1143327D01*
G01X1260200Y1148173D02*
Y1152173D01*
X1252800D01*
G01X1236081Y1135413D02*
Y1137913D01*
X1237122D01*
X1237456Y1137788D01*
X1237664Y1137621D01*
X1237747Y1137288D01*
X1237664Y1136955D01*
X1237414Y1136746D01*
X1237122Y1136621D01*
X1236081D01*
G01X1237122D02*
X1237747Y1135413D01*
G01X1239097Y1135788D02*
X1239347Y1135580D01*
X1239639Y1135455D01*
X1240014Y1135413D01*
X1240389Y1135496D01*
X1240681Y1135663D01*
X1240889Y1135955D01*
X1240931Y1136288D01*
X1240847Y1136621D01*
X1240639Y1136830D01*
X1240347Y1136996D01*
X1240056Y1137038D01*
X1239764Y1136996D01*
X1239389Y1136830D01*
X1239514Y1137913D01*
X1240639D01*
G01X1243031Y1135413D02*
X1243114Y1135955D01*
X1243239Y1136413D01*
X1243406Y1136830D01*
X1243614Y1137288D01*
X1243947Y1137913D01*
X1242281D01*
G01X1245422Y1136455D02*
X1245714Y1136746D01*
X1245964Y1136913D01*
X1246297Y1136996D01*
X1246589Y1136913D01*
X1246797Y1136746D01*
X1246964Y1136496D01*
X1247006Y1136205D01*
X1246964Y1135955D01*
X1246797Y1135705D01*
X1246547Y1135496D01*
X1246256Y1135413D01*
X1245922Y1135496D01*
X1245631Y1135746D01*
X1245464Y1136121D01*
X1245422Y1136538D01*
X1245506Y1137080D01*
X1245631Y1137371D01*
X1245839Y1137663D01*
X1246131Y1137871D01*
X1246422Y1137913D01*
X1246714Y1137830D01*
X1246922Y1137621D01*
G01X1238364Y1147413D02*
Y1143413D01*
X1245764D01*
G01X1235295Y1166114D02*
X1234962Y1166156D01*
X1234670Y1166322D01*
X1234420Y1166572D01*
X1234253Y1166864D01*
X1234170Y1167197D01*
Y1167531D01*
X1234253Y1167864D01*
X1234420Y1168156D01*
X1234670Y1168406D01*
X1234962Y1168572D01*
X1235295Y1168614D01*
X1235628Y1168572D01*
X1235920Y1168406D01*
X1236170Y1168156D01*
X1236337Y1167864D01*
X1236420Y1167531D01*
Y1167197D01*
X1236337Y1166864D01*
X1236170Y1166572D01*
X1235920Y1166322D01*
X1235628Y1166156D01*
X1235295Y1166114D01*
G01X1235628Y1166781D02*
X1236128Y1166114D01*
G01X1237603Y1168197D02*
X1237853Y1168447D01*
X1238145Y1168572D01*
X1238478Y1168614D01*
X1238895Y1168531D01*
X1239187Y1168322D01*
X1239270Y1168072D01*
X1239228Y1167822D01*
X1239062Y1167614D01*
X1238228Y1167197D01*
X1237853Y1166906D01*
X1237603Y1166489D01*
X1237520Y1166114D01*
X1239270D01*
G01X1240787Y1166406D02*
X1241078Y1166197D01*
X1241412Y1166114D01*
X1241745Y1166197D01*
X1242037Y1166447D01*
X1242245Y1166822D01*
X1242328Y1167197D01*
Y1167656D01*
X1242245Y1168031D01*
X1242037Y1168364D01*
X1241787Y1168531D01*
X1241495Y1168614D01*
X1241162Y1168531D01*
X1240912Y1168364D01*
X1240745Y1168114D01*
X1240662Y1167781D01*
X1240745Y1167489D01*
X1240953Y1167197D01*
X1241203Y1167031D01*
X1241495Y1166989D01*
X1241828Y1167072D01*
X1242078Y1167281D01*
X1242328Y1167656D01*
G01X1243678Y1166614D02*
X1243928Y1166322D01*
X1244262Y1166156D01*
X1244637Y1166114D01*
X1244970Y1166156D01*
X1245303Y1166364D01*
X1245512Y1166614D01*
X1245553Y1166864D01*
X1245470Y1167156D01*
X1245178Y1167364D01*
X1244887Y1167447D01*
X1244512D01*
G01X1244887D02*
X1245137Y1167572D01*
X1245345Y1167781D01*
X1245428Y1168031D01*
X1245345Y1168281D01*
X1245137Y1168489D01*
X1244762Y1168614D01*
X1244387Y1168572D01*
X1244012Y1168406D01*
G01X1233445Y1164114D02*
Y1150114D01*
G01X1246445Y1164114D02*
X1233445D01*
G01X1246445Y1150114D02*
Y1164114D01*
G01X1233445Y1150114D02*
X1246445D01*
G01X1239350Y1178166D02*
Y1175666D01*
G01X1238392Y1178166D02*
X1240308D01*
G01X1241617Y1175666D02*
Y1178166D01*
X1242617D01*
X1242950Y1178041D01*
X1243200Y1177749D01*
X1243283Y1177416D01*
X1243200Y1177083D01*
X1242992Y1176833D01*
X1242617Y1176708D01*
X1241617D01*
G01X1244633Y1176166D02*
X1244883Y1175874D01*
X1245217Y1175708D01*
X1245592Y1175666D01*
X1245925Y1175708D01*
X1246258Y1175916D01*
X1246467Y1176166D01*
X1246508Y1176416D01*
X1246425Y1176708D01*
X1246133Y1176916D01*
X1245842Y1176999D01*
X1245467D01*
G01X1245842D02*
X1246092Y1177124D01*
X1246300Y1177333D01*
X1246383Y1177583D01*
X1246300Y1177833D01*
X1246092Y1178041D01*
X1245717Y1178166D01*
X1245342Y1178124D01*
X1244967Y1177958D01*
G01X1247858Y1177749D02*
X1248108Y1177999D01*
X1248400Y1178124D01*
X1248733Y1178166D01*
X1249150Y1178083D01*
X1249442Y1177874D01*
X1249525Y1177624D01*
X1249483Y1177374D01*
X1249317Y1177166D01*
X1248483Y1176749D01*
X1248108Y1176458D01*
X1247858Y1176041D01*
X1247775Y1175666D01*
X1249525D01*
G01X1257017Y1164667D02*
Y1167167D01*
X1258058D01*
X1258392Y1167042D01*
X1258600Y1166875D01*
X1258683Y1166542D01*
X1258600Y1166209D01*
X1258350Y1166000D01*
X1258058Y1165875D01*
X1257017D01*
G01X1258058D02*
X1258683Y1164667D01*
G01X1260158Y1166750D02*
X1260408Y1167000D01*
X1260700Y1167125D01*
X1261033Y1167167D01*
X1261450Y1167084D01*
X1261742Y1166875D01*
X1261825Y1166625D01*
X1261783Y1166375D01*
X1261617Y1166167D01*
X1260783Y1165750D01*
X1260408Y1165459D01*
X1260158Y1165042D01*
X1260075Y1164667D01*
X1261825D01*
G01X1263967D02*
X1264050Y1165209D01*
X1264175Y1165667D01*
X1264342Y1166084D01*
X1264550Y1166542D01*
X1264883Y1167167D01*
X1263217D01*
G01X1266358Y1166750D02*
X1266608Y1167000D01*
X1266900Y1167125D01*
X1267233Y1167167D01*
X1267650Y1167084D01*
X1267942Y1166875D01*
X1268025Y1166625D01*
X1267983Y1166375D01*
X1267817Y1166167D01*
X1266983Y1165750D01*
X1266608Y1165459D01*
X1266358Y1165042D01*
X1266275Y1164667D01*
X1268025D01*
G01X1253267Y1138965D02*
X1253017Y1139090D01*
X1252725Y1139173D01*
X1252392D01*
X1252017Y1139048D01*
X1251725Y1138840D01*
X1251517Y1138590D01*
X1251350Y1138173D01*
X1251308Y1137798D01*
X1251392Y1137423D01*
X1251517Y1137173D01*
X1251767Y1136923D01*
X1252058Y1136756D01*
X1252350Y1136673D01*
X1252642D01*
X1252933Y1136756D01*
X1253183Y1136881D01*
X1253392Y1137048D01*
G01X1255450Y1136673D02*
Y1139173D01*
X1254950Y1138673D01*
G01Y1136673D02*
X1255950D01*
G01X1257758Y1138756D02*
X1258008Y1139006D01*
X1258300Y1139131D01*
X1258633Y1139173D01*
X1259050Y1139090D01*
X1259342Y1138881D01*
X1259425Y1138631D01*
X1259383Y1138381D01*
X1259217Y1138173D01*
X1258383Y1137756D01*
X1258008Y1137465D01*
X1257758Y1137048D01*
X1257675Y1136673D01*
X1259425D01*
G01X1262150D02*
Y1139173D01*
X1260608Y1137381D01*
X1262692D01*
G01X1271825Y1231500D02*
Y1234000D01*
G01X1273575D02*
Y1231500D01*
G01Y1232750D02*
X1271825D01*
G01X1274883Y1231500D02*
Y1234000D01*
X1275717D01*
X1276050Y1233875D01*
X1276300Y1233708D01*
X1276508Y1233458D01*
X1276675Y1233167D01*
X1276717Y1232750D01*
X1276675Y1232333D01*
X1276508Y1232042D01*
X1276300Y1231792D01*
X1276050Y1231625D01*
X1275717Y1231500D01*
X1274883D01*
G01X1277983D02*
Y1234000D01*
X1278817D01*
X1279150Y1233875D01*
X1279400Y1233708D01*
X1279608Y1233458D01*
X1279775Y1233167D01*
X1279817Y1232750D01*
X1279775Y1232333D01*
X1279608Y1232042D01*
X1279400Y1231792D01*
X1279150Y1231625D01*
X1278817Y1231500D01*
X1277983D01*
G01X1281125Y1231833D02*
X1281458Y1231625D01*
X1281833Y1231500D01*
X1282167D01*
X1282500Y1231625D01*
X1282750Y1231833D01*
X1282875Y1232125D01*
X1282792Y1232417D01*
X1282583Y1232667D01*
X1282208Y1232833D01*
X1281708Y1232917D01*
X1281417Y1233083D01*
X1281292Y1233375D01*
X1281375Y1233667D01*
X1281583Y1233875D01*
X1281875Y1234000D01*
X1282167D01*
X1282458Y1233917D01*
X1282708Y1233708D01*
G01X1284058Y1231500D02*
X1285100Y1234000D01*
X1286142Y1231500D01*
G01X1285767Y1232375D02*
X1284433D01*
G01X1287325Y1231833D02*
X1287658Y1231625D01*
X1288033Y1231500D01*
X1288367D01*
X1288700Y1231625D01*
X1288950Y1231833D01*
X1289075Y1232125D01*
X1288992Y1232417D01*
X1288783Y1232667D01*
X1288408Y1232833D01*
X1287908Y1232917D01*
X1287617Y1233083D01*
X1287492Y1233375D01*
X1287575Y1233667D01*
X1287783Y1233875D01*
X1288075Y1234000D01*
X1288367D01*
X1288658Y1233917D01*
X1288908Y1233708D01*
G01X1290508Y1232542D02*
X1290800Y1232833D01*
X1291050Y1233000D01*
X1291383Y1233083D01*
X1291675Y1233000D01*
X1291883Y1232833D01*
X1292050Y1232583D01*
X1292092Y1232292D01*
X1292050Y1232042D01*
X1291883Y1231792D01*
X1291633Y1231583D01*
X1291342Y1231500D01*
X1291008Y1231583D01*
X1290717Y1231833D01*
X1290550Y1232208D01*
X1290508Y1232625D01*
X1290592Y1233167D01*
X1290717Y1233458D01*
X1290925Y1233750D01*
X1291217Y1233958D01*
X1291508Y1234000D01*
X1291800Y1233917D01*
X1292008Y1233708D01*
G01X1236348Y1271565D02*
Y1282765D01*
X1245148D01*
Y1271565D01*
X1236348D01*
G01X1323295Y61679D02*
Y75079D01*
G01X1333295Y61679D02*
X1323295D01*
G01X1313708Y66317D02*
X1313583Y66067D01*
X1313500Y65775D01*
Y65442D01*
X1313625Y65067D01*
X1313833Y64775D01*
X1314083Y64567D01*
X1314500Y64400D01*
X1314875Y64358D01*
X1315250Y64442D01*
X1315500Y64567D01*
X1315750Y64817D01*
X1315917Y65108D01*
X1316000Y65400D01*
Y65692D01*
X1315917Y65983D01*
X1315792Y66233D01*
X1315625Y66442D01*
G01X1316000Y68500D02*
X1313500D01*
X1314000Y68000D01*
G01X1316000D02*
Y69000D01*
G01X1315708Y70892D02*
X1315917Y71183D01*
X1316000Y71517D01*
X1315917Y71850D01*
X1315667Y72142D01*
X1315292Y72350D01*
X1314917Y72433D01*
X1314458D01*
X1314083Y72350D01*
X1313750Y72142D01*
X1313583Y71892D01*
X1313500Y71600D01*
X1313583Y71267D01*
X1313750Y71017D01*
X1314000Y70850D01*
X1314333Y70767D01*
X1314625Y70850D01*
X1314917Y71058D01*
X1315083Y71308D01*
X1315125Y71600D01*
X1315042Y71933D01*
X1314833Y72183D01*
X1314458Y72433D01*
G01X1287784Y107800D02*
X1285284D01*
Y108841D01*
X1285409Y109175D01*
X1285576Y109383D01*
X1285909Y109466D01*
X1286242Y109383D01*
X1286451Y109133D01*
X1286576Y108841D01*
Y107800D01*
G01Y108841D02*
X1287784Y109466D01*
G01Y111733D02*
X1285284D01*
X1285784Y111233D01*
G01X1287784D02*
Y112233D01*
G01X1287284Y113916D02*
X1287576Y114166D01*
X1287742Y114500D01*
X1287784Y114875D01*
X1287742Y115208D01*
X1287534Y115541D01*
X1287284Y115750D01*
X1287034Y115791D01*
X1286742Y115708D01*
X1286534Y115416D01*
X1286451Y115125D01*
Y114750D01*
G01Y115125D02*
X1286326Y115375D01*
X1286117Y115583D01*
X1285867Y115666D01*
X1285617Y115583D01*
X1285409Y115375D01*
X1285284Y115000D01*
X1285326Y114625D01*
X1285492Y114250D01*
G01X1285284Y117933D02*
X1285367Y117600D01*
X1285576Y117350D01*
X1285826Y117183D01*
X1286159Y117058D01*
X1286534Y117016D01*
X1286909Y117058D01*
X1287242Y117183D01*
X1287492Y117350D01*
X1287701Y117600D01*
X1287784Y117933D01*
X1287701Y118266D01*
X1287492Y118516D01*
X1287242Y118683D01*
X1286909Y118808D01*
X1286534Y118850D01*
X1286159Y118808D01*
X1285826Y118683D01*
X1285576Y118516D01*
X1285367Y118266D01*
X1285284Y117933D01*
G01Y121033D02*
X1285367Y120700D01*
X1285576Y120450D01*
X1285826Y120283D01*
X1286159Y120158D01*
X1286534Y120116D01*
X1286909Y120158D01*
X1287242Y120283D01*
X1287492Y120450D01*
X1287701Y120700D01*
X1287784Y121033D01*
X1287701Y121366D01*
X1287492Y121616D01*
X1287242Y121783D01*
X1286909Y121908D01*
X1286534Y121950D01*
X1286159Y121908D01*
X1285826Y121783D01*
X1285576Y121616D01*
X1285367Y121366D01*
X1285284Y121033D01*
G01X1311521Y75022D02*
X1309021D01*
Y76063D01*
X1309146Y76397D01*
X1309313Y76605D01*
X1309646Y76688D01*
X1309979Y76605D01*
X1310188Y76355D01*
X1310313Y76063D01*
Y75022D01*
G01Y76063D02*
X1311521Y76688D01*
G01X1310479Y78163D02*
X1310188Y78455D01*
X1310021Y78705D01*
X1309938Y79038D01*
X1310021Y79330D01*
X1310188Y79538D01*
X1310438Y79705D01*
X1310729Y79747D01*
X1310979Y79705D01*
X1311229Y79538D01*
X1311438Y79288D01*
X1311521Y78997D01*
X1311438Y78663D01*
X1311188Y78372D01*
X1310813Y78205D01*
X1310396Y78163D01*
X1309854Y78247D01*
X1309563Y78372D01*
X1309271Y78580D01*
X1309063Y78872D01*
X1309021Y79163D01*
X1309104Y79455D01*
X1309313Y79663D01*
G01X1310479Y81263D02*
X1310188Y81555D01*
X1310021Y81805D01*
X1309938Y82138D01*
X1310021Y82430D01*
X1310188Y82638D01*
X1310438Y82805D01*
X1310729Y82847D01*
X1310979Y82805D01*
X1311229Y82638D01*
X1311438Y82388D01*
X1311521Y82097D01*
X1311438Y81763D01*
X1311188Y81472D01*
X1310813Y81305D01*
X1310396Y81263D01*
X1309854Y81347D01*
X1309563Y81472D01*
X1309271Y81680D01*
X1309063Y81972D01*
X1309021Y82263D01*
X1309104Y82555D01*
X1309313Y82763D01*
G01X1325521Y88155D02*
X1321521D01*
Y80755D01*
G01X1295784Y107800D02*
X1293284D01*
Y108841D01*
X1293409Y109175D01*
X1293576Y109383D01*
X1293909Y109466D01*
X1294242Y109383D01*
X1294451Y109133D01*
X1294576Y108841D01*
Y107800D01*
G01Y108841D02*
X1295784Y109466D01*
G01Y111650D02*
X1295242Y111733D01*
X1294784Y111858D01*
X1294367Y112025D01*
X1293909Y112233D01*
X1293284Y112566D01*
Y110900D01*
G01Y114833D02*
X1293367Y114500D01*
X1293576Y114250D01*
X1293826Y114083D01*
X1294159Y113958D01*
X1294534Y113916D01*
X1294909Y113958D01*
X1295242Y114083D01*
X1295492Y114250D01*
X1295701Y114500D01*
X1295784Y114833D01*
X1295701Y115166D01*
X1295492Y115416D01*
X1295242Y115583D01*
X1294909Y115708D01*
X1294534Y115750D01*
X1294159Y115708D01*
X1293826Y115583D01*
X1293576Y115416D01*
X1293367Y115166D01*
X1293284Y114833D01*
G01X1286567Y89167D02*
Y91667D01*
X1287608D01*
X1287942Y91542D01*
X1288150Y91375D01*
X1288233Y91042D01*
X1288150Y90709D01*
X1287900Y90500D01*
X1287608Y90375D01*
X1286567D01*
G01X1287608D02*
X1288233Y89167D01*
G01X1290417D02*
X1290500Y89709D01*
X1290625Y90167D01*
X1290792Y90584D01*
X1291000Y91042D01*
X1291333Y91667D01*
X1289667D01*
G01X1292683Y89542D02*
X1292933Y89334D01*
X1293225Y89209D01*
X1293600Y89167D01*
X1293975Y89250D01*
X1294267Y89417D01*
X1294475Y89709D01*
X1294517Y90042D01*
X1294433Y90375D01*
X1294225Y90584D01*
X1293933Y90750D01*
X1293642Y90792D01*
X1293350Y90750D01*
X1292975Y90584D01*
X1293100Y91667D01*
X1294225D01*
G01X1308621Y92855D02*
Y88855D01*
X1316021D01*
G01X1286567Y84667D02*
Y87167D01*
X1287608D01*
X1287942Y87042D01*
X1288150Y86875D01*
X1288233Y86542D01*
X1288150Y86209D01*
X1287900Y86000D01*
X1287608Y85875D01*
X1286567D01*
G01X1287608D02*
X1288233Y84667D01*
G01X1290417D02*
X1290500Y85209D01*
X1290625Y85667D01*
X1290792Y86084D01*
X1291000Y86542D01*
X1291333Y87167D01*
X1289667D01*
G01X1292892Y84959D02*
X1293183Y84750D01*
X1293517Y84667D01*
X1293850Y84750D01*
X1294142Y85000D01*
X1294350Y85375D01*
X1294433Y85750D01*
Y86209D01*
X1294350Y86584D01*
X1294142Y86917D01*
X1293892Y87084D01*
X1293600Y87167D01*
X1293267Y87084D01*
X1293017Y86917D01*
X1292850Y86667D01*
X1292767Y86334D01*
X1292850Y86042D01*
X1293058Y85750D01*
X1293308Y85584D01*
X1293600Y85542D01*
X1293933Y85625D01*
X1294183Y85834D01*
X1294433Y86209D01*
G01X1308621Y88155D02*
Y84155D01*
X1316021D01*
G01X1306821Y75022D02*
X1304321D01*
Y76063D01*
X1304446Y76397D01*
X1304613Y76605D01*
X1304946Y76688D01*
X1305279Y76605D01*
X1305488Y76355D01*
X1305613Y76063D01*
Y75022D01*
G01Y76063D02*
X1306821Y76688D01*
G01Y78955D02*
X1306779Y79247D01*
X1306654Y79580D01*
X1306446Y79788D01*
X1306154Y79872D01*
X1305863Y79788D01*
X1305613Y79538D01*
X1305488Y79163D01*
Y78747D01*
X1305404Y78497D01*
X1305196Y78288D01*
X1304904Y78205D01*
X1304613Y78330D01*
X1304404Y78622D01*
X1304321Y78955D01*
X1304404Y79288D01*
X1304613Y79580D01*
X1304904Y79705D01*
X1305196Y79622D01*
X1305404Y79413D01*
X1305488Y79163D01*
Y78747D01*
X1305613Y78372D01*
X1305863Y78122D01*
X1306154Y78038D01*
X1306446Y78122D01*
X1306654Y78330D01*
X1306779Y78663D01*
X1306821Y78955D01*
G01X1304321Y82055D02*
X1304404Y81722D01*
X1304613Y81472D01*
X1304863Y81305D01*
X1305196Y81180D01*
X1305571Y81138D01*
X1305946Y81180D01*
X1306279Y81305D01*
X1306529Y81472D01*
X1306738Y81722D01*
X1306821Y82055D01*
X1306738Y82388D01*
X1306529Y82638D01*
X1306279Y82805D01*
X1305946Y82930D01*
X1305571Y82972D01*
X1305196Y82930D01*
X1304863Y82805D01*
X1304613Y82638D01*
X1304404Y82388D01*
X1304321Y82055D01*
G01X1320821Y88155D02*
X1316821D01*
Y80755D01*
G01X1291784Y107800D02*
X1289284D01*
Y108841D01*
X1289409Y109175D01*
X1289576Y109383D01*
X1289909Y109466D01*
X1290242Y109383D01*
X1290451Y109133D01*
X1290576Y108841D01*
Y107800D01*
G01Y108841D02*
X1291784Y109466D01*
G01Y111733D02*
X1291742Y112025D01*
X1291617Y112358D01*
X1291409Y112566D01*
X1291117Y112650D01*
X1290826Y112566D01*
X1290576Y112316D01*
X1290451Y111941D01*
Y111525D01*
X1290367Y111275D01*
X1290159Y111066D01*
X1289867Y110983D01*
X1289576Y111108D01*
X1289367Y111400D01*
X1289284Y111733D01*
X1289367Y112066D01*
X1289576Y112358D01*
X1289867Y112483D01*
X1290159Y112400D01*
X1290367Y112191D01*
X1290451Y111941D01*
Y111525D01*
X1290576Y111150D01*
X1290826Y110900D01*
X1291117Y110816D01*
X1291409Y110900D01*
X1291617Y111108D01*
X1291742Y111441D01*
X1291784Y111733D01*
G01Y114750D02*
X1291242Y114833D01*
X1290784Y114958D01*
X1290367Y115125D01*
X1289909Y115333D01*
X1289284Y115666D01*
Y114000D01*
G01X1299784Y107800D02*
X1297284D01*
Y108841D01*
X1297409Y109175D01*
X1297576Y109383D01*
X1297909Y109466D01*
X1298242Y109383D01*
X1298451Y109133D01*
X1298576Y108841D01*
Y107800D01*
G01Y108841D02*
X1299784Y109466D01*
G01X1299492Y111025D02*
X1299701Y111316D01*
X1299784Y111650D01*
X1299701Y111983D01*
X1299451Y112275D01*
X1299076Y112483D01*
X1298701Y112566D01*
X1298242D01*
X1297867Y112483D01*
X1297534Y112275D01*
X1297367Y112025D01*
X1297284Y111733D01*
X1297367Y111400D01*
X1297534Y111150D01*
X1297784Y110983D01*
X1298117Y110900D01*
X1298409Y110983D01*
X1298701Y111191D01*
X1298867Y111441D01*
X1298909Y111733D01*
X1298826Y112066D01*
X1298617Y112316D01*
X1298242Y112566D01*
G01X1297701Y114041D02*
X1297451Y114291D01*
X1297326Y114583D01*
X1297284Y114916D01*
X1297367Y115333D01*
X1297576Y115625D01*
X1297826Y115708D01*
X1298076Y115666D01*
X1298284Y115500D01*
X1298701Y114666D01*
X1298992Y114291D01*
X1299409Y114041D01*
X1299784Y113958D01*
Y115708D01*
G01X1315921Y75022D02*
X1313421D01*
Y76063D01*
X1313546Y76397D01*
X1313713Y76605D01*
X1314046Y76688D01*
X1314379Y76605D01*
X1314588Y76355D01*
X1314713Y76063D01*
Y75022D01*
G01Y76063D02*
X1315921Y76688D01*
G01X1315629Y78247D02*
X1315838Y78538D01*
X1315921Y78872D01*
X1315838Y79205D01*
X1315588Y79497D01*
X1315213Y79705D01*
X1314838Y79788D01*
X1314379D01*
X1314004Y79705D01*
X1313671Y79497D01*
X1313504Y79247D01*
X1313421Y78955D01*
X1313504Y78622D01*
X1313671Y78372D01*
X1313921Y78205D01*
X1314254Y78122D01*
X1314546Y78205D01*
X1314838Y78413D01*
X1315004Y78663D01*
X1315046Y78955D01*
X1314963Y79288D01*
X1314754Y79538D01*
X1314379Y79788D01*
G01X1315629Y81347D02*
X1315838Y81638D01*
X1315921Y81972D01*
X1315838Y82305D01*
X1315588Y82597D01*
X1315213Y82805D01*
X1314838Y82888D01*
X1314379D01*
X1314004Y82805D01*
X1313671Y82597D01*
X1313504Y82347D01*
X1313421Y82055D01*
X1313504Y81722D01*
X1313671Y81472D01*
X1313921Y81305D01*
X1314254Y81222D01*
X1314546Y81305D01*
X1314838Y81513D01*
X1315004Y81763D01*
X1315046Y82055D01*
X1314963Y82388D01*
X1314754Y82638D01*
X1314379Y82888D01*
G01X1325921Y80755D02*
X1329921D01*
Y88155D01*
G01X1297569Y85491D02*
X1301569D01*
Y92891D01*
G01X1306563Y92958D02*
X1302563D01*
Y85558D01*
G01X1323295Y75079D02*
X1333295D01*
G01X1320471Y91735D02*
Y112735D01*
X1352121D01*
Y101735D01*
X1320471D01*
G01Y110385D02*
X1323621Y107235D01*
X1320471Y104085D01*
G01X1307042Y98817D02*
X1306917Y98567D01*
X1306834Y98275D01*
Y97942D01*
X1306959Y97567D01*
X1307167Y97275D01*
X1307417Y97067D01*
X1307834Y96900D01*
X1308209Y96858D01*
X1308584Y96942D01*
X1308834Y97067D01*
X1309084Y97317D01*
X1309251Y97608D01*
X1309334Y97900D01*
Y98192D01*
X1309251Y98483D01*
X1309126Y98733D01*
X1308959Y98942D01*
G01X1307251Y100208D02*
X1307001Y100458D01*
X1306876Y100750D01*
X1306834Y101083D01*
X1306917Y101500D01*
X1307126Y101792D01*
X1307376Y101875D01*
X1307626Y101833D01*
X1307834Y101667D01*
X1308251Y100833D01*
X1308542Y100458D01*
X1308959Y100208D01*
X1309334Y100125D01*
Y101875D01*
G01X1306834Y104100D02*
X1306917Y103767D01*
X1307126Y103517D01*
X1307376Y103350D01*
X1307709Y103225D01*
X1308084Y103183D01*
X1308459Y103225D01*
X1308792Y103350D01*
X1309042Y103517D01*
X1309251Y103767D01*
X1309334Y104100D01*
X1309251Y104433D01*
X1309042Y104683D01*
X1308792Y104850D01*
X1308459Y104975D01*
X1308084Y105017D01*
X1307709Y104975D01*
X1307376Y104850D01*
X1307126Y104683D01*
X1306917Y104433D01*
X1306834Y104100D01*
G01X1311042Y99317D02*
X1310917Y99067D01*
X1310834Y98775D01*
Y98442D01*
X1310959Y98067D01*
X1311167Y97775D01*
X1311417Y97567D01*
X1311834Y97400D01*
X1312209Y97358D01*
X1312584Y97442D01*
X1312834Y97567D01*
X1313084Y97817D01*
X1313251Y98108D01*
X1313334Y98400D01*
Y98692D01*
X1313251Y98983D01*
X1313126Y99233D01*
X1312959Y99442D01*
G01X1313334Y101500D02*
X1310834D01*
X1311334Y101000D01*
G01X1313334D02*
Y102000D01*
G01X1312292Y103808D02*
X1312001Y104100D01*
X1311834Y104350D01*
X1311751Y104683D01*
X1311834Y104975D01*
X1312001Y105183D01*
X1312251Y105350D01*
X1312542Y105392D01*
X1312792Y105350D01*
X1313042Y105183D01*
X1313251Y104933D01*
X1313334Y104642D01*
X1313251Y104308D01*
X1313001Y104017D01*
X1312626Y103850D01*
X1312209Y103808D01*
X1311667Y103892D01*
X1311376Y104017D01*
X1311084Y104225D01*
X1310876Y104517D01*
X1310834Y104808D01*
X1310917Y105100D01*
X1311126Y105308D01*
G01X1313115Y128400D02*
X1317115D01*
Y135800D01*
G01X1322207Y128403D02*
X1326207D01*
Y135803D01*
G01X1317797Y128388D02*
X1321797D01*
Y135788D01*
G01X1326534Y128388D02*
X1330534D01*
Y135788D01*
G01X1306834Y151517D02*
X1304334D01*
Y152558D01*
X1304459Y152892D01*
X1304626Y153100D01*
X1304959Y153183D01*
X1305292Y153100D01*
X1305501Y152850D01*
X1305626Y152558D01*
Y151517D01*
G01Y152558D02*
X1306834Y153183D01*
G01Y155450D02*
X1306792Y155742D01*
X1306667Y156075D01*
X1306459Y156283D01*
X1306167Y156367D01*
X1305876Y156283D01*
X1305626Y156033D01*
X1305501Y155658D01*
Y155242D01*
X1305417Y154992D01*
X1305209Y154783D01*
X1304917Y154700D01*
X1304626Y154825D01*
X1304417Y155117D01*
X1304334Y155450D01*
X1304417Y155783D01*
X1304626Y156075D01*
X1304917Y156200D01*
X1305209Y156117D01*
X1305417Y155908D01*
X1305501Y155658D01*
Y155242D01*
X1305626Y154867D01*
X1305876Y154617D01*
X1306167Y154533D01*
X1306459Y154617D01*
X1306667Y154825D01*
X1306792Y155158D01*
X1306834Y155450D01*
G01X1304751Y157758D02*
X1304501Y158008D01*
X1304376Y158300D01*
X1304334Y158633D01*
X1304417Y159050D01*
X1304626Y159342D01*
X1304876Y159425D01*
X1305126Y159383D01*
X1305334Y159217D01*
X1305751Y158383D01*
X1306042Y158008D01*
X1306459Y157758D01*
X1306834Y157675D01*
Y159425D01*
G01Y161650D02*
X1306792Y161942D01*
X1306667Y162275D01*
X1306459Y162483D01*
X1306167Y162567D01*
X1305876Y162483D01*
X1305626Y162233D01*
X1305501Y161858D01*
Y161442D01*
X1305417Y161192D01*
X1305209Y160983D01*
X1304917Y160900D01*
X1304626Y161025D01*
X1304417Y161317D01*
X1304334Y161650D01*
X1304417Y161983D01*
X1304626Y162275D01*
X1304917Y162400D01*
X1305209Y162317D01*
X1305417Y162108D01*
X1305501Y161858D01*
Y161442D01*
X1305626Y161067D01*
X1305876Y160817D01*
X1306167Y160733D01*
X1306459Y160817D01*
X1306667Y161025D01*
X1306792Y161358D01*
X1306834Y161650D01*
G01X1310000Y163961D02*
X1314000D01*
Y171361D01*
G01X1320000Y163961D02*
X1324000D01*
Y171361D01*
G01X1301834Y151517D02*
X1299334D01*
Y152558D01*
X1299459Y152892D01*
X1299626Y153100D01*
X1299959Y153183D01*
X1300292Y153100D01*
X1300501Y152850D01*
X1300626Y152558D01*
Y151517D01*
G01Y152558D02*
X1301834Y153183D01*
G01Y155450D02*
X1301792Y155742D01*
X1301667Y156075D01*
X1301459Y156283D01*
X1301167Y156367D01*
X1300876Y156283D01*
X1300626Y156033D01*
X1300501Y155658D01*
Y155242D01*
X1300417Y154992D01*
X1300209Y154783D01*
X1299917Y154700D01*
X1299626Y154825D01*
X1299417Y155117D01*
X1299334Y155450D01*
X1299417Y155783D01*
X1299626Y156075D01*
X1299917Y156200D01*
X1300209Y156117D01*
X1300417Y155908D01*
X1300501Y155658D01*
Y155242D01*
X1300626Y154867D01*
X1300876Y154617D01*
X1301167Y154533D01*
X1301459Y154617D01*
X1301667Y154825D01*
X1301792Y155158D01*
X1301834Y155450D01*
G01X1301334Y157633D02*
X1301626Y157883D01*
X1301792Y158217D01*
X1301834Y158592D01*
X1301792Y158925D01*
X1301584Y159258D01*
X1301334Y159467D01*
X1301084Y159508D01*
X1300792Y159425D01*
X1300584Y159133D01*
X1300501Y158842D01*
Y158467D01*
G01Y158842D02*
X1300376Y159092D01*
X1300167Y159300D01*
X1299917Y159383D01*
X1299667Y159300D01*
X1299459Y159092D01*
X1299334Y158717D01*
X1299376Y158342D01*
X1299542Y157967D01*
G01X1301334Y160733D02*
X1301626Y160983D01*
X1301792Y161317D01*
X1301834Y161692D01*
X1301792Y162025D01*
X1301584Y162358D01*
X1301334Y162567D01*
X1301084Y162608D01*
X1300792Y162525D01*
X1300584Y162233D01*
X1300501Y161942D01*
Y161567D01*
G01Y161942D02*
X1300376Y162192D01*
X1300167Y162400D01*
X1299917Y162483D01*
X1299667Y162400D01*
X1299459Y162192D01*
X1299334Y161817D01*
X1299376Y161442D01*
X1299542Y161067D01*
G01X1309500Y171361D02*
X1305500D01*
Y163961D01*
G01X1313700Y189161D02*
Y193161D01*
X1306300D01*
G01X1324400Y176361D02*
X1328400D01*
Y183761D01*
G01X1327300Y196661D02*
Y192661D01*
X1334700D01*
G01X1319900Y176361D02*
X1323900D01*
Y183761D01*
G01X1299500Y174850D02*
X1299458Y174517D01*
X1299292Y174225D01*
X1299042Y173975D01*
X1298750Y173808D01*
X1298417Y173725D01*
X1298083D01*
X1297750Y173808D01*
X1297458Y173975D01*
X1297208Y174225D01*
X1297042Y174517D01*
X1297000Y174850D01*
X1297042Y175183D01*
X1297208Y175475D01*
X1297458Y175725D01*
X1297750Y175892D01*
X1298083Y175975D01*
X1298417D01*
X1298750Y175892D01*
X1299042Y175725D01*
X1299292Y175475D01*
X1299458Y175183D01*
X1299500Y174850D01*
G01X1298833Y175183D02*
X1299500Y175683D01*
G01Y177950D02*
X1297000D01*
X1297500Y177450D01*
G01X1299500D02*
Y178450D01*
G01Y181050D02*
X1299458Y181342D01*
X1299333Y181675D01*
X1299125Y181883D01*
X1298833Y181967D01*
X1298542Y181883D01*
X1298292Y181633D01*
X1298167Y181258D01*
Y180842D01*
X1298083Y180592D01*
X1297875Y180383D01*
X1297583Y180300D01*
X1297292Y180425D01*
X1297083Y180717D01*
X1297000Y181050D01*
X1297083Y181383D01*
X1297292Y181675D01*
X1297583Y181800D01*
X1297875Y181717D01*
X1298083Y181508D01*
X1298167Y181258D01*
Y180842D01*
X1298292Y180467D01*
X1298542Y180217D01*
X1298833Y180133D01*
X1299125Y180217D01*
X1299333Y180425D01*
X1299458Y180758D01*
X1299500Y181050D01*
G01Y184150D02*
X1297000D01*
X1297500Y183650D01*
G01X1299500D02*
Y184650D01*
G01X1300800Y183861D02*
Y172461D01*
G01X1314200Y183861D02*
X1300800D01*
G01X1314200Y172461D02*
Y183861D01*
G01X1300800Y172461D02*
X1314200D01*
G01X1336500Y184661D02*
X1320400D01*
G01Y191661D02*
X1336500D01*
G01X1320400Y184661D02*
Y191661D01*
G01X1312900Y218961D02*
Y199761D01*
X1324100D01*
Y218961D01*
X1312900D01*
Y218561D01*
G01X1299517Y233000D02*
Y235500D01*
X1300558D01*
X1300892Y235375D01*
X1301100Y235208D01*
X1301183Y234875D01*
X1301100Y234542D01*
X1300850Y234333D01*
X1300558Y234208D01*
X1299517D01*
G01X1300558D02*
X1301183Y233000D01*
G01X1303450D02*
X1303742Y233042D01*
X1304075Y233167D01*
X1304283Y233375D01*
X1304367Y233667D01*
X1304283Y233958D01*
X1304033Y234208D01*
X1303658Y234333D01*
X1303242D01*
X1302992Y234417D01*
X1302783Y234625D01*
X1302700Y234917D01*
X1302825Y235208D01*
X1303117Y235417D01*
X1303450Y235500D01*
X1303783Y235417D01*
X1304075Y235208D01*
X1304200Y234917D01*
X1304117Y234625D01*
X1303908Y234417D01*
X1303658Y234333D01*
X1303242D01*
X1302867Y234208D01*
X1302617Y233958D01*
X1302533Y233667D01*
X1302617Y233375D01*
X1302825Y233167D01*
X1303158Y233042D01*
X1303450Y233000D01*
G01X1306550D02*
Y235500D01*
X1306050Y235000D01*
G01Y233000D02*
X1307050D01*
G01X1308942Y233292D02*
X1309233Y233083D01*
X1309567Y233000D01*
X1309900Y233083D01*
X1310192Y233333D01*
X1310400Y233708D01*
X1310483Y234083D01*
Y234542D01*
X1310400Y234917D01*
X1310192Y235250D01*
X1309942Y235417D01*
X1309650Y235500D01*
X1309317Y235417D01*
X1309067Y235250D01*
X1308900Y235000D01*
X1308817Y234667D01*
X1308900Y234375D01*
X1309108Y234083D01*
X1309358Y233917D01*
X1309650Y233875D01*
X1309983Y233958D01*
X1310233Y234167D01*
X1310483Y234542D01*
G01X1313800Y244661D02*
Y236661D01*
X1296200D01*
Y244661D01*
X1313800D01*
G01X1300708Y248267D02*
X1300583Y248017D01*
X1300500Y247725D01*
Y247392D01*
X1300625Y247017D01*
X1300833Y246725D01*
X1301083Y246517D01*
X1301500Y246350D01*
X1301875Y246308D01*
X1302250Y246392D01*
X1302500Y246517D01*
X1302750Y246767D01*
X1302917Y247058D01*
X1303000Y247350D01*
Y247642D01*
X1302917Y247933D01*
X1302792Y248183D01*
X1302625Y248392D01*
G01X1303000Y250950D02*
X1300500D01*
X1302292Y249408D01*
Y251492D01*
G01X1302500Y252633D02*
X1302792Y252883D01*
X1302958Y253217D01*
X1303000Y253592D01*
X1302958Y253925D01*
X1302750Y254258D01*
X1302500Y254467D01*
X1302250Y254508D01*
X1301958Y254425D01*
X1301750Y254133D01*
X1301667Y253842D01*
Y253467D01*
G01Y253842D02*
X1301542Y254092D01*
X1301333Y254300D01*
X1301083Y254383D01*
X1300833Y254300D01*
X1300625Y254092D01*
X1300500Y253717D01*
X1300542Y253342D01*
X1300708Y252967D01*
G01X1303000Y256650D02*
X1300500D01*
X1301000Y256150D01*
G01X1303000D02*
Y257150D01*
G01X1304500Y250361D02*
Y255861D01*
G01X1312500Y250361D02*
X1304500D01*
G01X1312500Y255861D02*
Y250361D01*
G01X1326350Y260000D02*
X1326017Y260042D01*
X1325725Y260208D01*
X1325475Y260458D01*
X1325308Y260750D01*
X1325225Y261083D01*
Y261417D01*
X1325308Y261750D01*
X1325475Y262042D01*
X1325725Y262292D01*
X1326017Y262458D01*
X1326350Y262500D01*
X1326683Y262458D01*
X1326975Y262292D01*
X1327225Y262042D01*
X1327392Y261750D01*
X1327475Y261417D01*
Y261083D01*
X1327392Y260750D01*
X1327225Y260458D01*
X1326975Y260208D01*
X1326683Y260042D01*
X1326350Y260000D01*
G01X1326683Y260667D02*
X1327183Y260000D01*
G01X1329450D02*
Y262500D01*
X1328950Y262000D01*
G01Y260000D02*
X1329950D01*
G01X1332550D02*
X1332842Y260042D01*
X1333175Y260167D01*
X1333383Y260375D01*
X1333467Y260667D01*
X1333383Y260958D01*
X1333133Y261208D01*
X1332758Y261333D01*
X1332342D01*
X1332092Y261417D01*
X1331883Y261625D01*
X1331800Y261917D01*
X1331925Y262208D01*
X1332217Y262417D01*
X1332550Y262500D01*
X1332883Y262417D01*
X1333175Y262208D01*
X1333300Y261917D01*
X1333217Y261625D01*
X1333008Y261417D01*
X1332758Y261333D01*
X1332342D01*
X1331967Y261208D01*
X1331717Y260958D01*
X1331633Y260667D01*
X1331717Y260375D01*
X1331925Y260167D01*
X1332258Y260042D01*
X1332550Y260000D01*
G01X1334858Y262083D02*
X1335108Y262333D01*
X1335400Y262458D01*
X1335733Y262500D01*
X1336150Y262417D01*
X1336442Y262208D01*
X1336525Y261958D01*
X1336483Y261708D01*
X1336317Y261500D01*
X1335483Y261083D01*
X1335108Y260792D01*
X1334858Y260375D01*
X1334775Y260000D01*
X1336525D01*
G01X1315300Y246161D02*
X1317400Y244361D01*
X1315300Y242161D01*
G01X1315200Y238561D02*
X1334400D01*
Y249761D01*
X1315200D01*
Y238561D01*
X1315600D01*
G01X1305350Y220500D02*
X1305017Y220542D01*
X1304725Y220708D01*
X1304475Y220958D01*
X1304308Y221250D01*
X1304225Y221583D01*
Y221917D01*
X1304308Y222250D01*
X1304475Y222542D01*
X1304725Y222792D01*
X1305017Y222958D01*
X1305350Y223000D01*
X1305683Y222958D01*
X1305975Y222792D01*
X1306225Y222542D01*
X1306392Y222250D01*
X1306475Y221917D01*
Y221583D01*
X1306392Y221250D01*
X1306225Y220958D01*
X1305975Y220708D01*
X1305683Y220542D01*
X1305350Y220500D01*
G01X1305683Y221167D02*
X1306183Y220500D01*
G01X1308450D02*
Y223000D01*
X1307950Y222500D01*
G01Y220500D02*
X1308950D01*
G01X1311550D02*
X1311842Y220542D01*
X1312175Y220667D01*
X1312383Y220875D01*
X1312467Y221167D01*
X1312383Y221458D01*
X1312133Y221708D01*
X1311758Y221833D01*
X1311342D01*
X1311092Y221917D01*
X1310883Y222125D01*
X1310800Y222417D01*
X1310925Y222708D01*
X1311217Y222917D01*
X1311550Y223000D01*
X1311883Y222917D01*
X1312175Y222708D01*
X1312300Y222417D01*
X1312217Y222125D01*
X1312008Y221917D01*
X1311758Y221833D01*
X1311342D01*
X1310967Y221708D01*
X1310717Y221458D01*
X1310633Y221167D01*
X1310717Y220875D01*
X1310925Y220667D01*
X1311258Y220542D01*
X1311550Y220500D01*
G01X1314650Y223000D02*
X1314317Y222917D01*
X1314067Y222708D01*
X1313900Y222458D01*
X1313775Y222125D01*
X1313733Y221750D01*
X1313775Y221375D01*
X1313900Y221042D01*
X1314067Y220792D01*
X1314317Y220583D01*
X1314650Y220500D01*
X1314983Y220583D01*
X1315233Y220792D01*
X1315400Y221042D01*
X1315525Y221375D01*
X1315567Y221750D01*
X1315525Y222125D01*
X1315400Y222458D01*
X1315233Y222708D01*
X1314983Y222917D01*
X1314650Y223000D01*
G01X1320500Y218861D02*
X1318700Y216761D01*
X1316500Y218861D01*
G01X1315017Y279667D02*
Y282167D01*
X1316058D01*
X1316392Y282042D01*
X1316600Y281875D01*
X1316683Y281542D01*
X1316600Y281209D01*
X1316350Y281000D01*
X1316058Y280875D01*
X1315017D01*
G01X1316058D02*
X1316683Y279667D01*
G01X1318950D02*
X1319242Y279709D01*
X1319575Y279834D01*
X1319783Y280042D01*
X1319867Y280334D01*
X1319783Y280625D01*
X1319533Y280875D01*
X1319158Y281000D01*
X1318742D01*
X1318492Y281084D01*
X1318283Y281292D01*
X1318200Y281584D01*
X1318325Y281875D01*
X1318617Y282084D01*
X1318950Y282167D01*
X1319283Y282084D01*
X1319575Y281875D01*
X1319700Y281584D01*
X1319617Y281292D01*
X1319408Y281084D01*
X1319158Y281000D01*
X1318742D01*
X1318367Y280875D01*
X1318117Y280625D01*
X1318033Y280334D01*
X1318117Y280042D01*
X1318325Y279834D01*
X1318658Y279709D01*
X1318950Y279667D01*
G01X1321258Y281750D02*
X1321508Y282000D01*
X1321800Y282125D01*
X1322133Y282167D01*
X1322550Y282084D01*
X1322842Y281875D01*
X1322925Y281625D01*
X1322883Y281375D01*
X1322717Y281167D01*
X1321883Y280750D01*
X1321508Y280459D01*
X1321258Y280042D01*
X1321175Y279667D01*
X1322925D01*
G01X1325150D02*
Y282167D01*
X1324650Y281667D01*
G01Y279667D02*
X1325650D01*
G01X1322075Y277366D02*
Y269366D01*
X1304475D01*
Y277366D01*
X1322075D01*
G01X1325708Y289267D02*
X1325583Y289017D01*
X1325500Y288725D01*
Y288392D01*
X1325625Y288017D01*
X1325833Y287725D01*
X1326083Y287517D01*
X1326500Y287350D01*
X1326875Y287308D01*
X1327250Y287392D01*
X1327500Y287517D01*
X1327750Y287767D01*
X1327917Y288058D01*
X1328000Y288350D01*
Y288642D01*
X1327917Y288933D01*
X1327792Y289183D01*
X1327625Y289392D01*
G01X1328000Y291950D02*
X1325500D01*
X1327292Y290408D01*
Y292492D01*
G01X1327500Y293633D02*
X1327792Y293883D01*
X1327958Y294217D01*
X1328000Y294592D01*
X1327958Y294925D01*
X1327750Y295258D01*
X1327500Y295467D01*
X1327250Y295508D01*
X1326958Y295425D01*
X1326750Y295133D01*
X1326667Y294842D01*
Y294467D01*
G01Y294842D02*
X1326542Y295092D01*
X1326333Y295300D01*
X1326083Y295383D01*
X1325833Y295300D01*
X1325625Y295092D01*
X1325500Y294717D01*
X1325542Y294342D01*
X1325708Y293967D01*
G01X1326958Y296858D02*
X1326667Y297150D01*
X1326500Y297400D01*
X1326417Y297733D01*
X1326500Y298025D01*
X1326667Y298233D01*
X1326917Y298400D01*
X1327208Y298442D01*
X1327458Y298400D01*
X1327708Y298233D01*
X1327917Y297983D01*
X1328000Y297692D01*
X1327917Y297358D01*
X1327667Y297067D01*
X1327292Y296900D01*
X1326875Y296858D01*
X1326333Y296942D01*
X1326042Y297067D01*
X1325750Y297275D01*
X1325542Y297567D01*
X1325500Y297858D01*
X1325583Y298150D01*
X1325792Y298358D01*
G01X1321708Y289267D02*
X1321583Y289017D01*
X1321500Y288725D01*
Y288392D01*
X1321625Y288017D01*
X1321833Y287725D01*
X1322083Y287517D01*
X1322500Y287350D01*
X1322875Y287308D01*
X1323250Y287392D01*
X1323500Y287517D01*
X1323750Y287767D01*
X1323917Y288058D01*
X1324000Y288350D01*
Y288642D01*
X1323917Y288933D01*
X1323792Y289183D01*
X1323625Y289392D01*
G01X1324000Y291950D02*
X1321500D01*
X1323292Y290408D01*
Y292492D01*
G01X1323500Y293633D02*
X1323792Y293883D01*
X1323958Y294217D01*
X1324000Y294592D01*
X1323958Y294925D01*
X1323750Y295258D01*
X1323500Y295467D01*
X1323250Y295508D01*
X1322958Y295425D01*
X1322750Y295133D01*
X1322667Y294842D01*
Y294467D01*
G01Y294842D02*
X1322542Y295092D01*
X1322333Y295300D01*
X1322083Y295383D01*
X1321833Y295300D01*
X1321625Y295092D01*
X1321500Y294717D01*
X1321542Y294342D01*
X1321708Y293967D01*
G01X1323625Y296733D02*
X1323833Y296983D01*
X1323958Y297275D01*
X1324000Y297650D01*
X1323917Y298025D01*
X1323750Y298317D01*
X1323458Y298525D01*
X1323125Y298567D01*
X1322792Y298483D01*
X1322583Y298275D01*
X1322417Y297983D01*
X1322375Y297692D01*
X1322417Y297400D01*
X1322583Y297025D01*
X1321500Y297150D01*
Y298275D01*
G01X1312500Y267961D02*
Y262461D01*
G01X1304500Y267961D02*
X1312500D01*
G01X1304500Y262461D02*
Y267961D01*
G01X1317708Y289267D02*
X1317583Y289017D01*
X1317500Y288725D01*
Y288392D01*
X1317625Y288017D01*
X1317833Y287725D01*
X1318083Y287517D01*
X1318500Y287350D01*
X1318875Y287308D01*
X1319250Y287392D01*
X1319500Y287517D01*
X1319750Y287767D01*
X1319917Y288058D01*
X1320000Y288350D01*
Y288642D01*
X1319917Y288933D01*
X1319792Y289183D01*
X1319625Y289392D01*
G01X1320000Y291950D02*
X1317500D01*
X1319292Y290408D01*
Y292492D01*
G01X1319500Y293633D02*
X1319792Y293883D01*
X1319958Y294217D01*
X1320000Y294592D01*
X1319958Y294925D01*
X1319750Y295258D01*
X1319500Y295467D01*
X1319250Y295508D01*
X1318958Y295425D01*
X1318750Y295133D01*
X1318667Y294842D01*
Y294467D01*
G01Y294842D02*
X1318542Y295092D01*
X1318333Y295300D01*
X1318083Y295383D01*
X1317833Y295300D01*
X1317625Y295092D01*
X1317500Y294717D01*
X1317542Y294342D01*
X1317708Y293967D01*
G01X1320000Y297567D02*
X1319458Y297650D01*
X1319000Y297775D01*
X1318583Y297942D01*
X1318125Y298150D01*
X1317500Y298483D01*
Y296817D01*
G01X1301042Y271767D02*
X1300917Y271517D01*
X1300834Y271225D01*
Y270892D01*
X1300959Y270517D01*
X1301167Y270225D01*
X1301417Y270017D01*
X1301834Y269850D01*
X1302209Y269808D01*
X1302584Y269892D01*
X1302834Y270017D01*
X1303084Y270267D01*
X1303251Y270558D01*
X1303334Y270850D01*
Y271142D01*
X1303251Y271433D01*
X1303126Y271683D01*
X1302959Y271892D01*
G01X1303334Y274450D02*
X1300834D01*
X1302626Y272908D01*
Y274992D01*
G01X1302834Y276133D02*
X1303126Y276383D01*
X1303292Y276717D01*
X1303334Y277092D01*
X1303292Y277425D01*
X1303084Y277758D01*
X1302834Y277967D01*
X1302584Y278008D01*
X1302292Y277925D01*
X1302084Y277633D01*
X1302001Y277342D01*
Y276967D01*
G01Y277342D02*
X1301876Y277592D01*
X1301667Y277800D01*
X1301417Y277883D01*
X1301167Y277800D01*
X1300959Y277592D01*
X1300834Y277217D01*
X1300876Y276842D01*
X1301042Y276467D01*
G01X1300834Y280150D02*
X1300917Y279817D01*
X1301126Y279567D01*
X1301376Y279400D01*
X1301709Y279275D01*
X1302084Y279233D01*
X1302459Y279275D01*
X1302792Y279400D01*
X1303042Y279567D01*
X1303251Y279817D01*
X1303334Y280150D01*
X1303251Y280483D01*
X1303042Y280733D01*
X1302792Y280900D01*
X1302459Y281025D01*
X1302084Y281067D01*
X1301709Y281025D01*
X1301376Y280900D01*
X1301126Y280733D01*
X1300917Y280483D01*
X1300834Y280150D01*
G01X1329610Y496022D02*
X1342610D01*
G01X1329610Y510022D02*
Y496022D01*
G01X1329493Y522303D02*
Y524803D01*
X1330534D01*
X1330868Y524678D01*
X1331076Y524511D01*
X1331159Y524178D01*
X1331076Y523845D01*
X1330826Y523636D01*
X1330534Y523511D01*
X1329493D01*
G01X1330534D02*
X1331159Y522303D01*
G01X1332509Y522678D02*
X1332759Y522470D01*
X1333051Y522345D01*
X1333426Y522303D01*
X1333801Y522386D01*
X1334093Y522553D01*
X1334301Y522845D01*
X1334343Y523178D01*
X1334259Y523511D01*
X1334051Y523720D01*
X1333759Y523886D01*
X1333468Y523928D01*
X1333176Y523886D01*
X1332801Y523720D01*
X1332926Y524803D01*
X1334051D01*
G01X1335609Y522803D02*
X1335859Y522511D01*
X1336193Y522345D01*
X1336568Y522303D01*
X1336901Y522345D01*
X1337234Y522553D01*
X1337443Y522803D01*
X1337484Y523053D01*
X1337401Y523345D01*
X1337109Y523553D01*
X1336818Y523636D01*
X1336443D01*
G01X1336818D02*
X1337068Y523761D01*
X1337276Y523970D01*
X1337359Y524220D01*
X1337276Y524470D01*
X1337068Y524678D01*
X1336693Y524803D01*
X1336318Y524761D01*
X1335943Y524595D01*
G01X1339626Y524803D02*
X1339293Y524720D01*
X1339043Y524511D01*
X1338876Y524261D01*
X1338751Y523928D01*
X1338709Y523553D01*
X1338751Y523178D01*
X1338876Y522845D01*
X1339043Y522595D01*
X1339293Y522386D01*
X1339626Y522303D01*
X1339959Y522386D01*
X1340209Y522595D01*
X1340376Y522845D01*
X1340501Y523178D01*
X1340543Y523553D01*
X1340501Y523928D01*
X1340376Y524261D01*
X1340209Y524511D01*
X1339959Y524720D01*
X1339626Y524803D01*
G01X1342610Y510022D02*
X1329610D01*
G01X1313700Y641917D02*
Y645917D01*
X1306300D01*
G01X1313000Y602434D02*
X1310500D01*
Y603475D01*
X1310625Y603809D01*
X1310792Y604017D01*
X1311125Y604100D01*
X1311458Y604017D01*
X1311667Y603767D01*
X1311792Y603475D01*
Y602434D01*
G01Y603475D02*
X1313000Y604100D01*
G01X1312625Y605450D02*
X1312833Y605700D01*
X1312958Y605992D01*
X1313000Y606367D01*
X1312917Y606742D01*
X1312750Y607034D01*
X1312458Y607242D01*
X1312125Y607284D01*
X1311792Y607200D01*
X1311583Y606992D01*
X1311417Y606700D01*
X1311375Y606409D01*
X1311417Y606117D01*
X1311583Y605742D01*
X1310500Y605867D01*
Y606992D01*
G01X1312625Y608550D02*
X1312833Y608800D01*
X1312958Y609092D01*
X1313000Y609467D01*
X1312917Y609842D01*
X1312750Y610134D01*
X1312458Y610342D01*
X1312125Y610384D01*
X1311792Y610300D01*
X1311583Y610092D01*
X1311417Y609800D01*
X1311375Y609509D01*
X1311417Y609217D01*
X1311583Y608842D01*
X1310500Y608967D01*
Y610092D01*
G01X1310917Y611775D02*
X1310667Y612025D01*
X1310542Y612317D01*
X1310500Y612650D01*
X1310583Y613067D01*
X1310792Y613359D01*
X1311042Y613442D01*
X1311292Y613400D01*
X1311500Y613234D01*
X1311917Y612400D01*
X1312208Y612025D01*
X1312625Y611775D01*
X1313000Y611692D01*
Y613442D01*
G01X1310000Y616717D02*
X1314000D01*
Y624117D01*
G01X1323000Y604017D02*
X1320500D01*
Y605058D01*
X1320625Y605392D01*
X1320792Y605600D01*
X1321125Y605683D01*
X1321458Y605600D01*
X1321667Y605350D01*
X1321792Y605058D01*
Y604017D01*
G01Y605058D02*
X1323000Y605683D01*
G01X1322625Y607033D02*
X1322833Y607283D01*
X1322958Y607575D01*
X1323000Y607950D01*
X1322917Y608325D01*
X1322750Y608617D01*
X1322458Y608825D01*
X1322125Y608867D01*
X1321792Y608783D01*
X1321583Y608575D01*
X1321417Y608283D01*
X1321375Y607992D01*
X1321417Y607700D01*
X1321583Y607325D01*
X1320500Y607450D01*
Y608575D01*
G01X1322625Y610133D02*
X1322833Y610383D01*
X1322958Y610675D01*
X1323000Y611050D01*
X1322917Y611425D01*
X1322750Y611717D01*
X1322458Y611925D01*
X1322125Y611967D01*
X1321792Y611883D01*
X1321583Y611675D01*
X1321417Y611383D01*
X1321375Y611092D01*
X1321417Y610800D01*
X1321583Y610425D01*
X1320500Y610550D01*
Y611675D01*
G01X1322625Y613233D02*
X1322833Y613483D01*
X1322958Y613775D01*
X1323000Y614150D01*
X1322917Y614525D01*
X1322750Y614817D01*
X1322458Y615025D01*
X1322125Y615067D01*
X1321792Y614983D01*
X1321583Y614775D01*
X1321417Y614483D01*
X1321375Y614192D01*
X1321417Y613900D01*
X1321583Y613525D01*
X1320500Y613650D01*
Y614775D01*
G01X1320000Y616717D02*
X1324000D01*
Y624117D01*
G01X1308500Y602434D02*
X1306000D01*
Y603475D01*
X1306125Y603809D01*
X1306292Y604017D01*
X1306625Y604100D01*
X1306958Y604017D01*
X1307167Y603767D01*
X1307292Y603475D01*
Y602434D01*
G01Y603475D02*
X1308500Y604100D01*
G01X1308125Y605450D02*
X1308333Y605700D01*
X1308458Y605992D01*
X1308500Y606367D01*
X1308417Y606742D01*
X1308250Y607034D01*
X1307958Y607242D01*
X1307625Y607284D01*
X1307292Y607200D01*
X1307083Y606992D01*
X1306917Y606700D01*
X1306875Y606409D01*
X1306917Y606117D01*
X1307083Y605742D01*
X1306000Y605867D01*
Y606992D01*
G01X1308125Y608550D02*
X1308333Y608800D01*
X1308458Y609092D01*
X1308500Y609467D01*
X1308417Y609842D01*
X1308250Y610134D01*
X1307958Y610342D01*
X1307625Y610384D01*
X1307292Y610300D01*
X1307083Y610092D01*
X1306917Y609800D01*
X1306875Y609509D01*
X1306917Y609217D01*
X1307083Y608842D01*
X1306000Y608967D01*
Y610092D01*
G01X1307458Y611775D02*
X1307167Y612067D01*
X1307000Y612317D01*
X1306917Y612650D01*
X1307000Y612942D01*
X1307167Y613150D01*
X1307417Y613317D01*
X1307708Y613359D01*
X1307958Y613317D01*
X1308208Y613150D01*
X1308417Y612900D01*
X1308500Y612609D01*
X1308417Y612275D01*
X1308167Y611984D01*
X1307792Y611817D01*
X1307375Y611775D01*
X1306833Y611859D01*
X1306542Y611984D01*
X1306250Y612192D01*
X1306042Y612484D01*
X1306000Y612775D01*
X1306083Y613067D01*
X1306292Y613275D01*
G01X1309500Y624117D02*
X1305500D01*
Y616717D01*
G01X1324500Y629117D02*
X1328500D01*
Y636517D01*
G01X1327300Y649417D02*
Y645417D01*
X1334700D01*
G01X1320000Y629117D02*
X1324000D01*
Y636517D01*
G01X1298833Y626350D02*
X1298791Y626017D01*
X1298625Y625725D01*
X1298375Y625475D01*
X1298083Y625308D01*
X1297750Y625225D01*
X1297416D01*
X1297083Y625308D01*
X1296791Y625475D01*
X1296541Y625725D01*
X1296375Y626017D01*
X1296333Y626350D01*
X1296375Y626683D01*
X1296541Y626975D01*
X1296791Y627225D01*
X1297083Y627392D01*
X1297416Y627475D01*
X1297750D01*
X1298083Y627392D01*
X1298375Y627225D01*
X1298625Y626975D01*
X1298791Y626683D01*
X1298833Y626350D01*
G01X1298166Y626683D02*
X1298833Y627183D01*
G01Y629450D02*
X1296333D01*
X1296833Y628950D01*
G01X1298833D02*
Y629950D01*
G01X1296333Y632550D02*
X1296416Y632217D01*
X1296625Y631967D01*
X1296875Y631800D01*
X1297208Y631675D01*
X1297583Y631633D01*
X1297958Y631675D01*
X1298291Y631800D01*
X1298541Y631967D01*
X1298750Y632217D01*
X1298833Y632550D01*
X1298750Y632883D01*
X1298541Y633133D01*
X1298291Y633300D01*
X1297958Y633425D01*
X1297583Y633467D01*
X1297208Y633425D01*
X1296875Y633300D01*
X1296625Y633133D01*
X1296416Y632883D01*
X1296333Y632550D01*
G01X1298541Y634942D02*
X1298750Y635233D01*
X1298833Y635567D01*
X1298750Y635900D01*
X1298500Y636192D01*
X1298125Y636400D01*
X1297750Y636483D01*
X1297291D01*
X1296916Y636400D01*
X1296583Y636192D01*
X1296416Y635942D01*
X1296333Y635650D01*
X1296416Y635317D01*
X1296583Y635067D01*
X1296833Y634900D01*
X1297166Y634817D01*
X1297458Y634900D01*
X1297750Y635108D01*
X1297916Y635358D01*
X1297958Y635650D01*
X1297875Y635983D01*
X1297666Y636233D01*
X1297291Y636483D01*
G01X1300800Y636617D02*
Y625217D01*
G01X1314200Y636617D02*
X1300800D01*
G01X1314200Y625217D02*
Y636617D01*
G01X1300800Y625217D02*
X1314200D01*
G01X1336500Y637417D02*
X1320400D01*
G01Y644417D02*
X1336500D01*
G01X1320400Y637417D02*
Y644417D01*
G01X1300017Y685500D02*
Y688000D01*
X1301058D01*
X1301392Y687875D01*
X1301600Y687708D01*
X1301683Y687375D01*
X1301600Y687042D01*
X1301350Y686833D01*
X1301058Y686708D01*
X1300017D01*
G01X1301058D02*
X1301683Y685500D01*
G01X1303033Y685875D02*
X1303283Y685667D01*
X1303575Y685542D01*
X1303950Y685500D01*
X1304325Y685583D01*
X1304617Y685750D01*
X1304825Y686042D01*
X1304867Y686375D01*
X1304783Y686708D01*
X1304575Y686917D01*
X1304283Y687083D01*
X1303992Y687125D01*
X1303700Y687083D01*
X1303325Y686917D01*
X1303450Y688000D01*
X1304575D01*
G01X1307550Y685500D02*
Y688000D01*
X1306008Y686208D01*
X1308092D01*
G01X1309233Y686000D02*
X1309483Y685708D01*
X1309817Y685542D01*
X1310192Y685500D01*
X1310525Y685542D01*
X1310858Y685750D01*
X1311067Y686000D01*
X1311108Y686250D01*
X1311025Y686542D01*
X1310733Y686750D01*
X1310442Y686833D01*
X1310067D01*
G01X1310442D02*
X1310692Y686958D01*
X1310900Y687167D01*
X1310983Y687417D01*
X1310900Y687667D01*
X1310692Y687875D01*
X1310317Y688000D01*
X1309942Y687958D01*
X1309567Y687792D01*
G01X1313800Y697417D02*
Y689417D01*
X1296200D01*
Y697417D01*
X1313800D01*
G01X1315300Y698917D02*
X1317400Y697117D01*
X1315300Y694917D01*
G01X1315200Y691317D02*
X1334400D01*
Y702517D01*
X1315200D01*
Y691317D01*
X1315600D01*
G01X1305850Y673500D02*
X1305517Y673542D01*
X1305225Y673708D01*
X1304975Y673958D01*
X1304808Y674250D01*
X1304725Y674583D01*
Y674917D01*
X1304808Y675250D01*
X1304975Y675542D01*
X1305225Y675792D01*
X1305517Y675958D01*
X1305850Y676000D01*
X1306183Y675958D01*
X1306475Y675792D01*
X1306725Y675542D01*
X1306892Y675250D01*
X1306975Y674917D01*
Y674583D01*
X1306892Y674250D01*
X1306725Y673958D01*
X1306475Y673708D01*
X1306183Y673542D01*
X1305850Y673500D01*
G01X1306183Y674167D02*
X1306683Y673500D01*
G01X1308950D02*
Y676000D01*
X1308450Y675500D01*
G01Y673500D02*
X1309450D01*
G01X1312050Y676000D02*
X1311717Y675917D01*
X1311467Y675708D01*
X1311300Y675458D01*
X1311175Y675125D01*
X1311133Y674750D01*
X1311175Y674375D01*
X1311300Y674042D01*
X1311467Y673792D01*
X1311717Y673583D01*
X1312050Y673500D01*
X1312383Y673583D01*
X1312633Y673792D01*
X1312800Y674042D01*
X1312925Y674375D01*
X1312967Y674750D01*
X1312925Y675125D01*
X1312800Y675458D01*
X1312633Y675708D01*
X1312383Y675917D01*
X1312050Y676000D01*
G01X1315150Y673500D02*
X1315442Y673542D01*
X1315775Y673667D01*
X1315983Y673875D01*
X1316067Y674167D01*
X1315983Y674458D01*
X1315733Y674708D01*
X1315358Y674833D01*
X1314942D01*
X1314692Y674917D01*
X1314483Y675125D01*
X1314400Y675417D01*
X1314525Y675708D01*
X1314817Y675917D01*
X1315150Y676000D01*
X1315483Y675917D01*
X1315775Y675708D01*
X1315900Y675417D01*
X1315817Y675125D01*
X1315608Y674917D01*
X1315358Y674833D01*
X1314942D01*
X1314567Y674708D01*
X1314317Y674458D01*
X1314233Y674167D01*
X1314317Y673875D01*
X1314525Y673667D01*
X1314858Y673542D01*
X1315150Y673500D01*
G01X1320500Y671617D02*
X1318700Y669517D01*
X1316500Y671617D01*
G01X1312900Y671717D02*
Y652517D01*
X1324100D01*
Y671717D01*
X1312900D01*
Y671317D01*
G01X1313517Y731500D02*
Y734000D01*
X1314558D01*
X1314892Y733875D01*
X1315100Y733708D01*
X1315183Y733375D01*
X1315100Y733042D01*
X1314850Y732833D01*
X1314558Y732708D01*
X1313517D01*
G01X1314558D02*
X1315183Y731500D01*
G01X1316533Y731875D02*
X1316783Y731667D01*
X1317075Y731542D01*
X1317450Y731500D01*
X1317825Y731583D01*
X1318117Y731750D01*
X1318325Y732042D01*
X1318367Y732375D01*
X1318283Y732708D01*
X1318075Y732917D01*
X1317783Y733083D01*
X1317492Y733125D01*
X1317200Y733083D01*
X1316825Y732917D01*
X1316950Y734000D01*
X1318075D01*
G01X1321050Y731500D02*
Y734000D01*
X1319508Y732208D01*
X1321592D01*
G01X1322733Y731875D02*
X1322983Y731667D01*
X1323275Y731542D01*
X1323650Y731500D01*
X1324025Y731583D01*
X1324317Y731750D01*
X1324525Y732042D01*
X1324567Y732375D01*
X1324483Y732708D01*
X1324275Y732917D01*
X1323983Y733083D01*
X1323692Y733125D01*
X1323400Y733083D01*
X1323025Y732917D01*
X1323150Y734000D01*
X1324275D01*
G01X1322134Y730182D02*
Y722182D01*
X1304534D01*
Y730182D01*
X1322134D01*
G01X1326208Y742267D02*
X1326083Y742017D01*
X1326000Y741725D01*
Y741392D01*
X1326125Y741017D01*
X1326333Y740725D01*
X1326583Y740517D01*
X1327000Y740350D01*
X1327375Y740308D01*
X1327750Y740392D01*
X1328000Y740517D01*
X1328250Y740767D01*
X1328417Y741058D01*
X1328500Y741350D01*
Y741642D01*
X1328417Y741933D01*
X1328292Y742183D01*
X1328125Y742392D01*
G01X1326417Y743658D02*
X1326167Y743908D01*
X1326042Y744200D01*
X1326000Y744533D01*
X1326083Y744950D01*
X1326292Y745242D01*
X1326542Y745325D01*
X1326792Y745283D01*
X1327000Y745117D01*
X1327417Y744283D01*
X1327708Y743908D01*
X1328125Y743658D01*
X1328500Y743575D01*
Y745325D01*
G01Y747550D02*
X1328458Y747842D01*
X1328333Y748175D01*
X1328125Y748383D01*
X1327833Y748467D01*
X1327542Y748383D01*
X1327292Y748133D01*
X1327167Y747758D01*
Y747342D01*
X1327083Y747092D01*
X1326875Y746883D01*
X1326583Y746800D01*
X1326292Y746925D01*
X1326083Y747217D01*
X1326000Y747550D01*
X1326083Y747883D01*
X1326292Y748175D01*
X1326583Y748300D01*
X1326875Y748217D01*
X1327083Y748008D01*
X1327167Y747758D01*
Y747342D01*
X1327292Y746967D01*
X1327542Y746717D01*
X1327833Y746633D01*
X1328125Y746717D01*
X1328333Y746925D01*
X1328458Y747258D01*
X1328500Y747550D01*
G01X1326000Y750650D02*
X1326083Y750317D01*
X1326292Y750067D01*
X1326542Y749900D01*
X1326875Y749775D01*
X1327250Y749733D01*
X1327625Y749775D01*
X1327958Y749900D01*
X1328208Y750067D01*
X1328417Y750317D01*
X1328500Y750650D01*
X1328417Y750983D01*
X1328208Y751233D01*
X1327958Y751400D01*
X1327625Y751525D01*
X1327250Y751567D01*
X1326875Y751525D01*
X1326542Y751400D01*
X1326292Y751233D01*
X1326083Y750983D01*
X1326000Y750650D01*
G01X1322208Y742267D02*
X1322083Y742017D01*
X1322000Y741725D01*
Y741392D01*
X1322125Y741017D01*
X1322333Y740725D01*
X1322583Y740517D01*
X1323000Y740350D01*
X1323375Y740308D01*
X1323750Y740392D01*
X1324000Y740517D01*
X1324250Y740767D01*
X1324417Y741058D01*
X1324500Y741350D01*
Y741642D01*
X1324417Y741933D01*
X1324292Y742183D01*
X1324125Y742392D01*
G01X1322417Y743658D02*
X1322167Y743908D01*
X1322042Y744200D01*
X1322000Y744533D01*
X1322083Y744950D01*
X1322292Y745242D01*
X1322542Y745325D01*
X1322792Y745283D01*
X1323000Y745117D01*
X1323417Y744283D01*
X1323708Y743908D01*
X1324125Y743658D01*
X1324500Y743575D01*
Y745325D01*
G01Y747467D02*
X1323958Y747550D01*
X1323500Y747675D01*
X1323083Y747842D01*
X1322625Y748050D01*
X1322000Y748383D01*
Y746717D01*
G01X1324500Y750650D02*
X1324458Y750942D01*
X1324333Y751275D01*
X1324125Y751483D01*
X1323833Y751567D01*
X1323542Y751483D01*
X1323292Y751233D01*
X1323167Y750858D01*
Y750442D01*
X1323083Y750192D01*
X1322875Y749983D01*
X1322583Y749900D01*
X1322292Y750025D01*
X1322083Y750317D01*
X1322000Y750650D01*
X1322083Y750983D01*
X1322292Y751275D01*
X1322583Y751400D01*
X1322875Y751317D01*
X1323083Y751108D01*
X1323167Y750858D01*
Y750442D01*
X1323292Y750067D01*
X1323542Y749817D01*
X1323833Y749733D01*
X1324125Y749817D01*
X1324333Y750025D01*
X1324458Y750358D01*
X1324500Y750650D01*
G01X1300708Y700767D02*
X1300583Y700517D01*
X1300500Y700225D01*
Y699892D01*
X1300625Y699517D01*
X1300833Y699225D01*
X1301083Y699017D01*
X1301500Y698850D01*
X1301875Y698808D01*
X1302250Y698892D01*
X1302500Y699017D01*
X1302750Y699267D01*
X1302917Y699558D01*
X1303000Y699850D01*
Y700142D01*
X1302917Y700433D01*
X1302792Y700683D01*
X1302625Y700892D01*
G01X1300917Y702158D02*
X1300667Y702408D01*
X1300542Y702700D01*
X1300500Y703033D01*
X1300583Y703450D01*
X1300792Y703742D01*
X1301042Y703825D01*
X1301292Y703783D01*
X1301500Y703617D01*
X1301917Y702783D01*
X1302208Y702408D01*
X1302625Y702158D01*
X1303000Y702075D01*
Y703825D01*
G01Y705967D02*
X1302458Y706050D01*
X1302000Y706175D01*
X1301583Y706342D01*
X1301125Y706550D01*
X1300500Y706883D01*
Y705217D01*
G01X1302625Y708233D02*
X1302833Y708483D01*
X1302958Y708775D01*
X1303000Y709150D01*
X1302917Y709525D01*
X1302750Y709817D01*
X1302458Y710025D01*
X1302125Y710067D01*
X1301792Y709983D01*
X1301583Y709775D01*
X1301417Y709483D01*
X1301375Y709192D01*
X1301417Y708900D01*
X1301583Y708525D01*
X1300500Y708650D01*
Y709775D01*
G01X1304500Y703117D02*
Y708617D01*
G01X1312500Y703117D02*
X1304500D01*
G01X1312500Y708617D02*
Y703117D01*
G01Y720717D02*
Y715217D01*
G01X1304500Y720717D02*
X1312500D01*
G01X1304500Y715217D02*
Y720717D01*
G01X1326350Y712000D02*
X1326017Y712042D01*
X1325725Y712208D01*
X1325475Y712458D01*
X1325308Y712750D01*
X1325225Y713083D01*
Y713417D01*
X1325308Y713750D01*
X1325475Y714042D01*
X1325725Y714292D01*
X1326017Y714458D01*
X1326350Y714500D01*
X1326683Y714458D01*
X1326975Y714292D01*
X1327225Y714042D01*
X1327392Y713750D01*
X1327475Y713417D01*
Y713083D01*
X1327392Y712750D01*
X1327225Y712458D01*
X1326975Y712208D01*
X1326683Y712042D01*
X1326350Y712000D01*
G01X1326683Y712667D02*
X1327183Y712000D01*
G01X1329450D02*
Y714500D01*
X1328950Y714000D01*
G01Y712000D02*
X1329950D01*
G01X1332550D02*
Y714500D01*
X1332050Y714000D01*
G01Y712000D02*
X1333050D01*
G01X1335650Y714500D02*
X1335317Y714417D01*
X1335067Y714208D01*
X1334900Y713958D01*
X1334775Y713625D01*
X1334733Y713250D01*
X1334775Y712875D01*
X1334900Y712542D01*
X1335067Y712292D01*
X1335317Y712083D01*
X1335650Y712000D01*
X1335983Y712083D01*
X1336233Y712292D01*
X1336400Y712542D01*
X1336525Y712875D01*
X1336567Y713250D01*
X1336525Y713625D01*
X1336400Y713958D01*
X1336233Y714208D01*
X1335983Y714417D01*
X1335650Y714500D01*
G01X1318208Y742267D02*
X1318083Y742017D01*
X1318000Y741725D01*
Y741392D01*
X1318125Y741017D01*
X1318333Y740725D01*
X1318583Y740517D01*
X1319000Y740350D01*
X1319375Y740308D01*
X1319750Y740392D01*
X1320000Y740517D01*
X1320250Y740767D01*
X1320417Y741058D01*
X1320500Y741350D01*
Y741642D01*
X1320417Y741933D01*
X1320292Y742183D01*
X1320125Y742392D01*
G01X1318417Y743658D02*
X1318167Y743908D01*
X1318042Y744200D01*
X1318000Y744533D01*
X1318083Y744950D01*
X1318292Y745242D01*
X1318542Y745325D01*
X1318792Y745283D01*
X1319000Y745117D01*
X1319417Y744283D01*
X1319708Y743908D01*
X1320125Y743658D01*
X1320500Y743575D01*
Y745325D01*
G01Y747550D02*
X1320458Y747842D01*
X1320333Y748175D01*
X1320125Y748383D01*
X1319833Y748467D01*
X1319542Y748383D01*
X1319292Y748133D01*
X1319167Y747758D01*
Y747342D01*
X1319083Y747092D01*
X1318875Y746883D01*
X1318583Y746800D01*
X1318292Y746925D01*
X1318083Y747217D01*
X1318000Y747550D01*
X1318083Y747883D01*
X1318292Y748175D01*
X1318583Y748300D01*
X1318875Y748217D01*
X1319083Y748008D01*
X1319167Y747758D01*
Y747342D01*
X1319292Y746967D01*
X1319542Y746717D01*
X1319833Y746633D01*
X1320125Y746717D01*
X1320333Y746925D01*
X1320458Y747258D01*
X1320500Y747550D01*
G01Y750650D02*
X1318000D01*
X1318500Y750150D01*
G01X1320500D02*
Y751150D01*
G01X1297708Y724267D02*
X1297583Y724017D01*
X1297500Y723725D01*
Y723392D01*
X1297625Y723017D01*
X1297833Y722725D01*
X1298083Y722517D01*
X1298500Y722350D01*
X1298875Y722308D01*
X1299250Y722392D01*
X1299500Y722517D01*
X1299750Y722767D01*
X1299917Y723058D01*
X1300000Y723350D01*
Y723642D01*
X1299917Y723933D01*
X1299792Y724183D01*
X1299625Y724392D01*
G01X1297917Y725658D02*
X1297667Y725908D01*
X1297542Y726200D01*
X1297500Y726533D01*
X1297583Y726950D01*
X1297792Y727242D01*
X1298042Y727325D01*
X1298292Y727283D01*
X1298500Y727117D01*
X1298917Y726283D01*
X1299208Y725908D01*
X1299625Y725658D01*
X1300000Y725575D01*
Y727325D01*
G01Y729467D02*
X1299458Y729550D01*
X1299000Y729675D01*
X1298583Y729842D01*
X1298125Y730050D01*
X1297500Y730383D01*
Y728717D01*
G01X1300000Y733150D02*
X1297500D01*
X1299292Y731608D01*
Y733692D01*
G01X1309482Y1054804D02*
X1306982D01*
Y1055845D01*
X1307107Y1056179D01*
X1307274Y1056387D01*
X1307607Y1056470D01*
X1307940Y1056387D01*
X1308149Y1056137D01*
X1308274Y1055845D01*
Y1054804D01*
G01Y1055845D02*
X1309482Y1056470D01*
G01X1307399Y1057945D02*
X1307149Y1058195D01*
X1307024Y1058487D01*
X1306982Y1058820D01*
X1307065Y1059237D01*
X1307274Y1059529D01*
X1307524Y1059612D01*
X1307774Y1059570D01*
X1307982Y1059404D01*
X1308399Y1058570D01*
X1308690Y1058195D01*
X1309107Y1057945D01*
X1309482Y1057862D01*
Y1059612D01*
G01Y1061754D02*
X1308940Y1061837D01*
X1308482Y1061962D01*
X1308065Y1062129D01*
X1307607Y1062337D01*
X1306982Y1062670D01*
Y1061004D01*
G01X1308440Y1064145D02*
X1308149Y1064437D01*
X1307982Y1064687D01*
X1307899Y1065020D01*
X1307982Y1065312D01*
X1308149Y1065520D01*
X1308399Y1065687D01*
X1308690Y1065729D01*
X1308940Y1065687D01*
X1309190Y1065520D01*
X1309399Y1065270D01*
X1309482Y1064979D01*
X1309399Y1064645D01*
X1309149Y1064354D01*
X1308774Y1064187D01*
X1308357Y1064145D01*
X1307815Y1064229D01*
X1307524Y1064354D01*
X1307232Y1064562D01*
X1307024Y1064854D01*
X1306982Y1065145D01*
X1307065Y1065437D01*
X1307274Y1065645D01*
G01X1307600Y1069473D02*
X1311600D01*
Y1076873D01*
G01X1314811Y1054875D02*
X1312311D01*
Y1055916D01*
X1312436Y1056250D01*
X1312603Y1056458D01*
X1312936Y1056541D01*
X1313269Y1056458D01*
X1313478Y1056208D01*
X1313603Y1055916D01*
Y1054875D01*
G01Y1055916D02*
X1314811Y1056541D01*
G01X1312728Y1058016D02*
X1312478Y1058266D01*
X1312353Y1058558D01*
X1312311Y1058891D01*
X1312394Y1059308D01*
X1312603Y1059600D01*
X1312853Y1059683D01*
X1313103Y1059641D01*
X1313311Y1059475D01*
X1313728Y1058641D01*
X1314019Y1058266D01*
X1314436Y1058016D01*
X1314811Y1057933D01*
Y1059683D01*
G01Y1061825D02*
X1314269Y1061908D01*
X1313811Y1062033D01*
X1313394Y1062200D01*
X1312936Y1062408D01*
X1312311Y1062741D01*
Y1061075D01*
G01X1314519Y1064300D02*
X1314728Y1064591D01*
X1314811Y1064925D01*
X1314728Y1065258D01*
X1314478Y1065550D01*
X1314103Y1065758D01*
X1313728Y1065841D01*
X1313269D01*
X1312894Y1065758D01*
X1312561Y1065550D01*
X1312394Y1065300D01*
X1312311Y1065008D01*
X1312394Y1064675D01*
X1312561Y1064425D01*
X1312811Y1064258D01*
X1313144Y1064175D01*
X1313436Y1064258D01*
X1313728Y1064466D01*
X1313894Y1064716D01*
X1313936Y1065008D01*
X1313853Y1065341D01*
X1313644Y1065591D01*
X1313269Y1065841D01*
G01X1315400Y1069500D02*
X1319400D01*
Y1076900D01*
G01X1305782Y1054804D02*
X1303282D01*
Y1055845D01*
X1303407Y1056179D01*
X1303574Y1056387D01*
X1303907Y1056470D01*
X1304240Y1056387D01*
X1304449Y1056137D01*
X1304574Y1055845D01*
Y1054804D01*
G01Y1055845D02*
X1305782Y1056470D01*
G01X1303699Y1057945D02*
X1303449Y1058195D01*
X1303324Y1058487D01*
X1303282Y1058820D01*
X1303365Y1059237D01*
X1303574Y1059529D01*
X1303824Y1059612D01*
X1304074Y1059570D01*
X1304282Y1059404D01*
X1304699Y1058570D01*
X1304990Y1058195D01*
X1305407Y1057945D01*
X1305782Y1057862D01*
Y1059612D01*
G01Y1061837D02*
X1305740Y1062129D01*
X1305615Y1062462D01*
X1305407Y1062670D01*
X1305115Y1062754D01*
X1304824Y1062670D01*
X1304574Y1062420D01*
X1304449Y1062045D01*
Y1061629D01*
X1304365Y1061379D01*
X1304157Y1061170D01*
X1303865Y1061087D01*
X1303574Y1061212D01*
X1303365Y1061504D01*
X1303282Y1061837D01*
X1303365Y1062170D01*
X1303574Y1062462D01*
X1303865Y1062587D01*
X1304157Y1062504D01*
X1304365Y1062295D01*
X1304449Y1062045D01*
Y1061629D01*
X1304574Y1061254D01*
X1304824Y1061004D01*
X1305115Y1060920D01*
X1305407Y1061004D01*
X1305615Y1061212D01*
X1305740Y1061545D01*
X1305782Y1061837D01*
G01Y1064937D02*
X1303282D01*
X1303782Y1064437D01*
G01X1305782D02*
Y1065437D01*
G01X1307100Y1076873D02*
X1303100D01*
Y1069473D01*
G01X1324500Y1081873D02*
X1328500D01*
Y1089273D01*
G01X1320000Y1081873D02*
X1324000D01*
Y1089273D01*
G01X1299333Y1080900D02*
X1299291Y1080567D01*
X1299125Y1080275D01*
X1298875Y1080025D01*
X1298583Y1079858D01*
X1298250Y1079775D01*
X1297916D01*
X1297583Y1079858D01*
X1297291Y1080025D01*
X1297041Y1080275D01*
X1296875Y1080567D01*
X1296833Y1080900D01*
X1296875Y1081233D01*
X1297041Y1081525D01*
X1297291Y1081775D01*
X1297583Y1081942D01*
X1297916Y1082025D01*
X1298250D01*
X1298583Y1081942D01*
X1298875Y1081775D01*
X1299125Y1081525D01*
X1299291Y1081233D01*
X1299333Y1080900D01*
G01X1298666Y1081233D02*
X1299333Y1081733D01*
G01X1298833Y1083083D02*
X1299125Y1083333D01*
X1299291Y1083667D01*
X1299333Y1084042D01*
X1299291Y1084375D01*
X1299083Y1084708D01*
X1298833Y1084917D01*
X1298583Y1084958D01*
X1298291Y1084875D01*
X1298083Y1084583D01*
X1298000Y1084292D01*
Y1083917D01*
G01Y1084292D02*
X1297875Y1084542D01*
X1297666Y1084750D01*
X1297416Y1084833D01*
X1297166Y1084750D01*
X1296958Y1084542D01*
X1296833Y1084167D01*
X1296875Y1083792D01*
X1297041Y1083417D01*
G01X1299333Y1087017D02*
X1298791Y1087100D01*
X1298333Y1087225D01*
X1297916Y1087392D01*
X1297458Y1087600D01*
X1296833Y1087933D01*
Y1086267D01*
G01X1300800Y1089373D02*
Y1077973D01*
G01X1314200D02*
Y1089373D01*
G01X1300800Y1077973D02*
X1314200D01*
G01X1313700Y1094673D02*
Y1098673D01*
X1306300D01*
G01X1327300Y1102173D02*
Y1098173D01*
X1334700D01*
G01X1314200Y1089373D02*
X1300800D01*
G01X1336500Y1090173D02*
X1320400D01*
G01Y1097173D02*
X1336500D01*
G01X1320400Y1090173D02*
Y1097173D01*
G01X1315400Y1126500D02*
X1315067Y1126542D01*
X1314775Y1126708D01*
X1314525Y1126958D01*
X1314358Y1127250D01*
X1314275Y1127583D01*
Y1127917D01*
X1314358Y1128250D01*
X1314525Y1128542D01*
X1314775Y1128792D01*
X1315067Y1128958D01*
X1315400Y1129000D01*
X1315733Y1128958D01*
X1316025Y1128792D01*
X1316275Y1128542D01*
X1316442Y1128250D01*
X1316525Y1127917D01*
Y1127583D01*
X1316442Y1127250D01*
X1316275Y1126958D01*
X1316025Y1126708D01*
X1315733Y1126542D01*
X1315400Y1126500D01*
G01X1315733Y1127167D02*
X1316233Y1126500D01*
G01X1317583Y1127000D02*
X1317833Y1126708D01*
X1318167Y1126542D01*
X1318542Y1126500D01*
X1318875Y1126542D01*
X1319208Y1126750D01*
X1319417Y1127000D01*
X1319458Y1127250D01*
X1319375Y1127542D01*
X1319083Y1127750D01*
X1318792Y1127833D01*
X1318417D01*
G01X1318792D02*
X1319042Y1127958D01*
X1319250Y1128167D01*
X1319333Y1128417D01*
X1319250Y1128667D01*
X1319042Y1128875D01*
X1318667Y1129000D01*
X1318292Y1128958D01*
X1317917Y1128792D01*
G01X1320808Y1127542D02*
X1321100Y1127833D01*
X1321350Y1128000D01*
X1321683Y1128083D01*
X1321975Y1128000D01*
X1322183Y1127833D01*
X1322350Y1127583D01*
X1322392Y1127292D01*
X1322350Y1127042D01*
X1322183Y1126792D01*
X1321933Y1126583D01*
X1321642Y1126500D01*
X1321308Y1126583D01*
X1321017Y1126833D01*
X1320850Y1127208D01*
X1320808Y1127625D01*
X1320892Y1128167D01*
X1321017Y1128458D01*
X1321225Y1128750D01*
X1321517Y1128958D01*
X1321808Y1129000D01*
X1322100Y1128917D01*
X1322308Y1128708D01*
G01X1320500Y1124373D02*
X1318700Y1122273D01*
X1316500Y1124373D01*
G01X1312900Y1124473D02*
Y1105273D01*
X1324100D01*
Y1124473D01*
X1312900D01*
Y1124073D01*
G01X1300017Y1137500D02*
Y1140000D01*
X1301058D01*
X1301392Y1139875D01*
X1301600Y1139708D01*
X1301683Y1139375D01*
X1301600Y1139042D01*
X1301350Y1138833D01*
X1301058Y1138708D01*
X1300017D01*
G01X1301058D02*
X1301683Y1137500D01*
G01X1303158Y1139583D02*
X1303408Y1139833D01*
X1303700Y1139958D01*
X1304033Y1140000D01*
X1304450Y1139917D01*
X1304742Y1139708D01*
X1304825Y1139458D01*
X1304783Y1139208D01*
X1304617Y1139000D01*
X1303783Y1138583D01*
X1303408Y1138292D01*
X1303158Y1137875D01*
X1303075Y1137500D01*
X1304825D01*
G01X1306258Y1138542D02*
X1306550Y1138833D01*
X1306800Y1139000D01*
X1307133Y1139083D01*
X1307425Y1139000D01*
X1307633Y1138833D01*
X1307800Y1138583D01*
X1307842Y1138292D01*
X1307800Y1138042D01*
X1307633Y1137792D01*
X1307383Y1137583D01*
X1307092Y1137500D01*
X1306758Y1137583D01*
X1306467Y1137833D01*
X1306300Y1138208D01*
X1306258Y1138625D01*
X1306342Y1139167D01*
X1306467Y1139458D01*
X1306675Y1139750D01*
X1306967Y1139958D01*
X1307258Y1140000D01*
X1307550Y1139917D01*
X1307758Y1139708D01*
G01X1310067Y1137500D02*
X1310150Y1138042D01*
X1310275Y1138500D01*
X1310442Y1138917D01*
X1310650Y1139375D01*
X1310983Y1140000D01*
X1309317D01*
G01X1313800Y1150173D02*
Y1142173D01*
X1296200D01*
Y1150173D01*
X1313800D01*
G01X1316517Y1170500D02*
Y1173000D01*
X1317558D01*
X1317892Y1172875D01*
X1318100Y1172708D01*
X1318183Y1172375D01*
X1318100Y1172042D01*
X1317850Y1171833D01*
X1317558Y1171708D01*
X1316517D01*
G01X1317558D02*
X1318183Y1170500D01*
G01X1319658Y1172583D02*
X1319908Y1172833D01*
X1320200Y1172958D01*
X1320533Y1173000D01*
X1320950Y1172917D01*
X1321242Y1172708D01*
X1321325Y1172458D01*
X1321283Y1172208D01*
X1321117Y1172000D01*
X1320283Y1171583D01*
X1319908Y1171292D01*
X1319658Y1170875D01*
X1319575Y1170500D01*
X1321325D01*
G01X1323467D02*
X1323550Y1171042D01*
X1323675Y1171500D01*
X1323842Y1171917D01*
X1324050Y1172375D01*
X1324383Y1173000D01*
X1322717D01*
G01X1326650Y1170500D02*
Y1173000D01*
X1326150Y1172500D01*
G01Y1170500D02*
X1327150D01*
G01X1322075Y1182761D02*
Y1174761D01*
X1304475D01*
Y1182761D01*
X1322075D01*
G01X1301208Y1153767D02*
X1301083Y1153517D01*
X1301000Y1153225D01*
Y1152892D01*
X1301125Y1152517D01*
X1301333Y1152225D01*
X1301583Y1152017D01*
X1302000Y1151850D01*
X1302375Y1151808D01*
X1302750Y1151892D01*
X1303000Y1152017D01*
X1303250Y1152267D01*
X1303417Y1152558D01*
X1303500Y1152850D01*
Y1153142D01*
X1303417Y1153433D01*
X1303292Y1153683D01*
X1303125Y1153892D01*
G01X1303500Y1155950D02*
X1301000D01*
X1301500Y1155450D01*
G01X1303500D02*
Y1156450D01*
G01Y1159050D02*
X1301000D01*
X1301500Y1158550D01*
G01X1303500D02*
Y1159550D01*
G01X1303208Y1161442D02*
X1303417Y1161733D01*
X1303500Y1162067D01*
X1303417Y1162400D01*
X1303167Y1162692D01*
X1302792Y1162900D01*
X1302417Y1162983D01*
X1301958D01*
X1301583Y1162900D01*
X1301250Y1162692D01*
X1301083Y1162442D01*
X1301000Y1162150D01*
X1301083Y1161817D01*
X1301250Y1161567D01*
X1301500Y1161400D01*
X1301833Y1161317D01*
X1302125Y1161400D01*
X1302417Y1161608D01*
X1302583Y1161858D01*
X1302625Y1162150D01*
X1302542Y1162483D01*
X1302333Y1162733D01*
X1301958Y1162983D01*
G01X1304500Y1155873D02*
Y1161373D01*
G01X1312500Y1155873D02*
X1304500D01*
G01X1312500Y1161373D02*
Y1155873D01*
G01Y1173473D02*
Y1167973D01*
G01X1304500Y1173473D02*
X1312500D01*
G01X1304500Y1167973D02*
Y1173473D01*
G01X1330400Y1165166D02*
X1330067Y1165208D01*
X1329775Y1165374D01*
X1329525Y1165624D01*
X1329358Y1165916D01*
X1329275Y1166249D01*
Y1166583D01*
X1329358Y1166916D01*
X1329525Y1167208D01*
X1329775Y1167458D01*
X1330067Y1167624D01*
X1330400Y1167666D01*
X1330733Y1167624D01*
X1331025Y1167458D01*
X1331275Y1167208D01*
X1331442Y1166916D01*
X1331525Y1166583D01*
Y1166249D01*
X1331442Y1165916D01*
X1331275Y1165624D01*
X1331025Y1165374D01*
X1330733Y1165208D01*
X1330400Y1165166D01*
G01X1330733Y1165833D02*
X1331233Y1165166D01*
G01X1332583Y1165666D02*
X1332833Y1165374D01*
X1333167Y1165208D01*
X1333542Y1165166D01*
X1333875Y1165208D01*
X1334208Y1165416D01*
X1334417Y1165666D01*
X1334458Y1165916D01*
X1334375Y1166208D01*
X1334083Y1166416D01*
X1333792Y1166499D01*
X1333417D01*
G01X1333792D02*
X1334042Y1166624D01*
X1334250Y1166833D01*
X1334333Y1167083D01*
X1334250Y1167333D01*
X1334042Y1167541D01*
X1333667Y1167666D01*
X1333292Y1167624D01*
X1332917Y1167458D01*
G01X1336600Y1165166D02*
X1336892Y1165208D01*
X1337225Y1165333D01*
X1337433Y1165541D01*
X1337517Y1165833D01*
X1337433Y1166124D01*
X1337183Y1166374D01*
X1336808Y1166499D01*
X1336392D01*
X1336142Y1166583D01*
X1335933Y1166791D01*
X1335850Y1167083D01*
X1335975Y1167374D01*
X1336267Y1167583D01*
X1336600Y1167666D01*
X1336933Y1167583D01*
X1337225Y1167374D01*
X1337350Y1167083D01*
X1337267Y1166791D01*
X1337058Y1166583D01*
X1336808Y1166499D01*
X1336392D01*
X1336017Y1166374D01*
X1335767Y1166124D01*
X1335683Y1165833D01*
X1335767Y1165541D01*
X1335975Y1165333D01*
X1336308Y1165208D01*
X1336600Y1165166D01*
G01X1315300Y1151673D02*
X1317400Y1149873D01*
X1315300Y1147673D01*
G01X1315200Y1144073D02*
X1334400D01*
Y1155273D01*
X1315200D01*
Y1144073D01*
X1315600D01*
G01X1297708Y1176767D02*
X1297583Y1176517D01*
X1297500Y1176225D01*
Y1175892D01*
X1297625Y1175517D01*
X1297833Y1175225D01*
X1298083Y1175017D01*
X1298500Y1174850D01*
X1298875Y1174808D01*
X1299250Y1174892D01*
X1299500Y1175017D01*
X1299750Y1175267D01*
X1299917Y1175558D01*
X1300000Y1175850D01*
Y1176142D01*
X1299917Y1176433D01*
X1299792Y1176683D01*
X1299625Y1176892D01*
G01X1300000Y1178950D02*
X1297500D01*
X1298000Y1178450D01*
G01X1300000D02*
Y1179450D01*
G01Y1182050D02*
X1297500D01*
X1298000Y1181550D01*
G01X1300000D02*
Y1182550D01*
G01Y1185150D02*
X1299958Y1185442D01*
X1299833Y1185775D01*
X1299625Y1185983D01*
X1299333Y1186067D01*
X1299042Y1185983D01*
X1298792Y1185733D01*
X1298667Y1185358D01*
Y1184942D01*
X1298583Y1184692D01*
X1298375Y1184483D01*
X1298083Y1184400D01*
X1297792Y1184525D01*
X1297583Y1184817D01*
X1297500Y1185150D01*
X1297583Y1185483D01*
X1297792Y1185775D01*
X1298083Y1185900D01*
X1298375Y1185817D01*
X1298583Y1185608D01*
X1298667Y1185358D01*
Y1184942D01*
X1298792Y1184567D01*
X1299042Y1184317D01*
X1299333Y1184233D01*
X1299625Y1184317D01*
X1299833Y1184525D01*
X1299958Y1184858D01*
X1300000Y1185150D01*
G01X1326708Y1192767D02*
X1326583Y1192517D01*
X1326500Y1192225D01*
Y1191892D01*
X1326625Y1191517D01*
X1326833Y1191225D01*
X1327083Y1191017D01*
X1327500Y1190850D01*
X1327875Y1190808D01*
X1328250Y1190892D01*
X1328500Y1191017D01*
X1328750Y1191267D01*
X1328917Y1191558D01*
X1329000Y1191850D01*
Y1192142D01*
X1328917Y1192433D01*
X1328792Y1192683D01*
X1328625Y1192892D01*
G01X1329000Y1194950D02*
X1326500D01*
X1327000Y1194450D01*
G01X1329000D02*
Y1195450D01*
G01X1326917Y1197258D02*
X1326667Y1197508D01*
X1326542Y1197800D01*
X1326500Y1198133D01*
X1326583Y1198550D01*
X1326792Y1198842D01*
X1327042Y1198925D01*
X1327292Y1198883D01*
X1327500Y1198717D01*
X1327917Y1197883D01*
X1328208Y1197508D01*
X1328625Y1197258D01*
X1329000Y1197175D01*
Y1198925D01*
G01X1328500Y1200233D02*
X1328792Y1200483D01*
X1328958Y1200817D01*
X1329000Y1201192D01*
X1328958Y1201525D01*
X1328750Y1201858D01*
X1328500Y1202067D01*
X1328250Y1202108D01*
X1327958Y1202025D01*
X1327750Y1201733D01*
X1327667Y1201442D01*
Y1201067D01*
G01Y1201442D02*
X1327542Y1201692D01*
X1327333Y1201900D01*
X1327083Y1201983D01*
X1326833Y1201900D01*
X1326625Y1201692D01*
X1326500Y1201317D01*
X1326542Y1200942D01*
X1326708Y1200567D01*
G01X1322708Y1192767D02*
X1322583Y1192517D01*
X1322500Y1192225D01*
Y1191892D01*
X1322625Y1191517D01*
X1322833Y1191225D01*
X1323083Y1191017D01*
X1323500Y1190850D01*
X1323875Y1190808D01*
X1324250Y1190892D01*
X1324500Y1191017D01*
X1324750Y1191267D01*
X1324917Y1191558D01*
X1325000Y1191850D01*
Y1192142D01*
X1324917Y1192433D01*
X1324792Y1192683D01*
X1324625Y1192892D01*
G01X1325000Y1194950D02*
X1322500D01*
X1323000Y1194450D01*
G01X1325000D02*
Y1195450D01*
G01X1322917Y1197258D02*
X1322667Y1197508D01*
X1322542Y1197800D01*
X1322500Y1198133D01*
X1322583Y1198550D01*
X1322792Y1198842D01*
X1323042Y1198925D01*
X1323292Y1198883D01*
X1323500Y1198717D01*
X1323917Y1197883D01*
X1324208Y1197508D01*
X1324625Y1197258D01*
X1325000Y1197175D01*
Y1198925D01*
G01X1322917Y1200358D02*
X1322667Y1200608D01*
X1322542Y1200900D01*
X1322500Y1201233D01*
X1322583Y1201650D01*
X1322792Y1201942D01*
X1323042Y1202025D01*
X1323292Y1201983D01*
X1323500Y1201817D01*
X1323917Y1200983D01*
X1324208Y1200608D01*
X1324625Y1200358D01*
X1325000Y1200275D01*
Y1202025D01*
G01X1318708Y1192940D02*
X1318583Y1192690D01*
X1318500Y1192398D01*
Y1192065D01*
X1318625Y1191690D01*
X1318833Y1191398D01*
X1319083Y1191190D01*
X1319500Y1191023D01*
X1319875Y1190981D01*
X1320250Y1191065D01*
X1320500Y1191190D01*
X1320750Y1191440D01*
X1320917Y1191731D01*
X1321000Y1192023D01*
Y1192315D01*
X1320917Y1192606D01*
X1320792Y1192856D01*
X1320625Y1193065D01*
G01X1321000Y1195123D02*
X1318500D01*
X1319000Y1194623D01*
G01X1321000D02*
Y1195623D01*
G01X1318917Y1197431D02*
X1318667Y1197681D01*
X1318542Y1197973D01*
X1318500Y1198306D01*
X1318583Y1198723D01*
X1318792Y1199015D01*
X1319042Y1199098D01*
X1319292Y1199056D01*
X1319500Y1198890D01*
X1319917Y1198056D01*
X1320208Y1197681D01*
X1320625Y1197431D01*
X1321000Y1197348D01*
Y1199098D01*
G01X1320625Y1200406D02*
X1320833Y1200656D01*
X1320958Y1200948D01*
X1321000Y1201323D01*
X1320917Y1201698D01*
X1320750Y1201990D01*
X1320458Y1202198D01*
X1320125Y1202240D01*
X1319792Y1202156D01*
X1319583Y1201948D01*
X1319417Y1201656D01*
X1319375Y1201365D01*
X1319417Y1201073D01*
X1319583Y1200698D01*
X1318500Y1200823D01*
Y1201948D01*
G01X1335983Y66667D02*
Y64875D01*
X1336150Y64500D01*
X1336483Y64250D01*
X1336900Y64167D01*
X1337317Y64250D01*
X1337650Y64500D01*
X1337817Y64875D01*
Y66667D01*
G01X1339208Y66250D02*
X1339458Y66500D01*
X1339750Y66625D01*
X1340083Y66667D01*
X1340500Y66584D01*
X1340792Y66375D01*
X1340875Y66125D01*
X1340833Y65875D01*
X1340667Y65667D01*
X1339833Y65250D01*
X1339458Y64959D01*
X1339208Y64542D01*
X1339125Y64167D01*
X1340875D01*
G01X1342392Y64459D02*
X1342683Y64250D01*
X1343017Y64167D01*
X1343350Y64250D01*
X1343642Y64500D01*
X1343850Y64875D01*
X1343933Y65250D01*
Y65709D01*
X1343850Y66084D01*
X1343642Y66417D01*
X1343392Y66584D01*
X1343100Y66667D01*
X1342767Y66584D01*
X1342517Y66417D01*
X1342350Y66167D01*
X1342267Y65834D01*
X1342350Y65542D01*
X1342558Y65250D01*
X1342808Y65084D01*
X1343100Y65042D01*
X1343433Y65125D01*
X1343683Y65334D01*
X1343933Y65709D01*
G01X1333295Y75079D02*
Y61679D01*
G01X1362137Y78705D02*
X1359637D01*
Y79746D01*
X1359762Y80080D01*
X1359929Y80288D01*
X1360262Y80371D01*
X1360595Y80288D01*
X1360804Y80038D01*
X1360929Y79746D01*
Y78705D01*
G01Y79746D02*
X1362137Y80371D01*
G01Y83138D02*
X1359637D01*
X1361429Y81596D01*
Y83680D01*
G01X1361762Y84821D02*
X1361970Y85071D01*
X1362095Y85363D01*
X1362137Y85738D01*
X1362054Y86113D01*
X1361887Y86405D01*
X1361595Y86613D01*
X1361262Y86655D01*
X1360929Y86571D01*
X1360720Y86363D01*
X1360554Y86071D01*
X1360512Y85780D01*
X1360554Y85488D01*
X1360720Y85113D01*
X1359637Y85238D01*
Y86363D01*
G01X1361762Y87921D02*
X1361970Y88171D01*
X1362095Y88463D01*
X1362137Y88838D01*
X1362054Y89213D01*
X1361887Y89505D01*
X1361595Y89713D01*
X1361262Y89755D01*
X1360929Y89671D01*
X1360720Y89463D01*
X1360554Y89171D01*
X1360512Y88880D01*
X1360554Y88588D01*
X1360720Y88213D01*
X1359637Y88338D01*
Y89463D01*
G01X1356437Y86938D02*
X1352437D01*
Y79538D01*
G01X1357483Y110667D02*
Y108875D01*
X1357650Y108500D01*
X1357983Y108250D01*
X1358400Y108167D01*
X1358817Y108250D01*
X1359150Y108500D01*
X1359317Y108875D01*
Y110667D01*
G01X1361500Y108167D02*
Y110667D01*
X1361000Y110167D01*
G01Y108167D02*
X1362000D01*
G01X1363892Y108459D02*
X1364183Y108250D01*
X1364517Y108167D01*
X1364850Y108250D01*
X1365142Y108500D01*
X1365350Y108875D01*
X1365433Y109250D01*
Y109709D01*
X1365350Y110084D01*
X1365142Y110417D01*
X1364892Y110584D01*
X1364600Y110667D01*
X1364267Y110584D01*
X1364017Y110417D01*
X1363850Y110167D01*
X1363767Y109834D01*
X1363850Y109542D01*
X1364058Y109250D01*
X1364308Y109084D01*
X1364600Y109042D01*
X1364933Y109125D01*
X1365183Y109334D01*
X1365433Y109709D01*
G01X1330934Y128388D02*
X1334934D01*
Y135788D01*
G01X1339634D02*
X1335634D01*
Y128388D01*
G01X1355017Y125167D02*
Y127667D01*
X1356058D01*
X1356392Y127542D01*
X1356600Y127375D01*
X1356683Y127042D01*
X1356600Y126709D01*
X1356350Y126500D01*
X1356058Y126375D01*
X1355017D01*
G01X1356058D02*
X1356683Y125167D01*
G01X1358033Y125667D02*
X1358283Y125375D01*
X1358617Y125209D01*
X1358992Y125167D01*
X1359325Y125209D01*
X1359658Y125417D01*
X1359867Y125667D01*
X1359908Y125917D01*
X1359825Y126209D01*
X1359533Y126417D01*
X1359242Y126500D01*
X1358867D01*
G01X1359242D02*
X1359492Y126625D01*
X1359700Y126834D01*
X1359783Y127084D01*
X1359700Y127334D01*
X1359492Y127542D01*
X1359117Y127667D01*
X1358742Y127625D01*
X1358367Y127459D01*
G01X1361967Y125167D02*
X1362050Y125709D01*
X1362175Y126167D01*
X1362342Y126584D01*
X1362550Y127042D01*
X1362883Y127667D01*
X1361217D01*
G01X1364442Y125459D02*
X1364733Y125250D01*
X1365067Y125167D01*
X1365400Y125250D01*
X1365692Y125500D01*
X1365900Y125875D01*
X1365983Y126250D01*
Y126709D01*
X1365900Y127084D01*
X1365692Y127417D01*
X1365442Y127584D01*
X1365150Y127667D01*
X1364817Y127584D01*
X1364567Y127417D01*
X1364400Y127167D01*
X1364317Y126834D01*
X1364400Y126542D01*
X1364608Y126250D01*
X1364858Y126084D01*
X1365150Y126042D01*
X1365483Y126125D01*
X1365733Y126334D01*
X1365983Y126709D01*
G01X1340303Y135842D02*
Y131842D01*
X1347703D01*
G01X1333017Y164667D02*
Y167167D01*
X1334058D01*
X1334392Y167042D01*
X1334600Y166875D01*
X1334683Y166542D01*
X1334600Y166209D01*
X1334350Y166000D01*
X1334058Y165875D01*
X1333017D01*
G01X1334058D02*
X1334683Y164667D01*
G01X1336950D02*
X1337242Y164709D01*
X1337575Y164834D01*
X1337783Y165042D01*
X1337867Y165334D01*
X1337783Y165625D01*
X1337533Y165875D01*
X1337158Y166000D01*
X1336742D01*
X1336492Y166084D01*
X1336283Y166292D01*
X1336200Y166584D01*
X1336325Y166875D01*
X1336617Y167084D01*
X1336950Y167167D01*
X1337283Y167084D01*
X1337575Y166875D01*
X1337700Y166584D01*
X1337617Y166292D01*
X1337408Y166084D01*
X1337158Y166000D01*
X1336742D01*
X1336367Y165875D01*
X1336117Y165625D01*
X1336033Y165334D01*
X1336117Y165042D01*
X1336325Y164834D01*
X1336658Y164709D01*
X1336950Y164667D01*
G01X1339133Y165167D02*
X1339383Y164875D01*
X1339717Y164709D01*
X1340092Y164667D01*
X1340425Y164709D01*
X1340758Y164917D01*
X1340967Y165167D01*
X1341008Y165417D01*
X1340925Y165709D01*
X1340633Y165917D01*
X1340342Y166000D01*
X1339967D01*
G01X1340342D02*
X1340592Y166125D01*
X1340800Y166334D01*
X1340883Y166584D01*
X1340800Y166834D01*
X1340592Y167042D01*
X1340217Y167167D01*
X1339842Y167125D01*
X1339467Y166959D01*
G01X1343150Y164667D02*
Y167167D01*
X1342650Y166667D01*
G01Y164667D02*
X1343650D01*
G01X1339517Y189661D02*
Y192161D01*
X1340558D01*
X1340892Y192036D01*
X1341100Y191869D01*
X1341183Y191536D01*
X1341100Y191203D01*
X1340850Y190994D01*
X1340558Y190869D01*
X1339517D01*
G01X1340558D02*
X1341183Y189661D01*
G01X1343450D02*
X1343742Y189703D01*
X1344075Y189828D01*
X1344283Y190036D01*
X1344367Y190328D01*
X1344283Y190619D01*
X1344033Y190869D01*
X1343658Y190994D01*
X1343242D01*
X1342992Y191078D01*
X1342783Y191286D01*
X1342700Y191578D01*
X1342825Y191869D01*
X1343117Y192078D01*
X1343450Y192161D01*
X1343783Y192078D01*
X1344075Y191869D01*
X1344200Y191578D01*
X1344117Y191286D01*
X1343908Y191078D01*
X1343658Y190994D01*
X1343242D01*
X1342867Y190869D01*
X1342617Y190619D01*
X1342533Y190328D01*
X1342617Y190036D01*
X1342825Y189828D01*
X1343158Y189703D01*
X1343450Y189661D01*
G01X1345758Y191744D02*
X1346008Y191994D01*
X1346300Y192119D01*
X1346633Y192161D01*
X1347050Y192078D01*
X1347342Y191869D01*
X1347425Y191619D01*
X1347383Y191369D01*
X1347217Y191161D01*
X1346383Y190744D01*
X1346008Y190453D01*
X1345758Y190036D01*
X1345675Y189661D01*
X1347425D01*
G01X1349567D02*
X1349650Y190203D01*
X1349775Y190661D01*
X1349942Y191078D01*
X1350150Y191536D01*
X1350483Y192161D01*
X1348817D01*
G01X1339400Y171417D02*
X1336900D01*
Y172458D01*
X1337025Y172792D01*
X1337192Y173000D01*
X1337525Y173083D01*
X1337858Y173000D01*
X1338067Y172750D01*
X1338192Y172458D01*
Y171417D01*
G01Y172458D02*
X1339400Y173083D01*
G01Y175350D02*
X1339358Y175642D01*
X1339233Y175975D01*
X1339025Y176183D01*
X1338733Y176267D01*
X1338442Y176183D01*
X1338192Y175933D01*
X1338067Y175558D01*
Y175142D01*
X1337983Y174892D01*
X1337775Y174683D01*
X1337483Y174600D01*
X1337192Y174725D01*
X1336983Y175017D01*
X1336900Y175350D01*
X1336983Y175683D01*
X1337192Y175975D01*
X1337483Y176100D01*
X1337775Y176017D01*
X1337983Y175808D01*
X1338067Y175558D01*
Y175142D01*
X1338192Y174767D01*
X1338442Y174517D01*
X1338733Y174433D01*
X1339025Y174517D01*
X1339233Y174725D01*
X1339358Y175058D01*
X1339400Y175350D01*
G01X1338900Y177533D02*
X1339192Y177783D01*
X1339358Y178117D01*
X1339400Y178492D01*
X1339358Y178825D01*
X1339150Y179158D01*
X1338900Y179367D01*
X1338650Y179408D01*
X1338358Y179325D01*
X1338150Y179033D01*
X1338067Y178742D01*
Y178367D01*
G01Y178742D02*
X1337942Y178992D01*
X1337733Y179200D01*
X1337483Y179283D01*
X1337233Y179200D01*
X1337025Y178992D01*
X1336900Y178617D01*
X1336942Y178242D01*
X1337108Y177867D01*
G01X1339400Y182050D02*
X1336900D01*
X1338692Y180508D01*
Y182592D01*
G01X1353017Y193500D02*
Y196000D01*
X1354058D01*
X1354392Y195875D01*
X1354600Y195708D01*
X1354683Y195375D01*
X1354600Y195042D01*
X1354350Y194833D01*
X1354058Y194708D01*
X1353017D01*
G01X1354058D02*
X1354683Y193500D01*
G01X1356950D02*
X1357242Y193542D01*
X1357575Y193667D01*
X1357783Y193875D01*
X1357867Y194167D01*
X1357783Y194458D01*
X1357533Y194708D01*
X1357158Y194833D01*
X1356742D01*
X1356492Y194917D01*
X1356283Y195125D01*
X1356200Y195417D01*
X1356325Y195708D01*
X1356617Y195917D01*
X1356950Y196000D01*
X1357283Y195917D01*
X1357575Y195708D01*
X1357700Y195417D01*
X1357617Y195125D01*
X1357408Y194917D01*
X1357158Y194833D01*
X1356742D01*
X1356367Y194708D01*
X1356117Y194458D01*
X1356033Y194167D01*
X1356117Y193875D01*
X1356325Y193667D01*
X1356658Y193542D01*
X1356950Y193500D01*
G01X1359133Y194000D02*
X1359383Y193708D01*
X1359717Y193542D01*
X1360092Y193500D01*
X1360425Y193542D01*
X1360758Y193750D01*
X1360967Y194000D01*
X1361008Y194250D01*
X1360925Y194542D01*
X1360633Y194750D01*
X1360342Y194833D01*
X1359967D01*
G01X1360342D02*
X1360592Y194958D01*
X1360800Y195167D01*
X1360883Y195417D01*
X1360800Y195667D01*
X1360592Y195875D01*
X1360217Y196000D01*
X1359842Y195958D01*
X1359467Y195792D01*
G01X1362358Y194542D02*
X1362650Y194833D01*
X1362900Y195000D01*
X1363233Y195083D01*
X1363525Y195000D01*
X1363733Y194833D01*
X1363900Y194583D01*
X1363942Y194292D01*
X1363900Y194042D01*
X1363733Y193792D01*
X1363483Y193583D01*
X1363192Y193500D01*
X1362858Y193583D01*
X1362567Y193833D01*
X1362400Y194208D01*
X1362358Y194625D01*
X1362442Y195167D01*
X1362567Y195458D01*
X1362775Y195750D01*
X1363067Y195958D01*
X1363358Y196000D01*
X1363650Y195917D01*
X1363858Y195708D01*
G01X1335734Y171417D02*
X1333234D01*
Y172458D01*
X1333359Y172792D01*
X1333526Y173000D01*
X1333859Y173083D01*
X1334192Y173000D01*
X1334401Y172750D01*
X1334526Y172458D01*
Y171417D01*
G01Y172458D02*
X1335734Y173083D01*
G01Y175350D02*
X1335692Y175642D01*
X1335567Y175975D01*
X1335359Y176183D01*
X1335067Y176267D01*
X1334776Y176183D01*
X1334526Y175933D01*
X1334401Y175558D01*
Y175142D01*
X1334317Y174892D01*
X1334109Y174683D01*
X1333817Y174600D01*
X1333526Y174725D01*
X1333317Y175017D01*
X1333234Y175350D01*
X1333317Y175683D01*
X1333526Y175975D01*
X1333817Y176100D01*
X1334109Y176017D01*
X1334317Y175808D01*
X1334401Y175558D01*
Y175142D01*
X1334526Y174767D01*
X1334776Y174517D01*
X1335067Y174433D01*
X1335359Y174517D01*
X1335567Y174725D01*
X1335692Y175058D01*
X1335734Y175350D01*
G01X1335234Y177533D02*
X1335526Y177783D01*
X1335692Y178117D01*
X1335734Y178492D01*
X1335692Y178825D01*
X1335484Y179158D01*
X1335234Y179367D01*
X1334984Y179408D01*
X1334692Y179325D01*
X1334484Y179033D01*
X1334401Y178742D01*
Y178367D01*
G01Y178742D02*
X1334276Y178992D01*
X1334067Y179200D01*
X1333817Y179283D01*
X1333567Y179200D01*
X1333359Y178992D01*
X1333234Y178617D01*
X1333276Y178242D01*
X1333442Y177867D01*
G01X1335734Y181467D02*
X1335192Y181550D01*
X1334734Y181675D01*
X1334317Y181842D01*
X1333859Y182050D01*
X1333234Y182383D01*
Y180717D01*
G01X1352983Y189661D02*
Y192161D01*
X1353817D01*
X1354150Y192036D01*
X1354400Y191869D01*
X1354608Y191619D01*
X1354775Y191328D01*
X1354817Y190911D01*
X1354775Y190494D01*
X1354608Y190203D01*
X1354400Y189953D01*
X1354150Y189786D01*
X1353817Y189661D01*
X1352983D01*
G01X1356083Y190161D02*
X1356333Y189869D01*
X1356667Y189703D01*
X1357042Y189661D01*
X1357375Y189703D01*
X1357708Y189911D01*
X1357917Y190161D01*
X1357958Y190411D01*
X1357875Y190703D01*
X1357583Y190911D01*
X1357292Y190994D01*
X1356917D01*
G01X1357292D02*
X1357542Y191119D01*
X1357750Y191328D01*
X1357833Y191578D01*
X1357750Y191828D01*
X1357542Y192036D01*
X1357167Y192161D01*
X1356792Y192119D01*
X1356417Y191953D01*
G01X1360100Y192161D02*
X1359767Y192078D01*
X1359517Y191869D01*
X1359350Y191619D01*
X1359225Y191286D01*
X1359183Y190911D01*
X1359225Y190536D01*
X1359350Y190203D01*
X1359517Y189953D01*
X1359767Y189744D01*
X1360100Y189661D01*
X1360433Y189744D01*
X1360683Y189953D01*
X1360850Y190203D01*
X1360975Y190536D01*
X1361017Y190911D01*
X1360975Y191286D01*
X1360850Y191619D01*
X1360683Y191869D01*
X1360433Y192078D01*
X1360100Y192161D01*
G01X1336500Y191661D02*
Y184661D01*
G01X1368758Y172684D02*
X1368508Y172809D01*
X1368216Y172892D01*
X1367883D01*
X1367508Y172767D01*
X1367216Y172559D01*
X1367008Y172309D01*
X1366841Y171892D01*
X1366799Y171517D01*
X1366883Y171142D01*
X1367008Y170892D01*
X1367258Y170642D01*
X1367549Y170475D01*
X1367841Y170392D01*
X1368133D01*
X1368424Y170475D01*
X1368674Y170600D01*
X1368883Y170767D01*
G01X1371441Y170392D02*
Y172892D01*
X1369899Y171100D01*
X1371983D01*
G01X1374541Y170392D02*
Y172892D01*
X1372999Y171100D01*
X1375083D01*
G01X1376349Y172475D02*
X1376599Y172725D01*
X1376891Y172850D01*
X1377224Y172892D01*
X1377641Y172809D01*
X1377933Y172600D01*
X1378016Y172350D01*
X1377974Y172100D01*
X1377808Y171892D01*
X1376974Y171475D01*
X1376599Y171184D01*
X1376349Y170767D01*
X1376266Y170392D01*
X1378016D01*
G01X1368767Y176792D02*
X1368517Y176917D01*
X1368225Y177000D01*
X1367892D01*
X1367517Y176875D01*
X1367225Y176667D01*
X1367017Y176417D01*
X1366850Y176000D01*
X1366808Y175625D01*
X1366892Y175250D01*
X1367017Y175000D01*
X1367267Y174750D01*
X1367558Y174583D01*
X1367850Y174500D01*
X1368142D01*
X1368433Y174583D01*
X1368683Y174708D01*
X1368892Y174875D01*
G01X1371450Y174500D02*
Y177000D01*
X1369908Y175208D01*
X1371992D01*
G01X1374550Y174500D02*
Y177000D01*
X1373008Y175208D01*
X1375092D01*
G01X1377150Y174500D02*
Y177000D01*
X1376650Y176500D01*
G01Y174500D02*
X1377650D01*
G01X1341267Y196053D02*
X1341017Y196178D01*
X1340725Y196261D01*
X1340392D01*
X1340017Y196136D01*
X1339725Y195928D01*
X1339517Y195678D01*
X1339350Y195261D01*
X1339308Y194886D01*
X1339392Y194511D01*
X1339517Y194261D01*
X1339767Y194011D01*
X1340058Y193844D01*
X1340350Y193761D01*
X1340642D01*
X1340933Y193844D01*
X1341183Y193969D01*
X1341392Y194136D01*
G01X1343950Y193761D02*
Y196261D01*
X1342408Y194469D01*
X1344492D01*
G01X1345633Y194261D02*
X1345883Y193969D01*
X1346217Y193803D01*
X1346592Y193761D01*
X1346925Y193803D01*
X1347258Y194011D01*
X1347467Y194261D01*
X1347508Y194511D01*
X1347425Y194803D01*
X1347133Y195011D01*
X1346842Y195094D01*
X1346467D01*
G01X1346842D02*
X1347092Y195219D01*
X1347300Y195428D01*
X1347383Y195678D01*
X1347300Y195928D01*
X1347092Y196136D01*
X1346717Y196261D01*
X1346342Y196219D01*
X1345967Y196053D01*
G01X1349650Y193761D02*
X1349942Y193803D01*
X1350275Y193928D01*
X1350483Y194136D01*
X1350567Y194428D01*
X1350483Y194719D01*
X1350233Y194969D01*
X1349858Y195094D01*
X1349442D01*
X1349192Y195178D01*
X1348983Y195386D01*
X1348900Y195678D01*
X1349025Y195969D01*
X1349317Y196178D01*
X1349650Y196261D01*
X1349983Y196178D01*
X1350275Y195969D01*
X1350400Y195678D01*
X1350317Y195386D01*
X1350108Y195178D01*
X1349858Y195094D01*
X1349442D01*
X1349067Y194969D01*
X1348817Y194719D01*
X1348733Y194428D01*
X1348817Y194136D01*
X1349025Y193928D01*
X1349358Y193803D01*
X1349650Y193761D01*
G01X1339517Y222161D02*
Y224661D01*
X1340558D01*
X1340892Y224536D01*
X1341100Y224369D01*
X1341183Y224036D01*
X1341100Y223703D01*
X1340850Y223494D01*
X1340558Y223369D01*
X1339517D01*
G01X1340558D02*
X1341183Y222161D01*
G01X1343450D02*
X1343742Y222203D01*
X1344075Y222328D01*
X1344283Y222536D01*
X1344367Y222828D01*
X1344283Y223119D01*
X1344033Y223369D01*
X1343658Y223494D01*
X1343242D01*
X1342992Y223578D01*
X1342783Y223786D01*
X1342700Y224078D01*
X1342825Y224369D01*
X1343117Y224578D01*
X1343450Y224661D01*
X1343783Y224578D01*
X1344075Y224369D01*
X1344200Y224078D01*
X1344117Y223786D01*
X1343908Y223578D01*
X1343658Y223494D01*
X1343242D01*
X1342867Y223369D01*
X1342617Y223119D01*
X1342533Y222828D01*
X1342617Y222536D01*
X1342825Y222328D01*
X1343158Y222203D01*
X1343450Y222161D01*
G01X1345633Y222661D02*
X1345883Y222369D01*
X1346217Y222203D01*
X1346592Y222161D01*
X1346925Y222203D01*
X1347258Y222411D01*
X1347467Y222661D01*
X1347508Y222911D01*
X1347425Y223203D01*
X1347133Y223411D01*
X1346842Y223494D01*
X1346467D01*
G01X1346842D02*
X1347092Y223619D01*
X1347300Y223828D01*
X1347383Y224078D01*
X1347300Y224328D01*
X1347092Y224536D01*
X1346717Y224661D01*
X1346342Y224619D01*
X1345967Y224453D01*
G01X1348733Y222536D02*
X1348983Y222328D01*
X1349275Y222203D01*
X1349650Y222161D01*
X1350025Y222244D01*
X1350317Y222411D01*
X1350525Y222703D01*
X1350567Y223036D01*
X1350483Y223369D01*
X1350275Y223578D01*
X1349983Y223744D01*
X1349692Y223786D01*
X1349400Y223744D01*
X1349025Y223578D01*
X1349150Y224661D01*
X1350275D01*
G01X1337200Y221661D02*
Y225661D01*
X1329800D01*
G01X1362808Y244171D02*
Y246671D01*
X1363849D01*
X1364183Y246546D01*
X1364391Y246379D01*
X1364474Y246046D01*
X1364391Y245713D01*
X1364141Y245504D01*
X1363849Y245379D01*
X1362808D01*
G01X1363849D02*
X1364474Y244171D01*
G01X1366741D02*
X1367033Y244213D01*
X1367366Y244338D01*
X1367574Y244546D01*
X1367658Y244838D01*
X1367574Y245129D01*
X1367324Y245379D01*
X1366949Y245504D01*
X1366533D01*
X1366283Y245588D01*
X1366074Y245796D01*
X1365991Y246088D01*
X1366116Y246379D01*
X1366408Y246588D01*
X1366741Y246671D01*
X1367074Y246588D01*
X1367366Y246379D01*
X1367491Y246088D01*
X1367408Y245796D01*
X1367199Y245588D01*
X1366949Y245504D01*
X1366533D01*
X1366158Y245379D01*
X1365908Y245129D01*
X1365824Y244838D01*
X1365908Y244546D01*
X1366116Y244338D01*
X1366449Y244213D01*
X1366741Y244171D01*
G01X1370341D02*
Y246671D01*
X1368799Y244879D01*
X1370883D01*
G01X1372024Y244671D02*
X1372274Y244379D01*
X1372608Y244213D01*
X1372983Y244171D01*
X1373316Y244213D01*
X1373649Y244421D01*
X1373858Y244671D01*
X1373899Y244921D01*
X1373816Y245213D01*
X1373524Y245421D01*
X1373233Y245504D01*
X1372858D01*
G01X1373233D02*
X1373483Y245629D01*
X1373691Y245838D01*
X1373774Y246088D01*
X1373691Y246338D01*
X1373483Y246546D01*
X1373108Y246671D01*
X1372733Y246629D01*
X1372358Y246463D01*
G01X1360017Y255000D02*
Y257500D01*
X1361058D01*
X1361392Y257375D01*
X1361600Y257208D01*
X1361683Y256875D01*
X1361600Y256542D01*
X1361350Y256333D01*
X1361058Y256208D01*
X1360017D01*
G01X1361058D02*
X1361683Y255000D01*
G01X1363950D02*
X1364242Y255042D01*
X1364575Y255167D01*
X1364783Y255375D01*
X1364867Y255667D01*
X1364783Y255958D01*
X1364533Y256208D01*
X1364158Y256333D01*
X1363742D01*
X1363492Y256417D01*
X1363283Y256625D01*
X1363200Y256917D01*
X1363325Y257208D01*
X1363617Y257417D01*
X1363950Y257500D01*
X1364283Y257417D01*
X1364575Y257208D01*
X1364700Y256917D01*
X1364617Y256625D01*
X1364408Y256417D01*
X1364158Y256333D01*
X1363742D01*
X1363367Y256208D01*
X1363117Y255958D01*
X1363033Y255667D01*
X1363117Y255375D01*
X1363325Y255167D01*
X1363658Y255042D01*
X1363950Y255000D01*
G01X1367550D02*
Y257500D01*
X1366008Y255708D01*
X1368092D01*
G01X1370067Y255000D02*
X1370150Y255542D01*
X1370275Y256000D01*
X1370442Y256417D01*
X1370650Y256875D01*
X1370983Y257500D01*
X1369317D01*
G01X1364480Y241953D02*
X1364230Y242078D01*
X1363938Y242161D01*
X1363605D01*
X1363230Y242036D01*
X1362938Y241828D01*
X1362730Y241578D01*
X1362563Y241161D01*
X1362521Y240786D01*
X1362605Y240411D01*
X1362730Y240161D01*
X1362980Y239911D01*
X1363271Y239744D01*
X1363563Y239661D01*
X1363855D01*
X1364146Y239744D01*
X1364396Y239869D01*
X1364605Y240036D01*
G01X1367163Y239661D02*
Y242161D01*
X1365621Y240369D01*
X1367705D01*
G01X1370263Y239661D02*
Y242161D01*
X1368721Y240369D01*
X1370805D01*
G01X1372155Y239953D02*
X1372446Y239744D01*
X1372780Y239661D01*
X1373113Y239744D01*
X1373405Y239994D01*
X1373613Y240369D01*
X1373696Y240744D01*
Y241203D01*
X1373613Y241578D01*
X1373405Y241911D01*
X1373155Y242078D01*
X1372863Y242161D01*
X1372530Y242078D01*
X1372280Y241911D01*
X1372113Y241661D01*
X1372030Y241328D01*
X1372113Y241036D01*
X1372321Y240744D01*
X1372571Y240578D01*
X1372863Y240536D01*
X1373196Y240619D01*
X1373446Y240828D01*
X1373696Y241203D01*
G01X1341267Y228553D02*
X1341017Y228678D01*
X1340725Y228761D01*
X1340392D01*
X1340017Y228636D01*
X1339725Y228428D01*
X1339517Y228178D01*
X1339350Y227761D01*
X1339308Y227386D01*
X1339392Y227011D01*
X1339517Y226761D01*
X1339767Y226511D01*
X1340058Y226344D01*
X1340350Y226261D01*
X1340642D01*
X1340933Y226344D01*
X1341183Y226469D01*
X1341392Y226636D01*
G01X1343950Y226261D02*
Y228761D01*
X1342408Y226969D01*
X1344492D01*
G01X1345633Y226761D02*
X1345883Y226469D01*
X1346217Y226303D01*
X1346592Y226261D01*
X1346925Y226303D01*
X1347258Y226511D01*
X1347467Y226761D01*
X1347508Y227011D01*
X1347425Y227303D01*
X1347133Y227511D01*
X1346842Y227594D01*
X1346467D01*
G01X1346842D02*
X1347092Y227719D01*
X1347300Y227928D01*
X1347383Y228178D01*
X1347300Y228428D01*
X1347092Y228636D01*
X1346717Y228761D01*
X1346342Y228719D01*
X1345967Y228553D01*
G01X1348942Y226553D02*
X1349233Y226344D01*
X1349567Y226261D01*
X1349900Y226344D01*
X1350192Y226594D01*
X1350400Y226969D01*
X1350483Y227344D01*
Y227803D01*
X1350400Y228178D01*
X1350192Y228511D01*
X1349942Y228678D01*
X1349650Y228761D01*
X1349317Y228678D01*
X1349067Y228511D01*
X1348900Y228261D01*
X1348817Y227928D01*
X1348900Y227636D01*
X1349108Y227344D01*
X1349358Y227178D01*
X1349650Y227136D01*
X1349983Y227219D01*
X1350233Y227428D01*
X1350483Y227803D01*
G01X1360300Y270167D02*
Y267667D01*
G01X1359342Y270167D02*
X1361258D01*
G01X1362567Y267667D02*
Y270167D01*
X1363567D01*
X1363900Y270042D01*
X1364150Y269750D01*
X1364233Y269417D01*
X1364150Y269084D01*
X1363942Y268834D01*
X1363567Y268709D01*
X1362567D01*
G01X1366500Y267667D02*
Y270167D01*
X1366000Y269667D01*
G01Y267667D02*
X1367000D01*
G01X1368683Y268042D02*
X1368933Y267834D01*
X1369225Y267709D01*
X1369600Y267667D01*
X1369975Y267750D01*
X1370267Y267917D01*
X1370475Y268209D01*
X1370517Y268542D01*
X1370433Y268875D01*
X1370225Y269084D01*
X1369933Y269250D01*
X1369642Y269292D01*
X1369350Y269250D01*
X1368975Y269084D01*
X1369100Y270167D01*
X1370225D01*
G01X1372617Y267667D02*
X1372700Y268209D01*
X1372825Y268667D01*
X1372992Y269084D01*
X1373200Y269542D01*
X1373533Y270167D01*
X1371867D01*
G01X1356919Y382654D02*
Y385154D01*
X1358503D01*
G01X1357919Y383946D02*
X1356919D01*
G01X1359978Y385154D02*
Y382654D01*
X1361644D01*
G01X1364744D02*
X1363078D01*
Y385154D01*
X1364744D01*
G01X1364078Y383946D02*
X1363078D01*
G01X1366094Y382654D02*
Y385154D01*
X1366928D01*
X1367261Y385029D01*
X1367511Y384862D01*
X1367719Y384612D01*
X1367886Y384321D01*
X1367928Y383904D01*
X1367886Y383487D01*
X1367719Y383196D01*
X1367511Y382946D01*
X1367261Y382779D01*
X1366928Y382654D01*
X1366094D01*
G01X1369319Y384737D02*
X1369569Y384987D01*
X1369861Y385112D01*
X1370194Y385154D01*
X1370611Y385071D01*
X1370903Y384862D01*
X1370986Y384612D01*
X1370944Y384362D01*
X1370778Y384154D01*
X1369944Y383737D01*
X1369569Y383446D01*
X1369319Y383029D01*
X1369236Y382654D01*
X1370986D01*
G01X1373211Y385154D02*
X1372878Y385071D01*
X1372628Y384862D01*
X1372461Y384612D01*
X1372336Y384279D01*
X1372294Y383904D01*
X1372336Y383529D01*
X1372461Y383196D01*
X1372628Y382946D01*
X1372878Y382737D01*
X1373211Y382654D01*
X1373544Y382737D01*
X1373794Y382946D01*
X1373961Y383196D01*
X1374086Y383529D01*
X1374128Y383904D01*
X1374086Y384279D01*
X1373961Y384612D01*
X1373794Y384862D01*
X1373544Y385071D01*
X1373211Y385154D01*
G01X1360561Y366054D02*
Y377254D01*
X1369361D01*
Y366054D01*
X1360561D01*
G01X1330960Y492022D02*
X1330627Y492064D01*
X1330335Y492230D01*
X1330085Y492480D01*
X1329918Y492772D01*
X1329835Y493105D01*
Y493439D01*
X1329918Y493772D01*
X1330085Y494064D01*
X1330335Y494314D01*
X1330627Y494480D01*
X1330960Y494522D01*
X1331293Y494480D01*
X1331585Y494314D01*
X1331835Y494064D01*
X1332002Y493772D01*
X1332085Y493439D01*
Y493105D01*
X1332002Y492772D01*
X1331835Y492480D01*
X1331585Y492230D01*
X1331293Y492064D01*
X1330960Y492022D01*
G01X1331293Y492689D02*
X1331793Y492022D01*
G01X1333268Y494105D02*
X1333518Y494355D01*
X1333810Y494480D01*
X1334143Y494522D01*
X1334560Y494439D01*
X1334852Y494230D01*
X1334935Y493980D01*
X1334893Y493730D01*
X1334727Y493522D01*
X1333893Y493105D01*
X1333518Y492814D01*
X1333268Y492397D01*
X1333185Y492022D01*
X1334935D01*
G01X1337160D02*
X1337452Y492064D01*
X1337785Y492189D01*
X1337993Y492397D01*
X1338077Y492689D01*
X1337993Y492980D01*
X1337743Y493230D01*
X1337368Y493355D01*
X1336952D01*
X1336702Y493439D01*
X1336493Y493647D01*
X1336410Y493939D01*
X1336535Y494230D01*
X1336827Y494439D01*
X1337160Y494522D01*
X1337493Y494439D01*
X1337785Y494230D01*
X1337910Y493939D01*
X1337827Y493647D01*
X1337618Y493439D01*
X1337368Y493355D01*
X1336952D01*
X1336577Y493230D01*
X1336327Y492980D01*
X1336243Y492689D01*
X1336327Y492397D01*
X1336535Y492189D01*
X1336868Y492064D01*
X1337160Y492022D01*
G01X1339468Y494105D02*
X1339718Y494355D01*
X1340010Y494480D01*
X1340343Y494522D01*
X1340760Y494439D01*
X1341052Y494230D01*
X1341135Y493980D01*
X1341093Y493730D01*
X1340927Y493522D01*
X1340093Y493105D01*
X1339718Y492814D01*
X1339468Y492397D01*
X1339385Y492022D01*
X1341135D01*
G01X1342610Y496022D02*
Y510022D01*
G01X1345069Y492021D02*
X1344736Y492063D01*
X1344444Y492229D01*
X1344194Y492479D01*
X1344027Y492771D01*
X1343944Y493104D01*
Y493438D01*
X1344027Y493771D01*
X1344194Y494063D01*
X1344444Y494313D01*
X1344736Y494479D01*
X1345069Y494521D01*
X1345402Y494479D01*
X1345694Y494313D01*
X1345944Y494063D01*
X1346111Y493771D01*
X1346194Y493438D01*
Y493104D01*
X1346111Y492771D01*
X1345944Y492479D01*
X1345694Y492229D01*
X1345402Y492063D01*
X1345069Y492021D01*
G01X1345402Y492688D02*
X1345902Y492021D01*
G01X1347377Y494104D02*
X1347627Y494354D01*
X1347919Y494479D01*
X1348252Y494521D01*
X1348669Y494438D01*
X1348961Y494229D01*
X1349044Y493979D01*
X1349002Y493729D01*
X1348836Y493521D01*
X1348002Y493104D01*
X1347627Y492813D01*
X1347377Y492396D01*
X1347294Y492021D01*
X1349044D01*
G01X1351769D02*
Y494521D01*
X1350227Y492729D01*
X1352311D01*
G01X1353577Y493063D02*
X1353869Y493354D01*
X1354119Y493521D01*
X1354452Y493604D01*
X1354744Y493521D01*
X1354952Y493354D01*
X1355119Y493104D01*
X1355161Y492813D01*
X1355119Y492563D01*
X1354952Y492313D01*
X1354702Y492104D01*
X1354411Y492021D01*
X1354077Y492104D01*
X1353786Y492354D01*
X1353619Y492729D01*
X1353577Y493146D01*
X1353661Y493688D01*
X1353786Y493979D01*
X1353994Y494271D01*
X1354286Y494479D01*
X1354577Y494521D01*
X1354869Y494438D01*
X1355077Y494229D01*
G01X1356719Y496021D02*
Y510021D01*
G01X1343719Y496021D02*
X1356719D01*
G01X1343719Y510021D02*
Y496021D01*
G01X1365882Y481217D02*
X1363382D01*
Y482258D01*
X1363507Y482592D01*
X1363674Y482800D01*
X1364007Y482883D01*
X1364340Y482800D01*
X1364549Y482550D01*
X1364674Y482258D01*
Y481217D01*
G01Y482258D02*
X1365882Y482883D01*
G01X1365382Y484233D02*
X1365674Y484483D01*
X1365840Y484817D01*
X1365882Y485192D01*
X1365840Y485525D01*
X1365632Y485858D01*
X1365382Y486067D01*
X1365132Y486108D01*
X1364840Y486025D01*
X1364632Y485733D01*
X1364549Y485442D01*
Y485067D01*
G01Y485442D02*
X1364424Y485692D01*
X1364215Y485900D01*
X1363965Y485983D01*
X1363715Y485900D01*
X1363507Y485692D01*
X1363382Y485317D01*
X1363424Y484942D01*
X1363590Y484567D01*
G01X1363799Y487458D02*
X1363549Y487708D01*
X1363424Y488000D01*
X1363382Y488333D01*
X1363465Y488750D01*
X1363674Y489042D01*
X1363924Y489125D01*
X1364174Y489083D01*
X1364382Y488917D01*
X1364799Y488083D01*
X1365090Y487708D01*
X1365507Y487458D01*
X1365882Y487375D01*
Y489125D01*
G01X1365382Y490433D02*
X1365674Y490683D01*
X1365840Y491017D01*
X1365882Y491392D01*
X1365840Y491725D01*
X1365632Y492058D01*
X1365382Y492267D01*
X1365132Y492308D01*
X1364840Y492225D01*
X1364632Y491933D01*
X1364549Y491642D01*
Y491267D01*
G01Y491642D02*
X1364424Y491892D01*
X1364215Y492100D01*
X1363965Y492183D01*
X1363715Y492100D01*
X1363507Y491892D01*
X1363382Y491517D01*
X1363424Y491142D01*
X1363590Y490767D01*
G01X1360882Y481217D02*
X1358382D01*
Y482258D01*
X1358507Y482592D01*
X1358674Y482800D01*
X1359007Y482883D01*
X1359340Y482800D01*
X1359549Y482550D01*
X1359674Y482258D01*
Y481217D01*
G01Y482258D02*
X1360882Y482883D01*
G01X1360382Y484233D02*
X1360674Y484483D01*
X1360840Y484817D01*
X1360882Y485192D01*
X1360840Y485525D01*
X1360632Y485858D01*
X1360382Y486067D01*
X1360132Y486108D01*
X1359840Y486025D01*
X1359632Y485733D01*
X1359549Y485442D01*
Y485067D01*
G01Y485442D02*
X1359424Y485692D01*
X1359215Y485900D01*
X1358965Y485983D01*
X1358715Y485900D01*
X1358507Y485692D01*
X1358382Y485317D01*
X1358424Y484942D01*
X1358590Y484567D01*
G01X1360882Y488250D02*
X1358382D01*
X1358882Y487750D01*
G01X1360882D02*
Y488750D01*
G01X1360590Y490642D02*
X1360799Y490933D01*
X1360882Y491267D01*
X1360799Y491600D01*
X1360549Y491892D01*
X1360174Y492100D01*
X1359799Y492183D01*
X1359340D01*
X1358965Y492100D01*
X1358632Y491892D01*
X1358465Y491642D01*
X1358382Y491350D01*
X1358465Y491017D01*
X1358632Y490767D01*
X1358882Y490600D01*
X1359215Y490517D01*
X1359507Y490600D01*
X1359799Y490808D01*
X1359965Y491058D01*
X1360007Y491350D01*
X1359924Y491683D01*
X1359715Y491933D01*
X1359340Y492183D01*
G01X1340526Y541120D02*
Y543620D01*
X1341567D01*
X1341901Y543495D01*
X1342109Y543328D01*
X1342192Y542995D01*
X1342109Y542662D01*
X1341859Y542453D01*
X1341567Y542328D01*
X1340526D01*
G01X1341567D02*
X1342192Y541120D01*
G01X1344459D02*
Y543620D01*
X1343959Y543120D01*
G01Y541120D02*
X1344959D01*
G01X1347559D02*
Y543620D01*
X1347059Y543120D01*
G01Y541120D02*
X1348059D01*
G01X1350659Y543620D02*
X1350326Y543537D01*
X1350076Y543328D01*
X1349909Y543078D01*
X1349784Y542745D01*
X1349742Y542370D01*
X1349784Y541995D01*
X1349909Y541662D01*
X1350076Y541412D01*
X1350326Y541203D01*
X1350659Y541120D01*
X1350992Y541203D01*
X1351242Y541412D01*
X1351409Y541662D01*
X1351534Y541995D01*
X1351576Y542370D01*
X1351534Y542745D01*
X1351409Y543078D01*
X1351242Y543328D01*
X1350992Y543537D01*
X1350659Y543620D01*
G01X1352967Y543203D02*
X1353217Y543453D01*
X1353509Y543578D01*
X1353842Y543620D01*
X1354259Y543537D01*
X1354551Y543328D01*
X1354634Y543078D01*
X1354592Y542828D01*
X1354426Y542620D01*
X1353592Y542203D01*
X1353217Y541912D01*
X1352967Y541495D01*
X1352884Y541120D01*
X1354634D01*
G01X1358528Y544311D02*
Y540311D01*
X1365928D01*
G01X1343630Y522334D02*
Y524834D01*
X1344671D01*
X1345005Y524709D01*
X1345213Y524542D01*
X1345296Y524209D01*
X1345213Y523876D01*
X1344963Y523667D01*
X1344671Y523542D01*
X1343630D01*
G01X1344671D02*
X1345296Y522334D01*
G01X1346646Y522709D02*
X1346896Y522501D01*
X1347188Y522376D01*
X1347563Y522334D01*
X1347938Y522417D01*
X1348230Y522584D01*
X1348438Y522876D01*
X1348480Y523209D01*
X1348396Y523542D01*
X1348188Y523751D01*
X1347896Y523917D01*
X1347605Y523959D01*
X1347313Y523917D01*
X1346938Y523751D01*
X1347063Y524834D01*
X1348188D01*
G01X1349746Y522834D02*
X1349996Y522542D01*
X1350330Y522376D01*
X1350705Y522334D01*
X1351038Y522376D01*
X1351371Y522584D01*
X1351580Y522834D01*
X1351621Y523084D01*
X1351538Y523376D01*
X1351246Y523584D01*
X1350955Y523667D01*
X1350580D01*
G01X1350955D02*
X1351205Y523792D01*
X1351413Y524001D01*
X1351496Y524251D01*
X1351413Y524501D01*
X1351205Y524709D01*
X1350830Y524834D01*
X1350455Y524792D01*
X1350080Y524626D01*
G01X1352971Y524417D02*
X1353221Y524667D01*
X1353513Y524792D01*
X1353846Y524834D01*
X1354263Y524751D01*
X1354555Y524542D01*
X1354638Y524292D01*
X1354596Y524042D01*
X1354430Y523834D01*
X1353596Y523417D01*
X1353221Y523126D01*
X1352971Y522709D01*
X1352888Y522334D01*
X1354638D01*
G01X1351813Y511334D02*
Y515334D01*
X1344413D01*
G01X1337676Y511303D02*
Y515303D01*
X1330276D01*
G01X1356719Y510021D02*
X1343719D01*
G01X1372300Y536900D02*
Y566900D01*
X1395100D01*
Y536900D01*
X1372300D01*
G01X1345350Y555667D02*
X1345017Y555709D01*
X1344725Y555875D01*
X1344475Y556125D01*
X1344308Y556417D01*
X1344225Y556750D01*
Y557084D01*
X1344308Y557417D01*
X1344475Y557709D01*
X1344725Y557959D01*
X1345017Y558125D01*
X1345350Y558167D01*
X1345683Y558125D01*
X1345975Y557959D01*
X1346225Y557709D01*
X1346392Y557417D01*
X1346475Y557084D01*
Y556750D01*
X1346392Y556417D01*
X1346225Y556125D01*
X1345975Y555875D01*
X1345683Y555709D01*
X1345350Y555667D01*
G01X1345683Y556334D02*
X1346183Y555667D01*
G01X1347658Y557750D02*
X1347908Y558000D01*
X1348200Y558125D01*
X1348533Y558167D01*
X1348950Y558084D01*
X1349242Y557875D01*
X1349325Y557625D01*
X1349283Y557375D01*
X1349117Y557167D01*
X1348283Y556750D01*
X1347908Y556459D01*
X1347658Y556042D01*
X1347575Y555667D01*
X1349325D01*
G01X1350758Y557750D02*
X1351008Y558000D01*
X1351300Y558125D01*
X1351633Y558167D01*
X1352050Y558084D01*
X1352342Y557875D01*
X1352425Y557625D01*
X1352383Y557375D01*
X1352217Y557167D01*
X1351383Y556750D01*
X1351008Y556459D01*
X1350758Y556042D01*
X1350675Y555667D01*
X1352425D01*
G01X1353858Y557750D02*
X1354108Y558000D01*
X1354400Y558125D01*
X1354733Y558167D01*
X1355150Y558084D01*
X1355442Y557875D01*
X1355525Y557625D01*
X1355483Y557375D01*
X1355317Y557167D01*
X1354483Y556750D01*
X1354108Y556459D01*
X1353858Y556042D01*
X1353775Y555667D01*
X1355525D01*
G01X1360443Y574829D02*
X1360318Y574579D01*
X1360235Y574287D01*
Y573954D01*
X1360360Y573579D01*
X1360568Y573287D01*
X1360818Y573079D01*
X1361235Y572912D01*
X1361610Y572870D01*
X1361985Y572954D01*
X1362235Y573079D01*
X1362485Y573329D01*
X1362652Y573620D01*
X1362735Y573912D01*
Y574204D01*
X1362652Y574495D01*
X1362527Y574745D01*
X1362360Y574954D01*
G01Y576095D02*
X1362568Y576345D01*
X1362693Y576637D01*
X1362735Y577012D01*
X1362652Y577387D01*
X1362485Y577679D01*
X1362193Y577887D01*
X1361860Y577929D01*
X1361527Y577845D01*
X1361318Y577637D01*
X1361152Y577345D01*
X1361110Y577054D01*
X1361152Y576762D01*
X1361318Y576387D01*
X1360235Y576512D01*
Y577637D01*
G01X1361693Y579320D02*
X1361402Y579612D01*
X1361235Y579862D01*
X1361152Y580195D01*
X1361235Y580487D01*
X1361402Y580695D01*
X1361652Y580862D01*
X1361943Y580904D01*
X1362193Y580862D01*
X1362443Y580695D01*
X1362652Y580445D01*
X1362735Y580154D01*
X1362652Y579820D01*
X1362402Y579529D01*
X1362027Y579362D01*
X1361610Y579320D01*
X1361068Y579404D01*
X1360777Y579529D01*
X1360485Y579737D01*
X1360277Y580029D01*
X1360235Y580320D01*
X1360318Y580612D01*
X1360527Y580820D01*
G01X1362360Y582295D02*
X1362568Y582545D01*
X1362693Y582837D01*
X1362735Y583212D01*
X1362652Y583587D01*
X1362485Y583879D01*
X1362193Y584087D01*
X1361860Y584129D01*
X1361527Y584045D01*
X1361318Y583837D01*
X1361152Y583545D01*
X1361110Y583254D01*
X1361152Y582962D01*
X1361318Y582587D01*
X1360235Y582712D01*
Y583837D01*
G01X1330419Y623219D02*
Y625719D01*
X1331460D01*
X1331794Y625594D01*
X1332002Y625427D01*
X1332085Y625094D01*
X1332002Y624761D01*
X1331752Y624552D01*
X1331460Y624427D01*
X1330419D01*
G01X1331460D02*
X1332085Y623219D01*
G01X1333435Y623594D02*
X1333685Y623386D01*
X1333977Y623261D01*
X1334352Y623219D01*
X1334727Y623302D01*
X1335019Y623469D01*
X1335227Y623761D01*
X1335269Y624094D01*
X1335185Y624427D01*
X1334977Y624636D01*
X1334685Y624802D01*
X1334394Y624844D01*
X1334102Y624802D01*
X1333727Y624636D01*
X1333852Y625719D01*
X1334977D01*
G01X1336535Y623594D02*
X1336785Y623386D01*
X1337077Y623261D01*
X1337452Y623219D01*
X1337827Y623302D01*
X1338119Y623469D01*
X1338327Y623761D01*
X1338369Y624094D01*
X1338285Y624427D01*
X1338077Y624636D01*
X1337785Y624802D01*
X1337494Y624844D01*
X1337202Y624802D01*
X1336827Y624636D01*
X1336952Y625719D01*
X1338077D01*
G01X1340552Y623219D02*
Y625719D01*
X1340052Y625219D01*
G01Y623219D02*
X1341052D01*
G01X1350468Y609583D02*
X1347968D01*
Y610624D01*
X1348093Y610958D01*
X1348260Y611166D01*
X1348593Y611249D01*
X1348926Y611166D01*
X1349135Y610916D01*
X1349260Y610624D01*
Y609583D01*
G01Y610624D02*
X1350468Y611249D01*
G01X1350093Y612599D02*
X1350301Y612849D01*
X1350426Y613141D01*
X1350468Y613516D01*
X1350385Y613891D01*
X1350218Y614183D01*
X1349926Y614391D01*
X1349593Y614433D01*
X1349260Y614349D01*
X1349051Y614141D01*
X1348885Y613849D01*
X1348843Y613558D01*
X1348885Y613266D01*
X1349051Y612891D01*
X1347968Y613016D01*
Y614141D01*
G01X1350093Y615699D02*
X1350301Y615949D01*
X1350426Y616241D01*
X1350468Y616616D01*
X1350385Y616991D01*
X1350218Y617283D01*
X1349926Y617491D01*
X1349593Y617533D01*
X1349260Y617449D01*
X1349051Y617241D01*
X1348885Y616949D01*
X1348843Y616658D01*
X1348885Y616366D01*
X1349051Y615991D01*
X1347968Y616116D01*
Y617241D01*
G01X1350468Y619716D02*
X1350426Y620008D01*
X1350301Y620341D01*
X1350093Y620549D01*
X1349801Y620633D01*
X1349510Y620549D01*
X1349260Y620299D01*
X1349135Y619924D01*
Y619508D01*
X1349051Y619258D01*
X1348843Y619049D01*
X1348551Y618966D01*
X1348260Y619091D01*
X1348051Y619383D01*
X1347968Y619716D01*
X1348051Y620049D01*
X1348260Y620341D01*
X1348551Y620466D01*
X1348843Y620383D01*
X1349051Y620174D01*
X1349135Y619924D01*
Y619508D01*
X1349260Y619133D01*
X1349510Y618883D01*
X1349801Y618799D01*
X1350093Y618883D01*
X1350301Y619091D01*
X1350426Y619424D01*
X1350468Y619716D01*
G01X1343663Y626848D02*
Y629348D01*
X1344704D01*
X1345038Y629223D01*
X1345246Y629056D01*
X1345329Y628723D01*
X1345246Y628390D01*
X1344996Y628181D01*
X1344704Y628056D01*
X1343663D01*
G01X1344704D02*
X1345329Y626848D01*
G01X1346679Y627223D02*
X1346929Y627015D01*
X1347221Y626890D01*
X1347596Y626848D01*
X1347971Y626931D01*
X1348263Y627098D01*
X1348471Y627390D01*
X1348513Y627723D01*
X1348429Y628056D01*
X1348221Y628265D01*
X1347929Y628431D01*
X1347638Y628473D01*
X1347346Y628431D01*
X1346971Y628265D01*
X1347096Y629348D01*
X1348221D01*
G01X1349904Y627890D02*
X1350196Y628181D01*
X1350446Y628348D01*
X1350779Y628431D01*
X1351071Y628348D01*
X1351279Y628181D01*
X1351446Y627931D01*
X1351488Y627640D01*
X1351446Y627390D01*
X1351279Y627140D01*
X1351029Y626931D01*
X1350738Y626848D01*
X1350404Y626931D01*
X1350113Y627181D01*
X1349946Y627556D01*
X1349904Y627973D01*
X1349988Y628515D01*
X1350113Y628806D01*
X1350321Y629098D01*
X1350613Y629306D01*
X1350904Y629348D01*
X1351196Y629265D01*
X1351404Y629056D01*
G01X1353796Y629348D02*
X1353463Y629265D01*
X1353213Y629056D01*
X1353046Y628806D01*
X1352921Y628473D01*
X1352879Y628098D01*
X1352921Y627723D01*
X1353046Y627390D01*
X1353213Y627140D01*
X1353463Y626931D01*
X1353796Y626848D01*
X1354129Y626931D01*
X1354379Y627140D01*
X1354546Y627390D01*
X1354671Y627723D01*
X1354713Y628098D01*
X1354671Y628473D01*
X1354546Y628806D01*
X1354379Y629056D01*
X1354129Y629265D01*
X1353796Y629348D01*
G01X1345968Y609583D02*
X1343468D01*
Y610624D01*
X1343593Y610958D01*
X1343760Y611166D01*
X1344093Y611249D01*
X1344426Y611166D01*
X1344635Y610916D01*
X1344760Y610624D01*
Y609583D01*
G01Y610624D02*
X1345968Y611249D01*
G01X1345593Y612599D02*
X1345801Y612849D01*
X1345926Y613141D01*
X1345968Y613516D01*
X1345885Y613891D01*
X1345718Y614183D01*
X1345426Y614391D01*
X1345093Y614433D01*
X1344760Y614349D01*
X1344551Y614141D01*
X1344385Y613849D01*
X1344343Y613558D01*
X1344385Y613266D01*
X1344551Y612891D01*
X1343468Y613016D01*
Y614141D01*
G01X1344926Y615824D02*
X1344635Y616116D01*
X1344468Y616366D01*
X1344385Y616699D01*
X1344468Y616991D01*
X1344635Y617199D01*
X1344885Y617366D01*
X1345176Y617408D01*
X1345426Y617366D01*
X1345676Y617199D01*
X1345885Y616949D01*
X1345968Y616658D01*
X1345885Y616324D01*
X1345635Y616033D01*
X1345260Y615866D01*
X1344843Y615824D01*
X1344301Y615908D01*
X1344010Y616033D01*
X1343718Y616241D01*
X1343510Y616533D01*
X1343468Y616824D01*
X1343551Y617116D01*
X1343760Y617324D01*
G01X1345968Y619716D02*
X1343468D01*
X1343968Y619216D01*
G01X1345968D02*
Y620216D01*
G01X1343579Y623148D02*
Y625648D01*
X1344413D01*
X1344746Y625523D01*
X1344996Y625356D01*
X1345204Y625106D01*
X1345371Y624815D01*
X1345413Y624398D01*
X1345371Y623981D01*
X1345204Y623690D01*
X1344996Y623440D01*
X1344746Y623273D01*
X1344413Y623148D01*
X1343579D01*
G01X1347596D02*
Y625648D01*
X1347096Y625148D01*
G01Y623148D02*
X1348096D01*
G01X1350696D02*
X1350988Y623190D01*
X1351321Y623315D01*
X1351529Y623523D01*
X1351613Y623815D01*
X1351529Y624106D01*
X1351279Y624356D01*
X1350904Y624481D01*
X1350488D01*
X1350238Y624565D01*
X1350029Y624773D01*
X1349946Y625065D01*
X1350071Y625356D01*
X1350363Y625565D01*
X1350696Y625648D01*
X1351029Y625565D01*
X1351321Y625356D01*
X1351446Y625065D01*
X1351363Y624773D01*
X1351154Y624565D01*
X1350904Y624481D01*
X1350488D01*
X1350113Y624356D01*
X1349863Y624106D01*
X1349779Y623815D01*
X1349863Y623523D01*
X1350071Y623315D01*
X1350404Y623190D01*
X1350696Y623148D01*
G01X1336500Y644417D02*
Y637417D01*
G01X1372606Y621980D02*
X1372356Y622105D01*
X1372064Y622188D01*
X1371731D01*
X1371356Y622063D01*
X1371064Y621855D01*
X1370856Y621605D01*
X1370689Y621188D01*
X1370647Y620813D01*
X1370731Y620438D01*
X1370856Y620188D01*
X1371106Y619938D01*
X1371397Y619771D01*
X1371689Y619688D01*
X1371981D01*
X1372272Y619771D01*
X1372522Y619896D01*
X1372731Y620063D01*
G01X1373997Y621771D02*
X1374247Y622021D01*
X1374539Y622146D01*
X1374872Y622188D01*
X1375289Y622105D01*
X1375581Y621896D01*
X1375664Y621646D01*
X1375622Y621396D01*
X1375456Y621188D01*
X1374622Y620771D01*
X1374247Y620480D01*
X1373997Y620063D01*
X1373914Y619688D01*
X1375664D01*
G01X1377889D02*
X1378181Y619730D01*
X1378514Y619855D01*
X1378722Y620063D01*
X1378806Y620355D01*
X1378722Y620646D01*
X1378472Y620896D01*
X1378097Y621021D01*
X1377681D01*
X1377431Y621105D01*
X1377222Y621313D01*
X1377139Y621605D01*
X1377264Y621896D01*
X1377556Y622105D01*
X1377889Y622188D01*
X1378222Y622105D01*
X1378514Y621896D01*
X1378639Y621605D01*
X1378556Y621313D01*
X1378347Y621105D01*
X1378097Y621021D01*
X1377681D01*
X1377306Y620896D01*
X1377056Y620646D01*
X1376972Y620355D01*
X1377056Y620063D01*
X1377264Y619855D01*
X1377597Y619730D01*
X1377889Y619688D01*
G01X1380197Y620730D02*
X1380489Y621021D01*
X1380739Y621188D01*
X1381072Y621271D01*
X1381364Y621188D01*
X1381572Y621021D01*
X1381739Y620771D01*
X1381781Y620480D01*
X1381739Y620230D01*
X1381572Y619980D01*
X1381322Y619771D01*
X1381031Y619688D01*
X1380697Y619771D01*
X1380406Y620021D01*
X1380239Y620396D01*
X1380197Y620813D01*
X1380281Y621355D01*
X1380406Y621646D01*
X1380614Y621938D01*
X1380906Y622146D01*
X1381197Y622188D01*
X1381489Y622105D01*
X1381697Y621896D01*
G01X1372615Y625832D02*
X1372365Y625957D01*
X1372073Y626040D01*
X1371740D01*
X1371365Y625915D01*
X1371073Y625707D01*
X1370865Y625457D01*
X1370698Y625040D01*
X1370656Y624665D01*
X1370740Y624290D01*
X1370865Y624040D01*
X1371115Y623790D01*
X1371406Y623623D01*
X1371698Y623540D01*
X1371990D01*
X1372281Y623623D01*
X1372531Y623748D01*
X1372740Y623915D01*
G01X1374006Y625623D02*
X1374256Y625873D01*
X1374548Y625998D01*
X1374881Y626040D01*
X1375298Y625957D01*
X1375590Y625748D01*
X1375673Y625498D01*
X1375631Y625248D01*
X1375465Y625040D01*
X1374631Y624623D01*
X1374256Y624332D01*
X1374006Y623915D01*
X1373923Y623540D01*
X1375673D01*
G01X1377898D02*
X1378190Y623582D01*
X1378523Y623707D01*
X1378731Y623915D01*
X1378815Y624207D01*
X1378731Y624498D01*
X1378481Y624748D01*
X1378106Y624873D01*
X1377690D01*
X1377440Y624957D01*
X1377231Y625165D01*
X1377148Y625457D01*
X1377273Y625748D01*
X1377565Y625957D01*
X1377898Y626040D01*
X1378231Y625957D01*
X1378523Y625748D01*
X1378648Y625457D01*
X1378565Y625165D01*
X1378356Y624957D01*
X1378106Y624873D01*
X1377690D01*
X1377315Y624748D01*
X1377065Y624498D01*
X1376981Y624207D01*
X1377065Y623915D01*
X1377273Y623707D01*
X1377606Y623582D01*
X1377898Y623540D01*
G01X1380081Y623915D02*
X1380331Y623707D01*
X1380623Y623582D01*
X1380998Y623540D01*
X1381373Y623623D01*
X1381665Y623790D01*
X1381873Y624082D01*
X1381915Y624415D01*
X1381831Y624748D01*
X1381623Y624957D01*
X1381331Y625123D01*
X1381040Y625165D01*
X1380748Y625123D01*
X1380373Y624957D01*
X1380498Y626040D01*
X1381623D01*
G01X1332169Y629211D02*
X1331919Y629336D01*
X1331627Y629419D01*
X1331294D01*
X1330919Y629294D01*
X1330627Y629086D01*
X1330419Y628836D01*
X1330252Y628419D01*
X1330210Y628044D01*
X1330294Y627669D01*
X1330419Y627419D01*
X1330669Y627169D01*
X1330960Y627002D01*
X1331252Y626919D01*
X1331544D01*
X1331835Y627002D01*
X1332085Y627127D01*
X1332294Y627294D01*
G01X1333560Y629002D02*
X1333810Y629252D01*
X1334102Y629377D01*
X1334435Y629419D01*
X1334852Y629336D01*
X1335144Y629127D01*
X1335227Y628877D01*
X1335185Y628627D01*
X1335019Y628419D01*
X1334185Y628002D01*
X1333810Y627711D01*
X1333560Y627294D01*
X1333477Y626919D01*
X1335227D01*
G01X1337452D02*
X1337744Y626961D01*
X1338077Y627086D01*
X1338285Y627294D01*
X1338369Y627586D01*
X1338285Y627877D01*
X1338035Y628127D01*
X1337660Y628252D01*
X1337244D01*
X1336994Y628336D01*
X1336785Y628544D01*
X1336702Y628836D01*
X1336827Y629127D01*
X1337119Y629336D01*
X1337452Y629419D01*
X1337785Y629336D01*
X1338077Y629127D01*
X1338202Y628836D01*
X1338119Y628544D01*
X1337910Y628336D01*
X1337660Y628252D01*
X1337244D01*
X1336869Y628127D01*
X1336619Y627877D01*
X1336535Y627586D01*
X1336619Y627294D01*
X1336827Y627086D01*
X1337160Y626961D01*
X1337452Y626919D01*
G01X1339760Y629002D02*
X1340010Y629252D01*
X1340302Y629377D01*
X1340635Y629419D01*
X1341052Y629336D01*
X1341344Y629127D01*
X1341427Y628877D01*
X1341385Y628627D01*
X1341219Y628419D01*
X1340385Y628002D01*
X1340010Y627711D01*
X1339760Y627294D01*
X1339677Y626919D01*
X1341427D01*
G01X1339017Y674917D02*
Y677417D01*
X1340058D01*
X1340392Y677292D01*
X1340600Y677125D01*
X1340683Y676792D01*
X1340600Y676459D01*
X1340350Y676250D01*
X1340058Y676125D01*
X1339017D01*
G01X1340058D02*
X1340683Y674917D01*
G01X1342033Y675292D02*
X1342283Y675084D01*
X1342575Y674959D01*
X1342950Y674917D01*
X1343325Y675000D01*
X1343617Y675167D01*
X1343825Y675459D01*
X1343867Y675792D01*
X1343783Y676125D01*
X1343575Y676334D01*
X1343283Y676500D01*
X1342992Y676542D01*
X1342700Y676500D01*
X1342325Y676334D01*
X1342450Y677417D01*
X1343575D01*
G01X1345133Y675292D02*
X1345383Y675084D01*
X1345675Y674959D01*
X1346050Y674917D01*
X1346425Y675000D01*
X1346717Y675167D01*
X1346925Y675459D01*
X1346967Y675792D01*
X1346883Y676125D01*
X1346675Y676334D01*
X1346383Y676500D01*
X1346092Y676542D01*
X1345800Y676500D01*
X1345425Y676334D01*
X1345550Y677417D01*
X1346675D01*
G01X1348442Y675209D02*
X1348733Y675000D01*
X1349067Y674917D01*
X1349400Y675000D01*
X1349692Y675250D01*
X1349900Y675625D01*
X1349983Y676000D01*
Y676459D01*
X1349900Y676834D01*
X1349692Y677167D01*
X1349442Y677334D01*
X1349150Y677417D01*
X1348817Y677334D01*
X1348567Y677167D01*
X1348400Y676917D01*
X1348317Y676584D01*
X1348400Y676292D01*
X1348608Y676000D01*
X1348858Y675834D01*
X1349150Y675792D01*
X1349483Y675875D01*
X1349733Y676084D01*
X1349983Y676459D01*
G01X1337200Y674417D02*
Y678417D01*
X1329800D01*
G01X1360230Y696517D02*
Y699017D01*
X1361271D01*
X1361605Y698892D01*
X1361813Y698725D01*
X1361896Y698392D01*
X1361813Y698059D01*
X1361563Y697850D01*
X1361271Y697725D01*
X1360230D01*
G01X1361271D02*
X1361896Y696517D01*
G01X1363246Y696892D02*
X1363496Y696684D01*
X1363788Y696559D01*
X1364163Y696517D01*
X1364538Y696600D01*
X1364830Y696767D01*
X1365038Y697059D01*
X1365080Y697392D01*
X1364996Y697725D01*
X1364788Y697934D01*
X1364496Y698100D01*
X1364205Y698142D01*
X1363913Y698100D01*
X1363538Y697934D01*
X1363663Y699017D01*
X1364788D01*
G01X1366471Y697559D02*
X1366763Y697850D01*
X1367013Y698017D01*
X1367346Y698100D01*
X1367638Y698017D01*
X1367846Y697850D01*
X1368013Y697600D01*
X1368055Y697309D01*
X1368013Y697059D01*
X1367846Y696809D01*
X1367596Y696600D01*
X1367305Y696517D01*
X1366971Y696600D01*
X1366680Y696850D01*
X1366513Y697225D01*
X1366471Y697642D01*
X1366555Y698184D01*
X1366680Y698475D01*
X1366888Y698767D01*
X1367180Y698975D01*
X1367471Y699017D01*
X1367763Y698934D01*
X1367971Y698725D01*
G01X1370280Y696517D02*
X1370363Y697059D01*
X1370488Y697517D01*
X1370655Y697934D01*
X1370863Y698392D01*
X1371196Y699017D01*
X1369530D01*
G01X1373513Y699517D02*
Y695517D01*
X1380913D01*
G01X1361980Y694709D02*
X1361730Y694834D01*
X1361438Y694917D01*
X1361105D01*
X1360730Y694792D01*
X1360438Y694584D01*
X1360230Y694334D01*
X1360063Y693917D01*
X1360021Y693542D01*
X1360105Y693167D01*
X1360230Y692917D01*
X1360480Y692667D01*
X1360771Y692500D01*
X1361063Y692417D01*
X1361355D01*
X1361646Y692500D01*
X1361896Y692625D01*
X1362105Y692792D01*
G01X1363371Y694500D02*
X1363621Y694750D01*
X1363913Y694875D01*
X1364246Y694917D01*
X1364663Y694834D01*
X1364955Y694625D01*
X1365038Y694375D01*
X1364996Y694125D01*
X1364830Y693917D01*
X1363996Y693500D01*
X1363621Y693209D01*
X1363371Y692792D01*
X1363288Y692417D01*
X1365038D01*
G01X1366555Y692709D02*
X1366846Y692500D01*
X1367180Y692417D01*
X1367513Y692500D01*
X1367805Y692750D01*
X1368013Y693125D01*
X1368096Y693500D01*
Y693959D01*
X1368013Y694334D01*
X1367805Y694667D01*
X1367555Y694834D01*
X1367263Y694917D01*
X1366930Y694834D01*
X1366680Y694667D01*
X1366513Y694417D01*
X1366430Y694084D01*
X1366513Y693792D01*
X1366721Y693500D01*
X1366971Y693334D01*
X1367263Y693292D01*
X1367596Y693375D01*
X1367846Y693584D01*
X1368096Y693959D01*
G01X1369446Y692917D02*
X1369696Y692625D01*
X1370030Y692459D01*
X1370405Y692417D01*
X1370738Y692459D01*
X1371071Y692667D01*
X1371280Y692917D01*
X1371321Y693167D01*
X1371238Y693459D01*
X1370946Y693667D01*
X1370655Y693750D01*
X1370280D01*
G01X1370655D02*
X1370905Y693875D01*
X1371113Y694084D01*
X1371196Y694334D01*
X1371113Y694584D01*
X1370905Y694792D01*
X1370530Y694917D01*
X1370155Y694875D01*
X1369780Y694709D01*
G01X1340767Y681309D02*
X1340517Y681434D01*
X1340225Y681517D01*
X1339892D01*
X1339517Y681392D01*
X1339225Y681184D01*
X1339017Y680934D01*
X1338850Y680517D01*
X1338808Y680142D01*
X1338892Y679767D01*
X1339017Y679517D01*
X1339267Y679267D01*
X1339558Y679100D01*
X1339850Y679017D01*
X1340142D01*
X1340433Y679100D01*
X1340683Y679225D01*
X1340892Y679392D01*
G01X1342158Y681100D02*
X1342408Y681350D01*
X1342700Y681475D01*
X1343033Y681517D01*
X1343450Y681434D01*
X1343742Y681225D01*
X1343825Y680975D01*
X1343783Y680725D01*
X1343617Y680517D01*
X1342783Y680100D01*
X1342408Y679809D01*
X1342158Y679392D01*
X1342075Y679017D01*
X1343825D01*
G01X1346050D02*
X1346342Y679059D01*
X1346675Y679184D01*
X1346883Y679392D01*
X1346967Y679684D01*
X1346883Y679975D01*
X1346633Y680225D01*
X1346258Y680350D01*
X1345842D01*
X1345592Y680434D01*
X1345383Y680642D01*
X1345300Y680934D01*
X1345425Y681225D01*
X1345717Y681434D01*
X1346050Y681517D01*
X1346383Y681434D01*
X1346675Y681225D01*
X1346800Y680934D01*
X1346717Y680642D01*
X1346508Y680434D01*
X1346258Y680350D01*
X1345842D01*
X1345467Y680225D01*
X1345217Y679975D01*
X1345133Y679684D01*
X1345217Y679392D01*
X1345425Y679184D01*
X1345758Y679059D01*
X1346050Y679017D01*
G01X1348233Y679517D02*
X1348483Y679225D01*
X1348817Y679059D01*
X1349192Y679017D01*
X1349525Y679059D01*
X1349858Y679267D01*
X1350067Y679517D01*
X1350108Y679767D01*
X1350025Y680059D01*
X1349733Y680267D01*
X1349442Y680350D01*
X1349067D01*
G01X1349442D02*
X1349692Y680475D01*
X1349900Y680684D01*
X1349983Y680934D01*
X1349900Y681184D01*
X1349692Y681392D01*
X1349317Y681517D01*
X1348942Y681475D01*
X1348567Y681309D01*
G01X1364850Y724166D02*
Y721666D01*
G01X1363892Y724166D02*
X1365808D01*
G01X1367117Y721666D02*
Y724166D01*
X1368117D01*
X1368450Y724041D01*
X1368700Y723749D01*
X1368783Y723416D01*
X1368700Y723083D01*
X1368492Y722833D01*
X1368117Y722708D01*
X1367117D01*
G01X1370342Y721958D02*
X1370633Y721749D01*
X1370967Y721666D01*
X1371300Y721749D01*
X1371592Y721999D01*
X1371800Y722374D01*
X1371883Y722749D01*
Y723208D01*
X1371800Y723583D01*
X1371592Y723916D01*
X1371342Y724083D01*
X1371050Y724166D01*
X1370717Y724083D01*
X1370467Y723916D01*
X1370300Y723666D01*
X1370217Y723333D01*
X1370300Y723041D01*
X1370508Y722749D01*
X1370758Y722583D01*
X1371050Y722541D01*
X1371383Y722624D01*
X1371633Y722833D01*
X1371883Y723208D01*
G01X1374067Y721666D02*
X1374150Y722208D01*
X1374275Y722666D01*
X1374442Y723083D01*
X1374650Y723541D01*
X1374983Y724166D01*
X1373317D01*
G01X1358730Y707917D02*
Y710417D01*
X1359771D01*
X1360105Y710292D01*
X1360313Y710125D01*
X1360396Y709792D01*
X1360313Y709459D01*
X1360063Y709250D01*
X1359771Y709125D01*
X1358730D01*
G01X1359771D02*
X1360396Y707917D01*
G01X1361746Y708292D02*
X1361996Y708084D01*
X1362288Y707959D01*
X1362663Y707917D01*
X1363038Y708000D01*
X1363330Y708167D01*
X1363538Y708459D01*
X1363580Y708792D01*
X1363496Y709125D01*
X1363288Y709334D01*
X1362996Y709500D01*
X1362705Y709542D01*
X1362413Y709500D01*
X1362038Y709334D01*
X1362163Y710417D01*
X1363288D01*
G01X1365680Y707917D02*
X1365763Y708459D01*
X1365888Y708917D01*
X1366055Y709334D01*
X1366263Y709792D01*
X1366596Y710417D01*
X1364930D01*
G01X1368863Y707917D02*
Y710417D01*
X1368363Y709917D01*
G01Y707917D02*
X1369363D01*
G01X1357969Y837409D02*
Y839909D01*
X1359553D01*
G01X1358969Y838701D02*
X1357969D01*
G01X1361028Y839909D02*
Y837409D01*
X1362694D01*
G01X1365794D02*
X1364128D01*
Y839909D01*
X1365794D01*
G01X1365128Y838701D02*
X1364128D01*
G01X1367144Y837409D02*
Y839909D01*
X1367978D01*
X1368311Y839784D01*
X1368561Y839617D01*
X1368769Y839367D01*
X1368936Y839076D01*
X1368978Y838659D01*
X1368936Y838242D01*
X1368769Y837951D01*
X1368561Y837701D01*
X1368311Y837534D01*
X1367978Y837409D01*
X1367144D01*
G01X1371161D02*
X1371453Y837451D01*
X1371786Y837576D01*
X1371994Y837784D01*
X1372078Y838076D01*
X1371994Y838367D01*
X1371744Y838617D01*
X1371369Y838742D01*
X1370953D01*
X1370703Y838826D01*
X1370494Y839034D01*
X1370411Y839326D01*
X1370536Y839617D01*
X1370828Y839826D01*
X1371161Y839909D01*
X1371494Y839826D01*
X1371786Y839617D01*
X1371911Y839326D01*
X1371828Y839034D01*
X1371619Y838826D01*
X1371369Y838742D01*
X1370953D01*
X1370578Y838617D01*
X1370328Y838367D01*
X1370244Y838076D01*
X1370328Y837784D01*
X1370536Y837576D01*
X1370869Y837451D01*
X1371161Y837409D01*
G01X1360561Y818809D02*
Y830009D01*
X1369361D01*
Y818809D01*
X1360561D01*
G01X1345063Y971705D02*
Y974205D01*
X1346104D01*
X1346438Y974080D01*
X1346646Y973913D01*
X1346729Y973580D01*
X1346646Y973247D01*
X1346396Y973038D01*
X1346104Y972913D01*
X1345063D01*
G01X1346104D02*
X1346729Y971705D01*
G01X1349496D02*
Y974205D01*
X1347954Y972413D01*
X1350038D01*
G01X1352096Y971705D02*
X1352388Y971747D01*
X1352721Y971872D01*
X1352929Y972080D01*
X1353013Y972372D01*
X1352929Y972663D01*
X1352679Y972913D01*
X1352304Y973038D01*
X1351888D01*
X1351638Y973122D01*
X1351429Y973330D01*
X1351346Y973622D01*
X1351471Y973913D01*
X1351763Y974122D01*
X1352096Y974205D01*
X1352429Y974122D01*
X1352721Y973913D01*
X1352846Y973622D01*
X1352763Y973330D01*
X1352554Y973122D01*
X1352304Y973038D01*
X1351888D01*
X1351513Y972913D01*
X1351263Y972663D01*
X1351179Y972372D01*
X1351263Y972080D01*
X1351471Y971872D01*
X1351804Y971747D01*
X1352096Y971705D01*
G01X1355196D02*
Y974205D01*
X1354696Y973705D01*
G01Y971705D02*
X1355696D01*
G01X1354246Y963705D02*
Y967705D01*
X1346846D01*
G01X1331022Y971825D02*
Y974325D01*
X1332063D01*
X1332397Y974200D01*
X1332605Y974033D01*
X1332688Y973700D01*
X1332605Y973367D01*
X1332355Y973158D01*
X1332063Y973033D01*
X1331022D01*
G01X1332063D02*
X1332688Y971825D01*
G01X1335455D02*
Y974325D01*
X1333913Y972533D01*
X1335997D01*
G01X1338055Y971825D02*
X1338347Y971867D01*
X1338680Y971992D01*
X1338888Y972200D01*
X1338972Y972492D01*
X1338888Y972783D01*
X1338638Y973033D01*
X1338263Y973158D01*
X1337847D01*
X1337597Y973242D01*
X1337388Y973450D01*
X1337305Y973742D01*
X1337430Y974033D01*
X1337722Y974242D01*
X1338055Y974325D01*
X1338388Y974242D01*
X1338680Y974033D01*
X1338805Y973742D01*
X1338722Y973450D01*
X1338513Y973242D01*
X1338263Y973158D01*
X1337847D01*
X1337472Y973033D01*
X1337222Y972783D01*
X1337138Y972492D01*
X1337222Y972200D01*
X1337430Y971992D01*
X1337763Y971867D01*
X1338055Y971825D01*
G01X1341155Y974325D02*
X1340822Y974242D01*
X1340572Y974033D01*
X1340405Y973783D01*
X1340280Y973450D01*
X1340238Y973075D01*
X1340280Y972700D01*
X1340405Y972367D01*
X1340572Y972117D01*
X1340822Y971908D01*
X1341155Y971825D01*
X1341488Y971908D01*
X1341738Y972117D01*
X1341905Y972367D01*
X1342030Y972700D01*
X1342072Y973075D01*
X1342030Y973450D01*
X1341905Y973783D01*
X1341738Y974033D01*
X1341488Y974242D01*
X1341155Y974325D01*
G01X1340205Y963825D02*
Y967825D01*
X1332805D01*
G01X1333961Y944403D02*
X1333628Y944445D01*
X1333336Y944611D01*
X1333086Y944861D01*
X1332919Y945153D01*
X1332836Y945486D01*
Y945820D01*
X1332919Y946153D01*
X1333086Y946445D01*
X1333336Y946695D01*
X1333628Y946861D01*
X1333961Y946903D01*
X1334294Y946861D01*
X1334586Y946695D01*
X1334836Y946445D01*
X1335003Y946153D01*
X1335086Y945820D01*
Y945486D01*
X1335003Y945153D01*
X1334836Y944861D01*
X1334586Y944611D01*
X1334294Y944445D01*
X1333961Y944403D01*
G01X1334294Y945070D02*
X1334794Y944403D01*
G01X1336269Y946486D02*
X1336519Y946736D01*
X1336811Y946861D01*
X1337144Y946903D01*
X1337561Y946820D01*
X1337853Y946611D01*
X1337936Y946361D01*
X1337894Y946111D01*
X1337728Y945903D01*
X1336894Y945486D01*
X1336519Y945195D01*
X1336269Y944778D01*
X1336186Y944403D01*
X1337936D01*
G01X1340078D02*
X1340161Y944945D01*
X1340286Y945403D01*
X1340453Y945820D01*
X1340661Y946278D01*
X1340994Y946903D01*
X1339328D01*
G01X1343261D02*
X1342928Y946820D01*
X1342678Y946611D01*
X1342511Y946361D01*
X1342386Y946028D01*
X1342344Y945653D01*
X1342386Y945278D01*
X1342511Y944945D01*
X1342678Y944695D01*
X1342928Y944486D01*
X1343261Y944403D01*
X1343594Y944486D01*
X1343844Y944695D01*
X1344011Y944945D01*
X1344136Y945278D01*
X1344178Y945653D01*
X1344136Y946028D01*
X1344011Y946361D01*
X1343844Y946611D01*
X1343594Y946820D01*
X1343261Y946903D01*
G01X1345111Y948903D02*
Y962903D01*
G01X1332111Y948903D02*
X1345111D01*
G01X1332111Y962903D02*
Y948903D01*
G01X1345111Y962903D02*
X1332111D01*
G01X1348153Y944444D02*
X1347820Y944486D01*
X1347528Y944652D01*
X1347278Y944902D01*
X1347111Y945194D01*
X1347028Y945527D01*
Y945861D01*
X1347111Y946194D01*
X1347278Y946486D01*
X1347528Y946736D01*
X1347820Y946902D01*
X1348153Y946944D01*
X1348486Y946902D01*
X1348778Y946736D01*
X1349028Y946486D01*
X1349195Y946194D01*
X1349278Y945861D01*
Y945527D01*
X1349195Y945194D01*
X1349028Y944902D01*
X1348778Y944652D01*
X1348486Y944486D01*
X1348153Y944444D01*
G01X1348486Y945111D02*
X1348986Y944444D01*
G01X1350461Y946527D02*
X1350711Y946777D01*
X1351003Y946902D01*
X1351336Y946944D01*
X1351753Y946861D01*
X1352045Y946652D01*
X1352128Y946402D01*
X1352086Y946152D01*
X1351920Y945944D01*
X1351086Y945527D01*
X1350711Y945236D01*
X1350461Y944819D01*
X1350378Y944444D01*
X1352128D01*
G01X1353436Y944944D02*
X1353686Y944652D01*
X1354020Y944486D01*
X1354395Y944444D01*
X1354728Y944486D01*
X1355061Y944694D01*
X1355270Y944944D01*
X1355311Y945194D01*
X1355228Y945486D01*
X1354936Y945694D01*
X1354645Y945777D01*
X1354270D01*
G01X1354645D02*
X1354895Y945902D01*
X1355103Y946111D01*
X1355186Y946361D01*
X1355103Y946611D01*
X1354895Y946819D01*
X1354520Y946944D01*
X1354145Y946902D01*
X1353770Y946736D01*
G01X1357953Y944444D02*
Y946944D01*
X1356411Y945152D01*
X1358495D01*
G01X1359303Y948944D02*
Y962944D01*
G01X1346303Y948944D02*
X1359303D01*
G01X1346303Y962944D02*
Y948944D01*
G01X1359303Y962944D02*
X1346303D01*
G01X1379382Y947772D02*
X1376882D01*
Y948813D01*
X1377007Y949147D01*
X1377174Y949355D01*
X1377507Y949438D01*
X1377840Y949355D01*
X1378049Y949105D01*
X1378174Y948813D01*
Y947772D01*
G01Y948813D02*
X1379382Y949438D01*
G01X1377299Y950913D02*
X1377049Y951163D01*
X1376924Y951455D01*
X1376882Y951788D01*
X1376965Y952205D01*
X1377174Y952497D01*
X1377424Y952580D01*
X1377674Y952538D01*
X1377882Y952372D01*
X1378299Y951538D01*
X1378590Y951163D01*
X1379007Y950913D01*
X1379382Y950830D01*
Y952580D01*
G01Y955305D02*
X1376882D01*
X1378674Y953763D01*
Y955847D01*
G01X1378340Y957113D02*
X1378049Y957405D01*
X1377882Y957655D01*
X1377799Y957988D01*
X1377882Y958280D01*
X1378049Y958488D01*
X1378299Y958655D01*
X1378590Y958697D01*
X1378840Y958655D01*
X1379090Y958488D01*
X1379299Y958238D01*
X1379382Y957947D01*
X1379299Y957613D01*
X1379049Y957322D01*
X1378674Y957155D01*
X1378257Y957113D01*
X1377715Y957197D01*
X1377424Y957322D01*
X1377132Y957530D01*
X1376924Y957822D01*
X1376882Y958113D01*
X1376965Y958405D01*
X1377174Y958613D01*
G01X1374382Y947772D02*
X1371882D01*
Y948813D01*
X1372007Y949147D01*
X1372174Y949355D01*
X1372507Y949438D01*
X1372840Y949355D01*
X1373049Y949105D01*
X1373174Y948813D01*
Y947772D01*
G01Y948813D02*
X1374382Y949438D01*
G01X1372299Y950913D02*
X1372049Y951163D01*
X1371924Y951455D01*
X1371882Y951788D01*
X1371965Y952205D01*
X1372174Y952497D01*
X1372424Y952580D01*
X1372674Y952538D01*
X1372882Y952372D01*
X1373299Y951538D01*
X1373590Y951163D01*
X1374007Y950913D01*
X1374382Y950830D01*
Y952580D01*
G01Y955305D02*
X1371882D01*
X1373674Y953763D01*
Y955847D01*
G01X1373882Y956988D02*
X1374174Y957238D01*
X1374340Y957572D01*
X1374382Y957947D01*
X1374340Y958280D01*
X1374132Y958613D01*
X1373882Y958822D01*
X1373632Y958863D01*
X1373340Y958780D01*
X1373132Y958488D01*
X1373049Y958197D01*
Y957822D01*
G01Y958197D02*
X1372924Y958447D01*
X1372715Y958655D01*
X1372465Y958738D01*
X1372215Y958655D01*
X1372007Y958447D01*
X1371882Y958072D01*
X1371924Y957697D01*
X1372090Y957322D01*
G01X1371758Y1078196D02*
X1371508Y1078321D01*
X1371216Y1078404D01*
X1370883D01*
X1370508Y1078279D01*
X1370216Y1078071D01*
X1370008Y1077821D01*
X1369841Y1077404D01*
X1369799Y1077029D01*
X1369883Y1076654D01*
X1370008Y1076404D01*
X1370258Y1076154D01*
X1370549Y1075987D01*
X1370841Y1075904D01*
X1371133D01*
X1371424Y1075987D01*
X1371674Y1076112D01*
X1371883Y1076279D01*
G01X1373941Y1075904D02*
Y1078404D01*
X1373441Y1077904D01*
G01Y1075904D02*
X1374441D01*
G01X1376124Y1076404D02*
X1376374Y1076112D01*
X1376708Y1075946D01*
X1377083Y1075904D01*
X1377416Y1075946D01*
X1377749Y1076154D01*
X1377958Y1076404D01*
X1377999Y1076654D01*
X1377916Y1076946D01*
X1377624Y1077154D01*
X1377333Y1077237D01*
X1376958D01*
G01X1377333D02*
X1377583Y1077362D01*
X1377791Y1077571D01*
X1377874Y1077821D01*
X1377791Y1078071D01*
X1377583Y1078279D01*
X1377208Y1078404D01*
X1376833Y1078362D01*
X1376458Y1078196D01*
G01X1380141Y1078404D02*
X1379808Y1078321D01*
X1379558Y1078112D01*
X1379391Y1077862D01*
X1379266Y1077529D01*
X1379224Y1077154D01*
X1379266Y1076779D01*
X1379391Y1076446D01*
X1379558Y1076196D01*
X1379808Y1075987D01*
X1380141Y1075904D01*
X1380474Y1075987D01*
X1380724Y1076196D01*
X1380891Y1076446D01*
X1381016Y1076779D01*
X1381058Y1077154D01*
X1381016Y1077529D01*
X1380891Y1077862D01*
X1380724Y1078112D01*
X1380474Y1078321D01*
X1380141Y1078404D01*
G01X1371767Y1081792D02*
X1371517Y1081917D01*
X1371225Y1082000D01*
X1370892D01*
X1370517Y1081875D01*
X1370225Y1081667D01*
X1370017Y1081417D01*
X1369850Y1081000D01*
X1369808Y1080625D01*
X1369892Y1080250D01*
X1370017Y1080000D01*
X1370267Y1079750D01*
X1370558Y1079583D01*
X1370850Y1079500D01*
X1371142D01*
X1371433Y1079583D01*
X1371683Y1079708D01*
X1371892Y1079875D01*
G01X1373950Y1079500D02*
Y1082000D01*
X1373450Y1081500D01*
G01Y1079500D02*
X1374450D01*
G01X1376258Y1081583D02*
X1376508Y1081833D01*
X1376800Y1081958D01*
X1377133Y1082000D01*
X1377550Y1081917D01*
X1377842Y1081708D01*
X1377925Y1081458D01*
X1377883Y1081208D01*
X1377717Y1081000D01*
X1376883Y1080583D01*
X1376508Y1080292D01*
X1376258Y1079875D01*
X1376175Y1079500D01*
X1377925D01*
G01X1379442Y1079792D02*
X1379733Y1079583D01*
X1380067Y1079500D01*
X1380400Y1079583D01*
X1380692Y1079833D01*
X1380900Y1080208D01*
X1380983Y1080583D01*
Y1081042D01*
X1380900Y1081417D01*
X1380692Y1081750D01*
X1380442Y1081917D01*
X1380150Y1082000D01*
X1379817Y1081917D01*
X1379567Y1081750D01*
X1379400Y1081500D01*
X1379317Y1081167D01*
X1379400Y1080875D01*
X1379608Y1080583D01*
X1379858Y1080417D01*
X1380150Y1080375D01*
X1380483Y1080458D01*
X1380733Y1080667D01*
X1380983Y1081042D01*
G01X1339517Y1098500D02*
Y1101000D01*
X1340558D01*
X1340892Y1100875D01*
X1341100Y1100708D01*
X1341183Y1100375D01*
X1341100Y1100042D01*
X1340850Y1099833D01*
X1340558Y1099708D01*
X1339517D01*
G01X1340558D02*
X1341183Y1098500D01*
G01X1342658Y1100583D02*
X1342908Y1100833D01*
X1343200Y1100958D01*
X1343533Y1101000D01*
X1343950Y1100917D01*
X1344242Y1100708D01*
X1344325Y1100458D01*
X1344283Y1100208D01*
X1344117Y1100000D01*
X1343283Y1099583D01*
X1342908Y1099292D01*
X1342658Y1098875D01*
X1342575Y1098500D01*
X1344325D01*
G01X1346467D02*
X1346550Y1099042D01*
X1346675Y1099500D01*
X1346842Y1099917D01*
X1347050Y1100375D01*
X1347383Y1101000D01*
X1345717D01*
G01X1348733Y1098875D02*
X1348983Y1098667D01*
X1349275Y1098542D01*
X1349650Y1098500D01*
X1350025Y1098583D01*
X1350317Y1098750D01*
X1350525Y1099042D01*
X1350567Y1099375D01*
X1350483Y1099708D01*
X1350275Y1099917D01*
X1349983Y1100083D01*
X1349692Y1100125D01*
X1349400Y1100083D01*
X1349025Y1099917D01*
X1349150Y1101000D01*
X1350275D01*
G01X1347000Y1085590D02*
X1344500D01*
Y1086631D01*
X1344625Y1086965D01*
X1344792Y1087173D01*
X1345125Y1087256D01*
X1345458Y1087173D01*
X1345667Y1086923D01*
X1345792Y1086631D01*
Y1085590D01*
G01Y1086631D02*
X1347000Y1087256D01*
G01X1344917Y1088731D02*
X1344667Y1088981D01*
X1344542Y1089273D01*
X1344500Y1089606D01*
X1344583Y1090023D01*
X1344792Y1090315D01*
X1345042Y1090398D01*
X1345292Y1090356D01*
X1345500Y1090190D01*
X1345917Y1089356D01*
X1346208Y1088981D01*
X1346625Y1088731D01*
X1347000Y1088648D01*
Y1090398D01*
G01Y1092623D02*
X1346958Y1092915D01*
X1346833Y1093248D01*
X1346625Y1093456D01*
X1346333Y1093540D01*
X1346042Y1093456D01*
X1345792Y1093206D01*
X1345667Y1092831D01*
Y1092415D01*
X1345583Y1092165D01*
X1345375Y1091956D01*
X1345083Y1091873D01*
X1344792Y1091998D01*
X1344583Y1092290D01*
X1344500Y1092623D01*
X1344583Y1092956D01*
X1344792Y1093248D01*
X1345083Y1093373D01*
X1345375Y1093290D01*
X1345583Y1093081D01*
X1345667Y1092831D01*
Y1092415D01*
X1345792Y1092040D01*
X1346042Y1091790D01*
X1346333Y1091706D01*
X1346625Y1091790D01*
X1346833Y1091998D01*
X1346958Y1092331D01*
X1347000Y1092623D01*
G01X1344917Y1094931D02*
X1344667Y1095181D01*
X1344542Y1095473D01*
X1344500Y1095806D01*
X1344583Y1096223D01*
X1344792Y1096515D01*
X1345042Y1096598D01*
X1345292Y1096556D01*
X1345500Y1096390D01*
X1345917Y1095556D01*
X1346208Y1095181D01*
X1346625Y1094931D01*
X1347000Y1094848D01*
Y1096598D01*
G01X1339017Y1127673D02*
Y1130173D01*
X1340058D01*
X1340392Y1130048D01*
X1340600Y1129881D01*
X1340683Y1129548D01*
X1340600Y1129215D01*
X1340350Y1129006D01*
X1340058Y1128881D01*
X1339017D01*
G01X1340058D02*
X1340683Y1127673D01*
G01X1342158Y1129756D02*
X1342408Y1130006D01*
X1342700Y1130131D01*
X1343033Y1130173D01*
X1343450Y1130090D01*
X1343742Y1129881D01*
X1343825Y1129631D01*
X1343783Y1129381D01*
X1343617Y1129173D01*
X1342783Y1128756D01*
X1342408Y1128465D01*
X1342158Y1128048D01*
X1342075Y1127673D01*
X1343825D01*
G01X1346050D02*
X1346342Y1127715D01*
X1346675Y1127840D01*
X1346883Y1128048D01*
X1346967Y1128340D01*
X1346883Y1128631D01*
X1346633Y1128881D01*
X1346258Y1129006D01*
X1345842D01*
X1345592Y1129090D01*
X1345383Y1129298D01*
X1345300Y1129590D01*
X1345425Y1129881D01*
X1345717Y1130090D01*
X1346050Y1130173D01*
X1346383Y1130090D01*
X1346675Y1129881D01*
X1346800Y1129590D01*
X1346717Y1129298D01*
X1346508Y1129090D01*
X1346258Y1129006D01*
X1345842D01*
X1345467Y1128881D01*
X1345217Y1128631D01*
X1345133Y1128340D01*
X1345217Y1128048D01*
X1345425Y1127840D01*
X1345758Y1127715D01*
X1346050Y1127673D01*
G01X1348233Y1128173D02*
X1348483Y1127881D01*
X1348817Y1127715D01*
X1349192Y1127673D01*
X1349525Y1127715D01*
X1349858Y1127923D01*
X1350067Y1128173D01*
X1350108Y1128423D01*
X1350025Y1128715D01*
X1349733Y1128923D01*
X1349442Y1129006D01*
X1349067D01*
G01X1349442D02*
X1349692Y1129131D01*
X1349900Y1129340D01*
X1349983Y1129590D01*
X1349900Y1129840D01*
X1349692Y1130048D01*
X1349317Y1130173D01*
X1348942Y1130131D01*
X1348567Y1129965D01*
G01X1337200Y1127173D02*
Y1131173D01*
X1329800D01*
G01X1352517Y1102673D02*
Y1105173D01*
X1353558D01*
X1353892Y1105048D01*
X1354100Y1104881D01*
X1354183Y1104548D01*
X1354100Y1104215D01*
X1353850Y1104006D01*
X1353558Y1103881D01*
X1352517D01*
G01X1353558D02*
X1354183Y1102673D01*
G01X1355658Y1104756D02*
X1355908Y1105006D01*
X1356200Y1105131D01*
X1356533Y1105173D01*
X1356950Y1105090D01*
X1357242Y1104881D01*
X1357325Y1104631D01*
X1357283Y1104381D01*
X1357117Y1104173D01*
X1356283Y1103756D01*
X1355908Y1103465D01*
X1355658Y1103048D01*
X1355575Y1102673D01*
X1357325D01*
G01X1359550D02*
X1359842Y1102715D01*
X1360175Y1102840D01*
X1360383Y1103048D01*
X1360467Y1103340D01*
X1360383Y1103631D01*
X1360133Y1103881D01*
X1359758Y1104006D01*
X1359342D01*
X1359092Y1104090D01*
X1358883Y1104298D01*
X1358800Y1104590D01*
X1358925Y1104881D01*
X1359217Y1105090D01*
X1359550Y1105173D01*
X1359883Y1105090D01*
X1360175Y1104881D01*
X1360300Y1104590D01*
X1360217Y1104298D01*
X1360008Y1104090D01*
X1359758Y1104006D01*
X1359342D01*
X1358967Y1103881D01*
X1358717Y1103631D01*
X1358633Y1103340D01*
X1358717Y1103048D01*
X1358925Y1102840D01*
X1359258Y1102715D01*
X1359550Y1102673D01*
G01X1363150D02*
Y1105173D01*
X1361608Y1103381D01*
X1363692D01*
G01X1342500Y1085590D02*
X1340000D01*
Y1086631D01*
X1340125Y1086965D01*
X1340292Y1087173D01*
X1340625Y1087256D01*
X1340958Y1087173D01*
X1341167Y1086923D01*
X1341292Y1086631D01*
Y1085590D01*
G01Y1086631D02*
X1342500Y1087256D01*
G01X1340417Y1088731D02*
X1340167Y1088981D01*
X1340042Y1089273D01*
X1340000Y1089606D01*
X1340083Y1090023D01*
X1340292Y1090315D01*
X1340542Y1090398D01*
X1340792Y1090356D01*
X1341000Y1090190D01*
X1341417Y1089356D01*
X1341708Y1088981D01*
X1342125Y1088731D01*
X1342500Y1088648D01*
Y1090398D01*
G01Y1092623D02*
X1342458Y1092915D01*
X1342333Y1093248D01*
X1342125Y1093456D01*
X1341833Y1093540D01*
X1341542Y1093456D01*
X1341292Y1093206D01*
X1341167Y1092831D01*
Y1092415D01*
X1341083Y1092165D01*
X1340875Y1091956D01*
X1340583Y1091873D01*
X1340292Y1091998D01*
X1340083Y1092290D01*
X1340000Y1092623D01*
X1340083Y1092956D01*
X1340292Y1093248D01*
X1340583Y1093373D01*
X1340875Y1093290D01*
X1341083Y1093081D01*
X1341167Y1092831D01*
Y1092415D01*
X1341292Y1092040D01*
X1341542Y1091790D01*
X1341833Y1091706D01*
X1342125Y1091790D01*
X1342333Y1091998D01*
X1342458Y1092331D01*
X1342500Y1092623D01*
G01X1342125Y1094806D02*
X1342333Y1095056D01*
X1342458Y1095348D01*
X1342500Y1095723D01*
X1342417Y1096098D01*
X1342250Y1096390D01*
X1341958Y1096598D01*
X1341625Y1096640D01*
X1341292Y1096556D01*
X1341083Y1096348D01*
X1340917Y1096056D01*
X1340875Y1095765D01*
X1340917Y1095473D01*
X1341083Y1095098D01*
X1340000Y1095223D01*
Y1096348D01*
G01X1362017Y1117000D02*
Y1119500D01*
X1363058D01*
X1363392Y1119375D01*
X1363600Y1119208D01*
X1363683Y1118875D01*
X1363600Y1118542D01*
X1363350Y1118333D01*
X1363058Y1118208D01*
X1362017D01*
G01X1363058D02*
X1363683Y1117000D01*
G01X1365033Y1117375D02*
X1365283Y1117167D01*
X1365575Y1117042D01*
X1365950Y1117000D01*
X1366325Y1117083D01*
X1366617Y1117250D01*
X1366825Y1117542D01*
X1366867Y1117875D01*
X1366783Y1118208D01*
X1366575Y1118417D01*
X1366283Y1118583D01*
X1365992Y1118625D01*
X1365700Y1118583D01*
X1365325Y1118417D01*
X1365450Y1119500D01*
X1366575D01*
G01X1368967Y1117000D02*
X1369050Y1117542D01*
X1369175Y1118000D01*
X1369342Y1118417D01*
X1369550Y1118875D01*
X1369883Y1119500D01*
X1368217D01*
G01X1372150Y1117000D02*
X1372442Y1117042D01*
X1372775Y1117167D01*
X1372983Y1117375D01*
X1373067Y1117667D01*
X1372983Y1117958D01*
X1372733Y1118208D01*
X1372358Y1118333D01*
X1371942D01*
X1371692Y1118417D01*
X1371483Y1118625D01*
X1371400Y1118917D01*
X1371525Y1119208D01*
X1371817Y1119417D01*
X1372150Y1119500D01*
X1372483Y1119417D01*
X1372775Y1119208D01*
X1372900Y1118917D01*
X1372817Y1118625D01*
X1372608Y1118417D01*
X1372358Y1118333D01*
X1371942D01*
X1371567Y1118208D01*
X1371317Y1117958D01*
X1371233Y1117667D01*
X1371317Y1117375D01*
X1371525Y1117167D01*
X1371858Y1117042D01*
X1372150Y1117000D01*
G01X1359954Y1125365D02*
Y1121365D01*
X1367354D01*
G01X1372000Y1130850D02*
X1371958Y1130517D01*
X1371792Y1130225D01*
X1371542Y1129975D01*
X1371250Y1129808D01*
X1370917Y1129725D01*
X1370583D01*
X1370250Y1129808D01*
X1369958Y1129975D01*
X1369708Y1130225D01*
X1369542Y1130517D01*
X1369500Y1130850D01*
X1369542Y1131183D01*
X1369708Y1131475D01*
X1369958Y1131725D01*
X1370250Y1131892D01*
X1370583Y1131975D01*
X1370917D01*
X1371250Y1131892D01*
X1371542Y1131725D01*
X1371792Y1131475D01*
X1371958Y1131183D01*
X1372000Y1130850D01*
G01X1371333Y1131183D02*
X1372000Y1131683D01*
G01X1369917Y1133158D02*
X1369667Y1133408D01*
X1369542Y1133700D01*
X1369500Y1134033D01*
X1369583Y1134450D01*
X1369792Y1134742D01*
X1370042Y1134825D01*
X1370292Y1134783D01*
X1370500Y1134617D01*
X1370917Y1133783D01*
X1371208Y1133408D01*
X1371625Y1133158D01*
X1372000Y1133075D01*
Y1134825D01*
G01X1371708Y1136342D02*
X1371917Y1136633D01*
X1372000Y1136967D01*
X1371917Y1137300D01*
X1371667Y1137592D01*
X1371292Y1137800D01*
X1370917Y1137883D01*
X1370458D01*
X1370083Y1137800D01*
X1369750Y1137592D01*
X1369583Y1137342D01*
X1369500Y1137050D01*
X1369583Y1136717D01*
X1369750Y1136467D01*
X1370000Y1136300D01*
X1370333Y1136217D01*
X1370625Y1136300D01*
X1370917Y1136508D01*
X1371083Y1136758D01*
X1371125Y1137050D01*
X1371042Y1137383D01*
X1370833Y1137633D01*
X1370458Y1137883D01*
G01X1372000Y1140650D02*
X1369500D01*
X1371292Y1139108D01*
Y1141192D01*
G01X1355086Y1142405D02*
Y1128405D01*
G01X1368086D02*
Y1142405D01*
G01X1355086Y1128405D02*
X1368086D01*
G01X1352533Y1098500D02*
Y1101000D01*
X1353367D01*
X1353700Y1100875D01*
X1353950Y1100708D01*
X1354158Y1100458D01*
X1354325Y1100167D01*
X1354367Y1099750D01*
X1354325Y1099333D01*
X1354158Y1099042D01*
X1353950Y1098792D01*
X1353700Y1098625D01*
X1353367Y1098500D01*
X1352533D01*
G01X1355758Y1099542D02*
X1356050Y1099833D01*
X1356300Y1100000D01*
X1356633Y1100083D01*
X1356925Y1100000D01*
X1357133Y1099833D01*
X1357300Y1099583D01*
X1357342Y1099292D01*
X1357300Y1099042D01*
X1357133Y1098792D01*
X1356883Y1098583D01*
X1356592Y1098500D01*
X1356258Y1098583D01*
X1355967Y1098833D01*
X1355800Y1099208D01*
X1355758Y1099625D01*
X1355842Y1100167D01*
X1355967Y1100458D01*
X1356175Y1100750D01*
X1356467Y1100958D01*
X1356758Y1101000D01*
X1357050Y1100917D01*
X1357258Y1100708D01*
G01X1336500Y1097173D02*
Y1090173D01*
G01X1340767Y1134065D02*
X1340517Y1134190D01*
X1340225Y1134273D01*
X1339892D01*
X1339517Y1134148D01*
X1339225Y1133940D01*
X1339017Y1133690D01*
X1338850Y1133273D01*
X1338808Y1132898D01*
X1338892Y1132523D01*
X1339017Y1132273D01*
X1339267Y1132023D01*
X1339558Y1131856D01*
X1339850Y1131773D01*
X1340142D01*
X1340433Y1131856D01*
X1340683Y1131981D01*
X1340892Y1132148D01*
G01X1342950Y1131773D02*
Y1134273D01*
X1342450Y1133773D01*
G01Y1131773D02*
X1343450D01*
G01X1345258Y1133856D02*
X1345508Y1134106D01*
X1345800Y1134231D01*
X1346133Y1134273D01*
X1346550Y1134190D01*
X1346842Y1133981D01*
X1346925Y1133731D01*
X1346883Y1133481D01*
X1346717Y1133273D01*
X1345883Y1132856D01*
X1345508Y1132565D01*
X1345258Y1132148D01*
X1345175Y1131773D01*
X1346925D01*
G01X1349067D02*
X1349150Y1132315D01*
X1349275Y1132773D01*
X1349442Y1133190D01*
X1349650Y1133648D01*
X1349983Y1134273D01*
X1348317D01*
G01X1341267Y1104892D02*
X1341017Y1105017D01*
X1340725Y1105100D01*
X1340392D01*
X1340017Y1104975D01*
X1339725Y1104767D01*
X1339517Y1104517D01*
X1339350Y1104100D01*
X1339308Y1103725D01*
X1339392Y1103350D01*
X1339517Y1103100D01*
X1339767Y1102850D01*
X1340058Y1102683D01*
X1340350Y1102600D01*
X1340642D01*
X1340933Y1102683D01*
X1341183Y1102808D01*
X1341392Y1102975D01*
G01X1343450Y1102600D02*
Y1105100D01*
X1342950Y1104600D01*
G01Y1102600D02*
X1343950D01*
G01X1345758Y1104683D02*
X1346008Y1104933D01*
X1346300Y1105058D01*
X1346633Y1105100D01*
X1347050Y1105017D01*
X1347342Y1104808D01*
X1347425Y1104558D01*
X1347383Y1104308D01*
X1347217Y1104100D01*
X1346383Y1103683D01*
X1346008Y1103392D01*
X1345758Y1102975D01*
X1345675Y1102600D01*
X1347425D01*
G01X1348858Y1103642D02*
X1349150Y1103933D01*
X1349400Y1104100D01*
X1349733Y1104183D01*
X1350025Y1104100D01*
X1350233Y1103933D01*
X1350400Y1103683D01*
X1350442Y1103392D01*
X1350400Y1103142D01*
X1350233Y1102892D01*
X1349983Y1102683D01*
X1349692Y1102600D01*
X1349358Y1102683D01*
X1349067Y1102933D01*
X1348900Y1103308D01*
X1348858Y1103725D01*
X1348942Y1104267D01*
X1349067Y1104558D01*
X1349275Y1104850D01*
X1349567Y1105058D01*
X1349858Y1105100D01*
X1350150Y1105017D01*
X1350358Y1104808D01*
G01X1377730Y1141273D02*
Y1143773D01*
X1378771D01*
X1379105Y1143648D01*
X1379313Y1143481D01*
X1379396Y1143148D01*
X1379313Y1142815D01*
X1379063Y1142606D01*
X1378771Y1142481D01*
X1377730D01*
G01X1378771D02*
X1379396Y1141273D01*
G01X1380871Y1143356D02*
X1381121Y1143606D01*
X1381413Y1143731D01*
X1381746Y1143773D01*
X1382163Y1143690D01*
X1382455Y1143481D01*
X1382538Y1143231D01*
X1382496Y1142981D01*
X1382330Y1142773D01*
X1381496Y1142356D01*
X1381121Y1142065D01*
X1380871Y1141648D01*
X1380788Y1141273D01*
X1382538D01*
G01X1384055Y1141565D02*
X1384346Y1141356D01*
X1384680Y1141273D01*
X1385013Y1141356D01*
X1385305Y1141606D01*
X1385513Y1141981D01*
X1385596Y1142356D01*
Y1142815D01*
X1385513Y1143190D01*
X1385305Y1143523D01*
X1385055Y1143690D01*
X1384763Y1143773D01*
X1384430Y1143690D01*
X1384180Y1143523D01*
X1384013Y1143273D01*
X1383930Y1142940D01*
X1384013Y1142648D01*
X1384221Y1142356D01*
X1384471Y1142190D01*
X1384763Y1142148D01*
X1385096Y1142231D01*
X1385346Y1142440D01*
X1385596Y1142815D01*
G01X1387863Y1141273D02*
Y1143773D01*
X1387363Y1143273D01*
G01Y1141273D02*
X1388363D01*
G01X1373513Y1152273D02*
Y1148273D01*
X1380913D01*
G01X1342017Y1145500D02*
Y1148000D01*
X1343058D01*
X1343392Y1147875D01*
X1343600Y1147708D01*
X1343683Y1147375D01*
X1343600Y1147042D01*
X1343350Y1146833D01*
X1343058Y1146708D01*
X1342017D01*
G01X1343058D02*
X1343683Y1145500D01*
G01X1345033Y1145875D02*
X1345283Y1145667D01*
X1345575Y1145542D01*
X1345950Y1145500D01*
X1346325Y1145583D01*
X1346617Y1145750D01*
X1346825Y1146042D01*
X1346867Y1146375D01*
X1346783Y1146708D01*
X1346575Y1146917D01*
X1346283Y1147083D01*
X1345992Y1147125D01*
X1345700Y1147083D01*
X1345325Y1146917D01*
X1345450Y1148000D01*
X1346575D01*
G01X1349050Y1145500D02*
X1349342Y1145542D01*
X1349675Y1145667D01*
X1349883Y1145875D01*
X1349967Y1146167D01*
X1349883Y1146458D01*
X1349633Y1146708D01*
X1349258Y1146833D01*
X1348842D01*
X1348592Y1146917D01*
X1348383Y1147125D01*
X1348300Y1147417D01*
X1348425Y1147708D01*
X1348717Y1147917D01*
X1349050Y1148000D01*
X1349383Y1147917D01*
X1349675Y1147708D01*
X1349800Y1147417D01*
X1349717Y1147125D01*
X1349508Y1146917D01*
X1349258Y1146833D01*
X1348842D01*
X1348467Y1146708D01*
X1348217Y1146458D01*
X1348133Y1146167D01*
X1348217Y1145875D01*
X1348425Y1145667D01*
X1348758Y1145542D01*
X1349050Y1145500D01*
G01X1352150D02*
X1352442Y1145542D01*
X1352775Y1145667D01*
X1352983Y1145875D01*
X1353067Y1146167D01*
X1352983Y1146458D01*
X1352733Y1146708D01*
X1352358Y1146833D01*
X1351942D01*
X1351692Y1146917D01*
X1351483Y1147125D01*
X1351400Y1147417D01*
X1351525Y1147708D01*
X1351817Y1147917D01*
X1352150Y1148000D01*
X1352483Y1147917D01*
X1352775Y1147708D01*
X1352900Y1147417D01*
X1352817Y1147125D01*
X1352608Y1146917D01*
X1352358Y1146833D01*
X1351942D01*
X1351567Y1146708D01*
X1351317Y1146458D01*
X1351233Y1146167D01*
X1351317Y1145875D01*
X1351525Y1145667D01*
X1351858Y1145542D01*
X1352150Y1145500D01*
G01X1359263Y1149073D02*
Y1145073D01*
X1366663D01*
G01X1368086Y1142405D02*
X1355086D01*
G01X1356350Y1166000D02*
X1356017Y1166042D01*
X1355725Y1166208D01*
X1355475Y1166458D01*
X1355308Y1166750D01*
X1355225Y1167083D01*
Y1167417D01*
X1355308Y1167750D01*
X1355475Y1168042D01*
X1355725Y1168292D01*
X1356017Y1168458D01*
X1356350Y1168500D01*
X1356683Y1168458D01*
X1356975Y1168292D01*
X1357225Y1168042D01*
X1357392Y1167750D01*
X1357475Y1167417D01*
Y1167083D01*
X1357392Y1166750D01*
X1357225Y1166458D01*
X1356975Y1166208D01*
X1356683Y1166042D01*
X1356350Y1166000D01*
G01X1356683Y1166667D02*
X1357183Y1166000D01*
G01X1358658Y1168083D02*
X1358908Y1168333D01*
X1359200Y1168458D01*
X1359533Y1168500D01*
X1359950Y1168417D01*
X1360242Y1168208D01*
X1360325Y1167958D01*
X1360283Y1167708D01*
X1360117Y1167500D01*
X1359283Y1167083D01*
X1358908Y1166792D01*
X1358658Y1166375D01*
X1358575Y1166000D01*
X1360325D01*
G01X1361633Y1166375D02*
X1361883Y1166167D01*
X1362175Y1166042D01*
X1362550Y1166000D01*
X1362925Y1166083D01*
X1363217Y1166250D01*
X1363425Y1166542D01*
X1363467Y1166875D01*
X1363383Y1167208D01*
X1363175Y1167417D01*
X1362883Y1167583D01*
X1362592Y1167625D01*
X1362300Y1167583D01*
X1361925Y1167417D01*
X1362050Y1168500D01*
X1363175D01*
G01X1365650Y1166000D02*
X1365942Y1166042D01*
X1366275Y1166167D01*
X1366483Y1166375D01*
X1366567Y1166667D01*
X1366483Y1166958D01*
X1366233Y1167208D01*
X1365858Y1167333D01*
X1365442D01*
X1365192Y1167417D01*
X1364983Y1167625D01*
X1364900Y1167917D01*
X1365025Y1168208D01*
X1365317Y1168417D01*
X1365650Y1168500D01*
X1365983Y1168417D01*
X1366275Y1168208D01*
X1366400Y1167917D01*
X1366317Y1167625D01*
X1366108Y1167417D01*
X1365858Y1167333D01*
X1365442D01*
X1365067Y1167208D01*
X1364817Y1166958D01*
X1364733Y1166667D01*
X1364817Y1166375D01*
X1365025Y1166167D01*
X1365358Y1166042D01*
X1365650Y1166000D01*
G01X1354294Y1163974D02*
Y1149974D01*
G01X1367294Y1163974D02*
X1354294D01*
G01X1367294Y1149974D02*
Y1163974D01*
G01X1354294Y1149974D02*
X1367294D01*
G01X1364850Y1177666D02*
Y1175166D01*
G01X1363892Y1177666D02*
X1365808D01*
G01X1367117Y1175166D02*
Y1177666D01*
X1368117D01*
X1368450Y1177541D01*
X1368700Y1177249D01*
X1368783Y1176916D01*
X1368700Y1176583D01*
X1368492Y1176333D01*
X1368117Y1176208D01*
X1367117D01*
G01X1370133Y1175666D02*
X1370383Y1175374D01*
X1370717Y1175208D01*
X1371092Y1175166D01*
X1371425Y1175208D01*
X1371758Y1175416D01*
X1371967Y1175666D01*
X1372008Y1175916D01*
X1371925Y1176208D01*
X1371633Y1176416D01*
X1371342Y1176499D01*
X1370967D01*
G01X1371342D02*
X1371592Y1176624D01*
X1371800Y1176833D01*
X1371883Y1177083D01*
X1371800Y1177333D01*
X1371592Y1177541D01*
X1371217Y1177666D01*
X1370842Y1177624D01*
X1370467Y1177458D01*
G01X1374067Y1175166D02*
X1374150Y1175708D01*
X1374275Y1176166D01*
X1374442Y1176583D01*
X1374650Y1177041D01*
X1374983Y1177666D01*
X1373317D01*
G01X1351500Y1165517D02*
X1349000D01*
Y1166558D01*
X1349125Y1166892D01*
X1349292Y1167100D01*
X1349625Y1167183D01*
X1349958Y1167100D01*
X1350167Y1166850D01*
X1350292Y1166558D01*
Y1165517D01*
G01Y1166558D02*
X1351500Y1167183D01*
G01X1349417Y1168658D02*
X1349167Y1168908D01*
X1349042Y1169200D01*
X1349000Y1169533D01*
X1349083Y1169950D01*
X1349292Y1170242D01*
X1349542Y1170325D01*
X1349792Y1170283D01*
X1350000Y1170117D01*
X1350417Y1169283D01*
X1350708Y1168908D01*
X1351125Y1168658D01*
X1351500Y1168575D01*
Y1170325D01*
G01Y1172550D02*
X1351458Y1172842D01*
X1351333Y1173175D01*
X1351125Y1173383D01*
X1350833Y1173467D01*
X1350542Y1173383D01*
X1350292Y1173133D01*
X1350167Y1172758D01*
Y1172342D01*
X1350083Y1172092D01*
X1349875Y1171883D01*
X1349583Y1171800D01*
X1349292Y1171925D01*
X1349083Y1172217D01*
X1349000Y1172550D01*
X1349083Y1172883D01*
X1349292Y1173175D01*
X1349583Y1173300D01*
X1349875Y1173217D01*
X1350083Y1173008D01*
X1350167Y1172758D01*
Y1172342D01*
X1350292Y1171967D01*
X1350542Y1171717D01*
X1350833Y1171633D01*
X1351125Y1171717D01*
X1351333Y1171925D01*
X1351458Y1172258D01*
X1351500Y1172550D01*
G01X1349000Y1175650D02*
X1349083Y1175317D01*
X1349292Y1175067D01*
X1349542Y1174900D01*
X1349875Y1174775D01*
X1350250Y1174733D01*
X1350625Y1174775D01*
X1350958Y1174900D01*
X1351208Y1175067D01*
X1351417Y1175317D01*
X1351500Y1175650D01*
X1351417Y1175983D01*
X1351208Y1176233D01*
X1350958Y1176400D01*
X1350625Y1176525D01*
X1350250Y1176567D01*
X1349875Y1176525D01*
X1349542Y1176400D01*
X1349292Y1176233D01*
X1349083Y1175983D01*
X1349000Y1175650D01*
G01X1347334Y1165517D02*
X1344834D01*
Y1166558D01*
X1344959Y1166892D01*
X1345126Y1167100D01*
X1345459Y1167183D01*
X1345792Y1167100D01*
X1346001Y1166850D01*
X1346126Y1166558D01*
Y1165517D01*
G01Y1166558D02*
X1347334Y1167183D01*
G01X1345251Y1168658D02*
X1345001Y1168908D01*
X1344876Y1169200D01*
X1344834Y1169533D01*
X1344917Y1169950D01*
X1345126Y1170242D01*
X1345376Y1170325D01*
X1345626Y1170283D01*
X1345834Y1170117D01*
X1346251Y1169283D01*
X1346542Y1168908D01*
X1346959Y1168658D01*
X1347334Y1168575D01*
Y1170325D01*
G01Y1172550D02*
X1347292Y1172842D01*
X1347167Y1173175D01*
X1346959Y1173383D01*
X1346667Y1173467D01*
X1346376Y1173383D01*
X1346126Y1173133D01*
X1346001Y1172758D01*
Y1172342D01*
X1345917Y1172092D01*
X1345709Y1171883D01*
X1345417Y1171800D01*
X1345126Y1171925D01*
X1344917Y1172217D01*
X1344834Y1172550D01*
X1344917Y1172883D01*
X1345126Y1173175D01*
X1345417Y1173300D01*
X1345709Y1173217D01*
X1345917Y1173008D01*
X1346001Y1172758D01*
Y1172342D01*
X1346126Y1171967D01*
X1346376Y1171717D01*
X1346667Y1171633D01*
X1346959Y1171717D01*
X1347167Y1171925D01*
X1347292Y1172258D01*
X1347334Y1172550D01*
G01Y1175567D02*
X1346792Y1175650D01*
X1346334Y1175775D01*
X1345917Y1175942D01*
X1345459Y1176150D01*
X1344834Y1176483D01*
Y1174817D01*
G01X1379480Y1139465D02*
X1379230Y1139590D01*
X1378938Y1139673D01*
X1378605D01*
X1378230Y1139548D01*
X1377938Y1139340D01*
X1377730Y1139090D01*
X1377563Y1138673D01*
X1377521Y1138298D01*
X1377605Y1137923D01*
X1377730Y1137673D01*
X1377980Y1137423D01*
X1378271Y1137256D01*
X1378563Y1137173D01*
X1378855D01*
X1379146Y1137256D01*
X1379396Y1137381D01*
X1379605Y1137548D01*
G01X1381663Y1137173D02*
Y1139673D01*
X1381163Y1139173D01*
G01Y1137173D02*
X1382163D01*
G01X1383846Y1137673D02*
X1384096Y1137381D01*
X1384430Y1137215D01*
X1384805Y1137173D01*
X1385138Y1137215D01*
X1385471Y1137423D01*
X1385680Y1137673D01*
X1385721Y1137923D01*
X1385638Y1138215D01*
X1385346Y1138423D01*
X1385055Y1138506D01*
X1384680D01*
G01X1385055D02*
X1385305Y1138631D01*
X1385513Y1138840D01*
X1385596Y1139090D01*
X1385513Y1139340D01*
X1385305Y1139548D01*
X1384930Y1139673D01*
X1384555Y1139631D01*
X1384180Y1139465D01*
G01X1387071Y1138215D02*
X1387363Y1138506D01*
X1387613Y1138673D01*
X1387946Y1138756D01*
X1388238Y1138673D01*
X1388446Y1138506D01*
X1388613Y1138256D01*
X1388655Y1137965D01*
X1388613Y1137715D01*
X1388446Y1137465D01*
X1388196Y1137256D01*
X1387905Y1137173D01*
X1387571Y1137256D01*
X1387280Y1137506D01*
X1387113Y1137881D01*
X1387071Y1138298D01*
X1387155Y1138840D01*
X1387280Y1139131D01*
X1387488Y1139423D01*
X1387780Y1139631D01*
X1388071Y1139673D01*
X1388363Y1139590D01*
X1388571Y1139381D01*
G01X1360561Y1271565D02*
Y1282765D01*
X1369361D01*
Y1271565D01*
X1360561D01*
G01X1355878Y1285665D02*
Y1288165D01*
X1356919D01*
X1357253Y1288040D01*
X1357461Y1287873D01*
X1357544Y1287540D01*
X1357461Y1287207D01*
X1357211Y1286998D01*
X1356919Y1286873D01*
X1355878D01*
G01X1356919D02*
X1357544Y1285665D01*
G01X1358978Y1288165D02*
Y1285665D01*
X1360644D01*
G01X1363744D02*
X1362078D01*
Y1288165D01*
X1363744D01*
G01X1363078Y1286957D02*
X1362078D01*
G01X1365094Y1285665D02*
Y1288165D01*
X1365928D01*
X1366261Y1288040D01*
X1366511Y1287873D01*
X1366719Y1287623D01*
X1366886Y1287332D01*
X1366928Y1286915D01*
X1366886Y1286498D01*
X1366719Y1286207D01*
X1366511Y1285957D01*
X1366261Y1285790D01*
X1365928Y1285665D01*
X1365094D01*
G01X1368194Y1286165D02*
X1368444Y1285873D01*
X1368778Y1285707D01*
X1369153Y1285665D01*
X1369486Y1285707D01*
X1369819Y1285915D01*
X1370028Y1286165D01*
X1370069Y1286415D01*
X1369986Y1286707D01*
X1369694Y1286915D01*
X1369403Y1286998D01*
X1369028D01*
G01X1369403D02*
X1369653Y1287123D01*
X1369861Y1287332D01*
X1369944Y1287582D01*
X1369861Y1287832D01*
X1369653Y1288040D01*
X1369278Y1288165D01*
X1368903Y1288123D01*
X1368528Y1287957D01*
G01X1371419Y1287748D02*
X1371669Y1287998D01*
X1371961Y1288123D01*
X1372294Y1288165D01*
X1372711Y1288082D01*
X1373003Y1287873D01*
X1373086Y1287623D01*
X1373044Y1287373D01*
X1372878Y1287165D01*
X1372044Y1286748D01*
X1371669Y1286457D01*
X1371419Y1286040D01*
X1371336Y1285665D01*
X1373086D01*
G01X1389006Y221492D02*
X1394056D01*
Y320192D01*
X1418706D01*
Y135792D01*
X1394056D01*
Y194492D01*
X1389006D01*
Y221492D01*
G01X1423500Y174350D02*
X1423458Y174017D01*
X1423292Y173725D01*
X1423042Y173475D01*
X1422750Y173308D01*
X1422417Y173225D01*
X1422083D01*
X1421750Y173308D01*
X1421458Y173475D01*
X1421208Y173725D01*
X1421042Y174017D01*
X1421000Y174350D01*
X1421042Y174683D01*
X1421208Y174975D01*
X1421458Y175225D01*
X1421750Y175392D01*
X1422083Y175475D01*
X1422417D01*
X1422750Y175392D01*
X1423042Y175225D01*
X1423292Y174975D01*
X1423458Y174683D01*
X1423500Y174350D01*
G01X1422833Y174683D02*
X1423500Y175183D01*
G01Y177450D02*
X1421000D01*
X1421500Y176950D01*
G01X1423500D02*
Y177950D01*
G01Y180550D02*
X1423458Y180842D01*
X1423333Y181175D01*
X1423125Y181383D01*
X1422833Y181467D01*
X1422542Y181383D01*
X1422292Y181133D01*
X1422167Y180758D01*
Y180342D01*
X1422083Y180092D01*
X1421875Y179883D01*
X1421583Y179800D01*
X1421292Y179925D01*
X1421083Y180217D01*
X1421000Y180550D01*
X1421083Y180883D01*
X1421292Y181175D01*
X1421583Y181300D01*
X1421875Y181217D01*
X1422083Y181008D01*
X1422167Y180758D01*
Y180342D01*
X1422292Y179967D01*
X1422542Y179717D01*
X1422833Y179633D01*
X1423125Y179717D01*
X1423333Y179925D01*
X1423458Y180258D01*
X1423500Y180550D01*
G01Y183567D02*
X1422958Y183650D01*
X1422500Y183775D01*
X1422083Y183942D01*
X1421625Y184150D01*
X1421000Y184483D01*
Y182817D01*
G01X1425013Y183861D02*
Y172461D01*
G01X1438413Y183861D02*
X1425013D01*
G01Y172461D02*
X1438413D01*
G01X1386409Y242829D02*
Y246829D01*
X1379009D01*
G01X1424517Y232500D02*
Y235000D01*
X1425558D01*
X1425892Y234875D01*
X1426100Y234708D01*
X1426183Y234375D01*
X1426100Y234042D01*
X1425850Y233833D01*
X1425558Y233708D01*
X1424517D01*
G01X1425558D02*
X1426183Y232500D01*
G01X1428450D02*
X1428742Y232542D01*
X1429075Y232667D01*
X1429283Y232875D01*
X1429367Y233167D01*
X1429283Y233458D01*
X1429033Y233708D01*
X1428658Y233833D01*
X1428242D01*
X1427992Y233917D01*
X1427783Y234125D01*
X1427700Y234417D01*
X1427825Y234708D01*
X1428117Y234917D01*
X1428450Y235000D01*
X1428783Y234917D01*
X1429075Y234708D01*
X1429200Y234417D01*
X1429117Y234125D01*
X1428908Y233917D01*
X1428658Y233833D01*
X1428242D01*
X1427867Y233708D01*
X1427617Y233458D01*
X1427533Y233167D01*
X1427617Y232875D01*
X1427825Y232667D01*
X1428158Y232542D01*
X1428450Y232500D01*
G01X1432050D02*
Y235000D01*
X1430508Y233208D01*
X1432592D01*
G01X1433858Y234583D02*
X1434108Y234833D01*
X1434400Y234958D01*
X1434733Y235000D01*
X1435150Y234917D01*
X1435442Y234708D01*
X1435525Y234458D01*
X1435483Y234208D01*
X1435317Y234000D01*
X1434483Y233583D01*
X1434108Y233292D01*
X1433858Y232875D01*
X1433775Y232500D01*
X1435525D01*
G01X1438013Y244661D02*
Y236661D01*
X1420413D01*
Y244661D01*
X1438013D01*
G01X1425208Y248267D02*
X1425083Y248017D01*
X1425000Y247725D01*
Y247392D01*
X1425125Y247017D01*
X1425333Y246725D01*
X1425583Y246517D01*
X1426000Y246350D01*
X1426375Y246308D01*
X1426750Y246392D01*
X1427000Y246517D01*
X1427250Y246767D01*
X1427417Y247058D01*
X1427500Y247350D01*
Y247642D01*
X1427417Y247933D01*
X1427292Y248183D01*
X1427125Y248392D01*
G01X1427500Y250950D02*
X1425000D01*
X1426792Y249408D01*
Y251492D01*
G01X1427500Y254050D02*
X1425000D01*
X1426792Y252508D01*
Y254592D01*
G01X1427500Y257150D02*
X1425000D01*
X1426792Y255608D01*
Y257692D01*
G01X1421208Y271267D02*
X1421083Y271017D01*
X1421000Y270725D01*
Y270392D01*
X1421125Y270017D01*
X1421333Y269725D01*
X1421583Y269517D01*
X1422000Y269350D01*
X1422375Y269308D01*
X1422750Y269392D01*
X1423000Y269517D01*
X1423250Y269767D01*
X1423417Y270058D01*
X1423500Y270350D01*
Y270642D01*
X1423417Y270933D01*
X1423292Y271183D01*
X1423125Y271392D01*
G01X1423500Y273950D02*
X1421000D01*
X1422792Y272408D01*
Y274492D01*
G01X1423500Y277050D02*
X1421000D01*
X1422792Y275508D01*
Y277592D01*
G01X1423000Y278733D02*
X1423292Y278983D01*
X1423458Y279317D01*
X1423500Y279692D01*
X1423458Y280025D01*
X1423250Y280358D01*
X1423000Y280567D01*
X1422750Y280608D01*
X1422458Y280525D01*
X1422250Y280233D01*
X1422167Y279942D01*
Y279567D01*
G01Y279942D02*
X1422042Y280192D01*
X1421833Y280400D01*
X1421583Y280483D01*
X1421333Y280400D01*
X1421125Y280192D01*
X1421000Y279817D01*
X1421042Y279442D01*
X1421208Y279067D01*
G01X1394181Y329492D02*
Y331992D01*
G01X1395931D02*
Y329492D01*
G01Y330742D02*
X1394181D01*
G01X1397239Y329492D02*
Y331992D01*
X1398073D01*
X1398406Y331867D01*
X1398656Y331700D01*
X1398864Y331450D01*
X1399031Y331159D01*
X1399073Y330742D01*
X1399031Y330325D01*
X1398864Y330034D01*
X1398656Y329784D01*
X1398406Y329617D01*
X1398073Y329492D01*
X1397239D01*
G01X1400339D02*
Y331992D01*
X1401173D01*
X1401506Y331867D01*
X1401756Y331700D01*
X1401964Y331450D01*
X1402131Y331159D01*
X1402173Y330742D01*
X1402131Y330325D01*
X1401964Y330034D01*
X1401756Y329784D01*
X1401506Y329617D01*
X1401173Y329492D01*
X1400339D01*
G01X1403481Y329825D02*
X1403814Y329617D01*
X1404189Y329492D01*
X1404523D01*
X1404856Y329617D01*
X1405106Y329825D01*
X1405231Y330117D01*
X1405148Y330409D01*
X1404939Y330659D01*
X1404564Y330825D01*
X1404064Y330909D01*
X1403773Y331075D01*
X1403648Y331367D01*
X1403731Y331659D01*
X1403939Y331867D01*
X1404231Y331992D01*
X1404523D01*
X1404814Y331909D01*
X1405064Y331700D01*
G01X1406414Y329492D02*
X1407456Y331992D01*
X1408498Y329492D01*
G01X1408123Y330367D02*
X1406789D01*
G01X1409681Y329825D02*
X1410014Y329617D01*
X1410389Y329492D01*
X1410723D01*
X1411056Y329617D01*
X1411306Y329825D01*
X1411431Y330117D01*
X1411348Y330409D01*
X1411139Y330659D01*
X1410764Y330825D01*
X1410264Y330909D01*
X1409973Y331075D01*
X1409848Y331367D01*
X1409931Y331659D01*
X1410139Y331867D01*
X1410431Y331992D01*
X1410723D01*
X1411014Y331909D01*
X1411264Y331700D01*
G01X1412739Y329992D02*
X1412989Y329700D01*
X1413323Y329534D01*
X1413698Y329492D01*
X1414031Y329534D01*
X1414364Y329742D01*
X1414573Y329992D01*
X1414614Y330242D01*
X1414531Y330534D01*
X1414239Y330742D01*
X1413948Y330825D01*
X1413573D01*
G01X1413948D02*
X1414198Y330950D01*
X1414406Y331159D01*
X1414489Y331409D01*
X1414406Y331659D01*
X1414198Y331867D01*
X1413823Y331992D01*
X1413448Y331950D01*
X1413073Y331784D01*
G01X1416756Y329492D02*
Y331992D01*
X1416256Y331492D01*
G01Y329492D02*
X1417256D01*
G01X1407867Y478767D02*
Y481267D01*
X1408908D01*
X1409242Y481142D01*
X1409450Y480975D01*
X1409533Y480642D01*
X1409450Y480309D01*
X1409200Y480100D01*
X1408908Y479975D01*
X1407867D01*
G01X1408908D02*
X1409533Y478767D01*
G01X1411800D02*
Y481267D01*
X1411300Y480767D01*
G01Y478767D02*
X1412300D01*
G01X1414900Y481267D02*
X1414567Y481184D01*
X1414317Y480975D01*
X1414150Y480725D01*
X1414025Y480392D01*
X1413983Y480017D01*
X1414025Y479642D01*
X1414150Y479309D01*
X1414317Y479059D01*
X1414567Y478850D01*
X1414900Y478767D01*
X1415233Y478850D01*
X1415483Y479059D01*
X1415650Y479309D01*
X1415775Y479642D01*
X1415817Y480017D01*
X1415775Y480392D01*
X1415650Y480725D01*
X1415483Y480975D01*
X1415233Y481184D01*
X1414900Y481267D01*
G01X1417292Y479059D02*
X1417583Y478850D01*
X1417917Y478767D01*
X1418250Y478850D01*
X1418542Y479100D01*
X1418750Y479475D01*
X1418833Y479850D01*
Y480309D01*
X1418750Y480684D01*
X1418542Y481017D01*
X1418292Y481184D01*
X1418000Y481267D01*
X1417667Y481184D01*
X1417417Y481017D01*
X1417250Y480767D01*
X1417167Y480434D01*
X1417250Y480142D01*
X1417458Y479850D01*
X1417708Y479684D01*
X1418000Y479642D01*
X1418333Y479725D01*
X1418583Y479934D01*
X1418833Y480309D01*
G01X1421017Y478767D02*
X1421100Y479309D01*
X1421225Y479767D01*
X1421392Y480184D01*
X1421600Y480642D01*
X1421933Y481267D01*
X1420267D01*
G01X1407867Y497767D02*
Y500267D01*
X1408908D01*
X1409242Y500142D01*
X1409450Y499975D01*
X1409533Y499642D01*
X1409450Y499309D01*
X1409200Y499100D01*
X1408908Y498975D01*
X1407867D01*
G01X1408908D02*
X1409533Y497767D01*
G01X1411800D02*
Y500267D01*
X1411300Y499767D01*
G01Y497767D02*
X1412300D01*
G01X1414900Y500267D02*
X1414567Y500184D01*
X1414317Y499975D01*
X1414150Y499725D01*
X1414025Y499392D01*
X1413983Y499017D01*
X1414025Y498642D01*
X1414150Y498309D01*
X1414317Y498059D01*
X1414567Y497850D01*
X1414900Y497767D01*
X1415233Y497850D01*
X1415483Y498059D01*
X1415650Y498309D01*
X1415775Y498642D01*
X1415817Y499017D01*
X1415775Y499392D01*
X1415650Y499725D01*
X1415483Y499975D01*
X1415233Y500184D01*
X1414900Y500267D01*
G01X1417292Y498059D02*
X1417583Y497850D01*
X1417917Y497767D01*
X1418250Y497850D01*
X1418542Y498100D01*
X1418750Y498475D01*
X1418833Y498850D01*
Y499309D01*
X1418750Y499684D01*
X1418542Y500017D01*
X1418292Y500184D01*
X1418000Y500267D01*
X1417667Y500184D01*
X1417417Y500017D01*
X1417250Y499767D01*
X1417167Y499434D01*
X1417250Y499142D01*
X1417458Y498850D01*
X1417708Y498684D01*
X1418000Y498642D01*
X1418333Y498725D01*
X1418583Y498934D01*
X1418833Y499309D01*
G01X1421100Y497767D02*
X1421392Y497809D01*
X1421725Y497934D01*
X1421933Y498142D01*
X1422017Y498434D01*
X1421933Y498725D01*
X1421683Y498975D01*
X1421308Y499100D01*
X1420892D01*
X1420642Y499184D01*
X1420433Y499392D01*
X1420350Y499684D01*
X1420475Y499975D01*
X1420767Y500184D01*
X1421100Y500267D01*
X1421433Y500184D01*
X1421725Y499975D01*
X1421850Y499684D01*
X1421767Y499392D01*
X1421558Y499184D01*
X1421308Y499100D01*
X1420892D01*
X1420517Y498975D01*
X1420267Y498725D01*
X1420183Y498434D01*
X1420267Y498142D01*
X1420475Y497934D01*
X1420808Y497809D01*
X1421100Y497767D01*
G01X1426134Y479467D02*
X1423634D01*
Y480508D01*
X1423759Y480842D01*
X1423926Y481050D01*
X1424259Y481133D01*
X1424592Y481050D01*
X1424801Y480800D01*
X1424926Y480508D01*
Y479467D01*
G01Y480508D02*
X1426134Y481133D01*
G01Y483400D02*
X1423634D01*
X1424134Y482900D01*
G01X1426134D02*
Y483900D01*
G01X1423634Y486500D02*
X1423717Y486167D01*
X1423926Y485917D01*
X1424176Y485750D01*
X1424509Y485625D01*
X1424884Y485583D01*
X1425259Y485625D01*
X1425592Y485750D01*
X1425842Y485917D01*
X1426051Y486167D01*
X1426134Y486500D01*
X1426051Y486833D01*
X1425842Y487083D01*
X1425592Y487250D01*
X1425259Y487375D01*
X1424884Y487417D01*
X1424509Y487375D01*
X1424176Y487250D01*
X1423926Y487083D01*
X1423717Y486833D01*
X1423634Y486500D01*
G01X1425842Y488892D02*
X1426051Y489183D01*
X1426134Y489517D01*
X1426051Y489850D01*
X1425801Y490142D01*
X1425426Y490350D01*
X1425051Y490433D01*
X1424592D01*
X1424217Y490350D01*
X1423884Y490142D01*
X1423717Y489892D01*
X1423634Y489600D01*
X1423717Y489267D01*
X1423884Y489017D01*
X1424134Y488850D01*
X1424467Y488767D01*
X1424759Y488850D01*
X1425051Y489058D01*
X1425217Y489308D01*
X1425259Y489600D01*
X1425176Y489933D01*
X1424967Y490183D01*
X1424592Y490433D01*
G01X1425842Y491992D02*
X1426051Y492283D01*
X1426134Y492617D01*
X1426051Y492950D01*
X1425801Y493242D01*
X1425426Y493450D01*
X1425051Y493533D01*
X1424592D01*
X1424217Y493450D01*
X1423884Y493242D01*
X1423717Y492992D01*
X1423634Y492700D01*
X1423717Y492367D01*
X1423884Y492117D01*
X1424134Y491950D01*
X1424467Y491867D01*
X1424759Y491950D01*
X1425051Y492158D01*
X1425217Y492408D01*
X1425259Y492700D01*
X1425176Y493033D01*
X1424967Y493283D01*
X1424592Y493533D01*
G01X1426734Y497567D02*
X1424234D01*
Y498608D01*
X1424359Y498942D01*
X1424526Y499150D01*
X1424859Y499233D01*
X1425192Y499150D01*
X1425401Y498900D01*
X1425526Y498608D01*
Y497567D01*
G01Y498608D02*
X1426734Y499233D01*
G01Y501500D02*
X1424234D01*
X1424734Y501000D01*
G01X1426734D02*
Y502000D01*
G01Y504600D02*
X1424234D01*
X1424734Y504100D01*
G01X1426734D02*
Y505100D01*
G01X1424234Y507700D02*
X1424317Y507367D01*
X1424526Y507117D01*
X1424776Y506950D01*
X1425109Y506825D01*
X1425484Y506783D01*
X1425859Y506825D01*
X1426192Y506950D01*
X1426442Y507117D01*
X1426651Y507367D01*
X1426734Y507700D01*
X1426651Y508033D01*
X1426442Y508283D01*
X1426192Y508450D01*
X1425859Y508575D01*
X1425484Y508617D01*
X1425109Y508575D01*
X1424776Y508450D01*
X1424526Y508283D01*
X1424317Y508033D01*
X1424234Y507700D01*
G01Y510800D02*
X1424317Y510467D01*
X1424526Y510217D01*
X1424776Y510050D01*
X1425109Y509925D01*
X1425484Y509883D01*
X1425859Y509925D01*
X1426192Y510050D01*
X1426442Y510217D01*
X1426651Y510467D01*
X1426734Y510800D01*
X1426651Y511133D01*
X1426442Y511383D01*
X1426192Y511550D01*
X1425859Y511675D01*
X1425484Y511717D01*
X1425109Y511675D01*
X1424776Y511550D01*
X1424526Y511383D01*
X1424317Y511133D01*
X1424234Y510800D01*
G01X1412369Y522457D02*
Y518457D01*
X1419769D01*
G01X1412369Y529857D02*
Y525857D01*
X1419769D01*
G01X1423969Y522457D02*
X1419969D01*
Y515057D01*
G01Y525957D02*
X1423969D01*
Y533357D01*
G01X1402617Y519272D02*
X1400117D01*
Y520313D01*
X1400242Y520647D01*
X1400409Y520855D01*
X1400742Y520938D01*
X1401075Y520855D01*
X1401284Y520605D01*
X1401409Y520313D01*
Y519272D01*
G01Y520313D02*
X1402617Y520938D01*
G01Y523205D02*
X1400117D01*
X1400617Y522705D01*
G01X1402617D02*
Y523705D01*
G01Y526305D02*
X1400117D01*
X1400617Y525805D01*
G01X1402617D02*
Y526805D01*
G01X1400117Y529405D02*
X1400200Y529072D01*
X1400409Y528822D01*
X1400659Y528655D01*
X1400992Y528530D01*
X1401367Y528488D01*
X1401742Y528530D01*
X1402075Y528655D01*
X1402325Y528822D01*
X1402534Y529072D01*
X1402617Y529405D01*
X1402534Y529738D01*
X1402325Y529988D01*
X1402075Y530155D01*
X1401742Y530280D01*
X1401367Y530322D01*
X1400992Y530280D01*
X1400659Y530155D01*
X1400409Y529988D01*
X1400200Y529738D01*
X1400117Y529405D01*
G01X1402617Y532505D02*
X1400117D01*
X1400617Y532005D01*
G01X1402617D02*
Y533005D01*
G01X1398757Y539431D02*
Y544631D01*
G01X1405757Y539431D02*
Y547231D01*
G01X1398757Y539431D02*
X1405757D01*
G01X1398757Y552831D02*
Y544131D01*
G01X1405757Y546431D02*
Y552831D01*
G01X1420000Y551600D02*
Y547600D01*
X1427400D01*
G01X1409082Y538594D02*
Y541094D01*
X1410123D01*
X1410457Y540969D01*
X1410665Y540802D01*
X1410748Y540469D01*
X1410665Y540136D01*
X1410415Y539927D01*
X1410123Y539802D01*
X1409082D01*
G01X1410123D02*
X1410748Y538594D01*
G01X1413015D02*
Y541094D01*
X1412515Y540594D01*
G01Y538594D02*
X1413515D01*
G01X1416115Y541094D02*
X1415782Y541011D01*
X1415532Y540802D01*
X1415365Y540552D01*
X1415240Y540219D01*
X1415198Y539844D01*
X1415240Y539469D01*
X1415365Y539136D01*
X1415532Y538886D01*
X1415782Y538677D01*
X1416115Y538594D01*
X1416448Y538677D01*
X1416698Y538886D01*
X1416865Y539136D01*
X1416990Y539469D01*
X1417032Y539844D01*
X1416990Y540219D01*
X1416865Y540552D01*
X1416698Y540802D01*
X1416448Y541011D01*
X1416115Y541094D01*
G01X1419132Y538594D02*
X1419215Y539136D01*
X1419340Y539594D01*
X1419507Y540011D01*
X1419715Y540469D01*
X1420048Y541094D01*
X1418382D01*
G01X1421398Y539094D02*
X1421648Y538802D01*
X1421982Y538636D01*
X1422357Y538594D01*
X1422690Y538636D01*
X1423023Y538844D01*
X1423232Y539094D01*
X1423273Y539344D01*
X1423190Y539636D01*
X1422898Y539844D01*
X1422607Y539927D01*
X1422232D01*
G01X1422607D02*
X1422857Y540052D01*
X1423065Y540261D01*
X1423148Y540511D01*
X1423065Y540761D01*
X1422857Y540969D01*
X1422482Y541094D01*
X1422107Y541052D01*
X1421732Y540886D01*
G01X1410832Y544586D02*
X1410582Y544711D01*
X1410290Y544794D01*
X1409957D01*
X1409582Y544669D01*
X1409290Y544461D01*
X1409082Y544211D01*
X1408915Y543794D01*
X1408873Y543419D01*
X1408957Y543044D01*
X1409082Y542794D01*
X1409332Y542544D01*
X1409623Y542377D01*
X1409915Y542294D01*
X1410207D01*
X1410498Y542377D01*
X1410748Y542502D01*
X1410957Y542669D01*
G01X1412098D02*
X1412348Y542461D01*
X1412640Y542336D01*
X1413015Y542294D01*
X1413390Y542377D01*
X1413682Y542544D01*
X1413890Y542836D01*
X1413932Y543169D01*
X1413848Y543502D01*
X1413640Y543711D01*
X1413348Y543877D01*
X1413057Y543919D01*
X1412765Y543877D01*
X1412390Y543711D01*
X1412515Y544794D01*
X1413640D01*
G01X1415198Y542669D02*
X1415448Y542461D01*
X1415740Y542336D01*
X1416115Y542294D01*
X1416490Y542377D01*
X1416782Y542544D01*
X1416990Y542836D01*
X1417032Y543169D01*
X1416948Y543502D01*
X1416740Y543711D01*
X1416448Y543877D01*
X1416157Y543919D01*
X1415865Y543877D01*
X1415490Y543711D01*
X1415615Y544794D01*
X1416740D01*
G01X1419132Y542294D02*
X1419215Y542836D01*
X1419340Y543294D01*
X1419507Y543711D01*
X1419715Y544169D01*
X1420048Y544794D01*
X1418382D01*
G01X1389006Y674248D02*
X1394056D01*
Y772948D01*
X1418706D01*
Y588548D01*
X1394056D01*
Y647248D01*
X1389006D01*
Y674248D01*
G01X1405757Y552831D02*
X1398757D01*
G01X1397546Y581735D02*
Y584235D01*
X1398587D01*
X1398921Y584110D01*
X1399129Y583943D01*
X1399212Y583610D01*
X1399129Y583277D01*
X1398879Y583068D01*
X1398587Y582943D01*
X1397546D01*
G01X1398587D02*
X1399212Y581735D01*
G01X1401479D02*
Y584235D01*
X1400979Y583735D01*
G01Y581735D02*
X1401979D01*
G01X1404579Y584235D02*
X1404246Y584152D01*
X1403996Y583943D01*
X1403829Y583693D01*
X1403704Y583360D01*
X1403662Y582985D01*
X1403704Y582610D01*
X1403829Y582277D01*
X1403996Y582027D01*
X1404246Y581818D01*
X1404579Y581735D01*
X1404912Y581818D01*
X1405162Y582027D01*
X1405329Y582277D01*
X1405454Y582610D01*
X1405496Y582985D01*
X1405454Y583360D01*
X1405329Y583693D01*
X1405162Y583943D01*
X1404912Y584152D01*
X1404579Y584235D01*
G01X1406971Y582027D02*
X1407262Y581818D01*
X1407596Y581735D01*
X1407929Y581818D01*
X1408221Y582068D01*
X1408429Y582443D01*
X1408512Y582818D01*
Y583277D01*
X1408429Y583652D01*
X1408221Y583985D01*
X1407971Y584152D01*
X1407679Y584235D01*
X1407346Y584152D01*
X1407096Y583985D01*
X1406929Y583735D01*
X1406846Y583402D01*
X1406929Y583110D01*
X1407137Y582818D01*
X1407387Y582652D01*
X1407679Y582610D01*
X1408012Y582693D01*
X1408262Y582902D01*
X1408512Y583277D01*
G01X1409987Y582777D02*
X1410279Y583068D01*
X1410529Y583235D01*
X1410862Y583318D01*
X1411154Y583235D01*
X1411362Y583068D01*
X1411529Y582818D01*
X1411571Y582527D01*
X1411529Y582277D01*
X1411362Y582027D01*
X1411112Y581818D01*
X1410821Y581735D01*
X1410487Y581818D01*
X1410196Y582068D01*
X1410029Y582443D01*
X1409987Y582860D01*
X1410071Y583402D01*
X1410196Y583693D01*
X1410404Y583985D01*
X1410696Y584193D01*
X1410987Y584235D01*
X1411279Y584152D01*
X1411487Y583943D01*
G01X1379450Y570100D02*
Y583100D01*
X1394950D01*
Y570100D01*
X1379450D01*
G01X1417350Y579500D02*
X1417017Y579542D01*
X1416725Y579708D01*
X1416475Y579958D01*
X1416308Y580250D01*
X1416225Y580583D01*
Y580917D01*
X1416308Y581250D01*
X1416475Y581542D01*
X1416725Y581792D01*
X1417017Y581958D01*
X1417350Y582000D01*
X1417683Y581958D01*
X1417975Y581792D01*
X1418225Y581542D01*
X1418392Y581250D01*
X1418475Y580917D01*
Y580583D01*
X1418392Y580250D01*
X1418225Y579958D01*
X1417975Y579708D01*
X1417683Y579542D01*
X1417350Y579500D01*
G01X1417683Y580167D02*
X1418183Y579500D01*
G01X1419658Y581583D02*
X1419908Y581833D01*
X1420200Y581958D01*
X1420533Y582000D01*
X1420950Y581917D01*
X1421242Y581708D01*
X1421325Y581458D01*
X1421283Y581208D01*
X1421117Y581000D01*
X1420283Y580583D01*
X1419908Y580292D01*
X1419658Y579875D01*
X1419575Y579500D01*
X1421325D01*
G01X1422758Y581583D02*
X1423008Y581833D01*
X1423300Y581958D01*
X1423633Y582000D01*
X1424050Y581917D01*
X1424342Y581708D01*
X1424425Y581458D01*
X1424383Y581208D01*
X1424217Y581000D01*
X1423383Y580583D01*
X1423008Y580292D01*
X1422758Y579875D01*
X1422675Y579500D01*
X1424425D01*
G01X1426650D02*
Y582000D01*
X1426150Y581500D01*
G01Y579500D02*
X1427150D01*
G01X1430200Y578100D02*
X1416200D01*
G01Y565100D02*
X1430200D01*
G01X1416200Y578100D02*
Y565100D01*
G01X1398374Y560309D02*
Y562809D01*
X1399415D01*
X1399749Y562684D01*
X1399957Y562517D01*
X1400040Y562184D01*
X1399957Y561851D01*
X1399707Y561642D01*
X1399415Y561517D01*
X1398374D01*
G01X1399415D02*
X1400040Y560309D01*
G01X1402307D02*
Y562809D01*
X1401807Y562309D01*
G01Y560309D02*
X1402807D01*
G01X1405407D02*
Y562809D01*
X1404907Y562309D01*
G01Y560309D02*
X1405907D01*
G01X1408507Y562809D02*
X1408174Y562726D01*
X1407924Y562517D01*
X1407757Y562267D01*
X1407632Y561934D01*
X1407590Y561559D01*
X1407632Y561184D01*
X1407757Y560851D01*
X1407924Y560601D01*
X1408174Y560392D01*
X1408507Y560309D01*
X1408840Y560392D01*
X1409090Y560601D01*
X1409257Y560851D01*
X1409382Y561184D01*
X1409424Y561559D01*
X1409382Y561934D01*
X1409257Y562267D01*
X1409090Y562517D01*
X1408840Y562726D01*
X1408507Y562809D01*
G01X1410815Y561351D02*
X1411107Y561642D01*
X1411357Y561809D01*
X1411690Y561892D01*
X1411982Y561809D01*
X1412190Y561642D01*
X1412357Y561392D01*
X1412399Y561101D01*
X1412357Y560851D01*
X1412190Y560601D01*
X1411940Y560392D01*
X1411649Y560309D01*
X1411315Y560392D01*
X1411024Y560642D01*
X1410857Y561017D01*
X1410815Y561434D01*
X1410899Y561976D01*
X1411024Y562267D01*
X1411232Y562559D01*
X1411524Y562767D01*
X1411815Y562809D01*
X1412107Y562726D01*
X1412315Y562517D01*
G01X1420000Y555600D02*
Y551600D01*
X1427400D01*
G01X1398374Y556309D02*
Y558809D01*
X1399415D01*
X1399749Y558684D01*
X1399957Y558517D01*
X1400040Y558184D01*
X1399957Y557851D01*
X1399707Y557642D01*
X1399415Y557517D01*
X1398374D01*
G01X1399415D02*
X1400040Y556309D01*
G01X1402307D02*
Y558809D01*
X1401807Y558309D01*
G01Y556309D02*
X1402807D01*
G01X1405407D02*
Y558809D01*
X1404907Y558309D01*
G01Y556309D02*
X1405907D01*
G01X1408507Y558809D02*
X1408174Y558726D01*
X1407924Y558517D01*
X1407757Y558267D01*
X1407632Y557934D01*
X1407590Y557559D01*
X1407632Y557184D01*
X1407757Y556851D01*
X1407924Y556601D01*
X1408174Y556392D01*
X1408507Y556309D01*
X1408840Y556392D01*
X1409090Y556601D01*
X1409257Y556851D01*
X1409382Y557184D01*
X1409424Y557559D01*
X1409382Y557934D01*
X1409257Y558267D01*
X1409090Y558517D01*
X1408840Y558726D01*
X1408507Y558809D01*
G01X1410690Y556684D02*
X1410940Y556476D01*
X1411232Y556351D01*
X1411607Y556309D01*
X1411982Y556392D01*
X1412274Y556559D01*
X1412482Y556851D01*
X1412524Y557184D01*
X1412440Y557517D01*
X1412232Y557726D01*
X1411940Y557892D01*
X1411649Y557934D01*
X1411357Y557892D01*
X1410982Y557726D01*
X1411107Y558809D01*
X1412232D01*
G01X1409200Y565467D02*
X1406700D01*
Y566508D01*
X1406825Y566842D01*
X1406992Y567050D01*
X1407325Y567133D01*
X1407658Y567050D01*
X1407867Y566800D01*
X1407992Y566508D01*
Y565467D01*
G01Y566508D02*
X1409200Y567133D01*
G01Y569400D02*
X1406700D01*
X1407200Y568900D01*
G01X1409200D02*
Y569900D01*
G01X1406700Y572500D02*
X1406783Y572167D01*
X1406992Y571917D01*
X1407242Y571750D01*
X1407575Y571625D01*
X1407950Y571583D01*
X1408325Y571625D01*
X1408658Y571750D01*
X1408908Y571917D01*
X1409117Y572167D01*
X1409200Y572500D01*
X1409117Y572833D01*
X1408908Y573083D01*
X1408658Y573250D01*
X1408325Y573375D01*
X1407950Y573417D01*
X1407575Y573375D01*
X1407242Y573250D01*
X1406992Y573083D01*
X1406783Y572833D01*
X1406700Y572500D01*
G01X1409200Y575517D02*
X1408658Y575600D01*
X1408200Y575725D01*
X1407783Y575892D01*
X1407325Y576100D01*
X1406700Y576433D01*
Y574767D01*
G01X1407117Y577908D02*
X1406867Y578158D01*
X1406742Y578450D01*
X1406700Y578783D01*
X1406783Y579200D01*
X1406992Y579492D01*
X1407242Y579575D01*
X1407492Y579533D01*
X1407700Y579367D01*
X1408117Y578533D01*
X1408408Y578158D01*
X1408825Y577908D01*
X1409200Y577825D01*
Y579575D01*
G01X1415400Y573300D02*
X1411400D01*
Y565900D01*
G01X1426767Y558958D02*
X1426517Y559083D01*
X1426225Y559166D01*
X1425892D01*
X1425517Y559041D01*
X1425225Y558833D01*
X1425017Y558583D01*
X1424850Y558166D01*
X1424808Y557791D01*
X1424892Y557416D01*
X1425017Y557166D01*
X1425267Y556916D01*
X1425558Y556749D01*
X1425850Y556666D01*
X1426142D01*
X1426433Y556749D01*
X1426683Y556874D01*
X1426892Y557041D01*
G01X1428033D02*
X1428283Y556833D01*
X1428575Y556708D01*
X1428950Y556666D01*
X1429325Y556749D01*
X1429617Y556916D01*
X1429825Y557208D01*
X1429867Y557541D01*
X1429783Y557874D01*
X1429575Y558083D01*
X1429283Y558249D01*
X1428992Y558291D01*
X1428700Y558249D01*
X1428325Y558083D01*
X1428450Y559166D01*
X1429575D01*
G01X1431967Y556666D02*
X1432050Y557208D01*
X1432175Y557666D01*
X1432342Y558083D01*
X1432550Y558541D01*
X1432883Y559166D01*
X1431217D01*
G01X1435150D02*
X1434817Y559083D01*
X1434567Y558874D01*
X1434400Y558624D01*
X1434275Y558291D01*
X1434233Y557916D01*
X1434275Y557541D01*
X1434400Y557208D01*
X1434567Y556958D01*
X1434817Y556749D01*
X1435150Y556666D01*
X1435483Y556749D01*
X1435733Y556958D01*
X1435900Y557208D01*
X1436025Y557541D01*
X1436067Y557916D01*
X1436025Y558291D01*
X1435900Y558624D01*
X1435733Y558874D01*
X1435483Y559083D01*
X1435150Y559166D01*
G01X1424908Y585867D02*
X1424783Y585617D01*
X1424700Y585325D01*
Y584992D01*
X1424825Y584617D01*
X1425033Y584325D01*
X1425283Y584117D01*
X1425700Y583950D01*
X1426075Y583908D01*
X1426450Y583992D01*
X1426700Y584117D01*
X1426950Y584367D01*
X1427117Y584658D01*
X1427200Y584950D01*
Y585242D01*
X1427117Y585533D01*
X1426992Y585783D01*
X1426825Y585992D01*
G01Y587133D02*
X1427033Y587383D01*
X1427158Y587675D01*
X1427200Y588050D01*
X1427117Y588425D01*
X1426950Y588717D01*
X1426658Y588925D01*
X1426325Y588967D01*
X1425992Y588883D01*
X1425783Y588675D01*
X1425617Y588383D01*
X1425575Y588092D01*
X1425617Y587800D01*
X1425783Y587425D01*
X1424700Y587550D01*
Y588675D01*
G01X1426825Y590233D02*
X1427033Y590483D01*
X1427158Y590775D01*
X1427200Y591150D01*
X1427117Y591525D01*
X1426950Y591817D01*
X1426658Y592025D01*
X1426325Y592067D01*
X1425992Y591983D01*
X1425783Y591775D01*
X1425617Y591483D01*
X1425575Y591192D01*
X1425617Y590900D01*
X1425783Y590525D01*
X1424700Y590650D01*
Y591775D01*
G01X1426825Y593333D02*
X1427033Y593583D01*
X1427158Y593875D01*
X1427200Y594250D01*
X1427117Y594625D01*
X1426950Y594917D01*
X1426658Y595125D01*
X1426325Y595167D01*
X1425992Y595083D01*
X1425783Y594875D01*
X1425617Y594583D01*
X1425575Y594292D01*
X1425617Y594000D01*
X1425783Y593625D01*
X1424700Y593750D01*
Y594875D01*
G01X1428713Y611934D02*
X1426213D01*
Y612975D01*
X1426338Y613309D01*
X1426505Y613517D01*
X1426838Y613600D01*
X1427171Y613517D01*
X1427380Y613267D01*
X1427505Y612975D01*
Y611934D01*
G01Y612975D02*
X1428713Y613600D01*
G01X1428338Y614950D02*
X1428546Y615200D01*
X1428671Y615492D01*
X1428713Y615867D01*
X1428630Y616242D01*
X1428463Y616534D01*
X1428171Y616742D01*
X1427838Y616784D01*
X1427505Y616700D01*
X1427296Y616492D01*
X1427130Y616200D01*
X1427088Y615909D01*
X1427130Y615617D01*
X1427296Y615242D01*
X1426213Y615367D01*
Y616492D01*
G01X1428713Y618884D02*
X1428171Y618967D01*
X1427713Y619092D01*
X1427296Y619259D01*
X1426838Y619467D01*
X1426213Y619800D01*
Y618134D01*
G01X1428338Y621150D02*
X1428546Y621400D01*
X1428671Y621692D01*
X1428713Y622067D01*
X1428630Y622442D01*
X1428463Y622734D01*
X1428171Y622942D01*
X1427838Y622984D01*
X1427505Y622900D01*
X1427296Y622692D01*
X1427130Y622400D01*
X1427088Y622109D01*
X1427130Y621817D01*
X1427296Y621442D01*
X1426213Y621567D01*
Y622692D01*
G01X1424213Y611934D02*
X1421713D01*
Y612975D01*
X1421838Y613309D01*
X1422005Y613517D01*
X1422338Y613600D01*
X1422671Y613517D01*
X1422880Y613267D01*
X1423005Y612975D01*
Y611934D01*
G01Y612975D02*
X1424213Y613600D01*
G01X1423838Y614950D02*
X1424046Y615200D01*
X1424171Y615492D01*
X1424213Y615867D01*
X1424130Y616242D01*
X1423963Y616534D01*
X1423671Y616742D01*
X1423338Y616784D01*
X1423005Y616700D01*
X1422796Y616492D01*
X1422630Y616200D01*
X1422588Y615909D01*
X1422630Y615617D01*
X1422796Y615242D01*
X1421713Y615367D01*
Y616492D01*
G01X1424213Y618884D02*
X1423671Y618967D01*
X1423213Y619092D01*
X1422796Y619259D01*
X1422338Y619467D01*
X1421713Y619800D01*
Y618134D01*
G01X1423921Y621359D02*
X1424130Y621650D01*
X1424213Y621984D01*
X1424130Y622317D01*
X1423880Y622609D01*
X1423505Y622817D01*
X1423130Y622900D01*
X1422671D01*
X1422296Y622817D01*
X1421963Y622609D01*
X1421796Y622359D01*
X1421713Y622067D01*
X1421796Y621734D01*
X1421963Y621484D01*
X1422213Y621317D01*
X1422546Y621234D01*
X1422838Y621317D01*
X1423130Y621525D01*
X1423296Y621775D01*
X1423338Y622067D01*
X1423255Y622400D01*
X1423046Y622650D01*
X1422671Y622900D01*
G01X1423333Y625850D02*
X1423291Y625517D01*
X1423125Y625225D01*
X1422875Y624975D01*
X1422583Y624808D01*
X1422250Y624725D01*
X1421916D01*
X1421583Y624808D01*
X1421291Y624975D01*
X1421041Y625225D01*
X1420875Y625517D01*
X1420833Y625850D01*
X1420875Y626183D01*
X1421041Y626475D01*
X1421291Y626725D01*
X1421583Y626892D01*
X1421916Y626975D01*
X1422250D01*
X1422583Y626892D01*
X1422875Y626725D01*
X1423125Y626475D01*
X1423291Y626183D01*
X1423333Y625850D01*
G01X1422666Y626183D02*
X1423333Y626683D01*
G01Y628950D02*
X1420833D01*
X1421333Y628450D01*
G01X1423333D02*
Y629450D01*
G01Y632050D02*
X1420833D01*
X1421333Y631550D01*
G01X1423333D02*
Y632550D01*
G01X1422958Y634233D02*
X1423166Y634483D01*
X1423291Y634775D01*
X1423333Y635150D01*
X1423250Y635525D01*
X1423083Y635817D01*
X1422791Y636025D01*
X1422458Y636067D01*
X1422125Y635983D01*
X1421916Y635775D01*
X1421750Y635483D01*
X1421708Y635192D01*
X1421750Y634900D01*
X1421916Y634525D01*
X1420833Y634650D01*
Y635775D01*
G01X1425013Y636617D02*
Y625217D01*
G01X1438413Y636617D02*
X1425013D01*
G01Y625217D02*
X1438413D01*
G01X1423517Y684500D02*
Y687000D01*
X1424558D01*
X1424892Y686875D01*
X1425100Y686708D01*
X1425183Y686375D01*
X1425100Y686042D01*
X1424850Y685833D01*
X1424558Y685708D01*
X1423517D01*
G01X1424558D02*
X1425183Y684500D01*
G01X1426533Y684875D02*
X1426783Y684667D01*
X1427075Y684542D01*
X1427450Y684500D01*
X1427825Y684583D01*
X1428117Y684750D01*
X1428325Y685042D01*
X1428367Y685375D01*
X1428283Y685708D01*
X1428075Y685917D01*
X1427783Y686083D01*
X1427492Y686125D01*
X1427200Y686083D01*
X1426825Y685917D01*
X1426950Y687000D01*
X1428075D01*
G01X1429758Y685542D02*
X1430050Y685833D01*
X1430300Y686000D01*
X1430633Y686083D01*
X1430925Y686000D01*
X1431133Y685833D01*
X1431300Y685583D01*
X1431342Y685292D01*
X1431300Y685042D01*
X1431133Y684792D01*
X1430883Y684583D01*
X1430592Y684500D01*
X1430258Y684583D01*
X1429967Y684833D01*
X1429800Y685208D01*
X1429758Y685625D01*
X1429842Y686167D01*
X1429967Y686458D01*
X1430175Y686750D01*
X1430467Y686958D01*
X1430758Y687000D01*
X1431050Y686917D01*
X1431258Y686708D01*
G01X1432858Y685542D02*
X1433150Y685833D01*
X1433400Y686000D01*
X1433733Y686083D01*
X1434025Y686000D01*
X1434233Y685833D01*
X1434400Y685583D01*
X1434442Y685292D01*
X1434400Y685042D01*
X1434233Y684792D01*
X1433983Y684583D01*
X1433692Y684500D01*
X1433358Y684583D01*
X1433067Y684833D01*
X1432900Y685208D01*
X1432858Y685625D01*
X1432942Y686167D01*
X1433067Y686458D01*
X1433275Y686750D01*
X1433567Y686958D01*
X1433858Y687000D01*
X1434150Y686917D01*
X1434358Y686708D01*
G01X1438013Y697417D02*
Y689417D01*
X1420413D01*
Y697417D01*
X1438013D01*
G01X1424708Y700767D02*
X1424583Y700517D01*
X1424500Y700225D01*
Y699892D01*
X1424625Y699517D01*
X1424833Y699225D01*
X1425083Y699017D01*
X1425500Y698850D01*
X1425875Y698808D01*
X1426250Y698892D01*
X1426500Y699017D01*
X1426750Y699267D01*
X1426917Y699558D01*
X1427000Y699850D01*
Y700142D01*
X1426917Y700433D01*
X1426792Y700683D01*
X1426625Y700892D01*
G01X1424917Y702158D02*
X1424667Y702408D01*
X1424542Y702700D01*
X1424500Y703033D01*
X1424583Y703450D01*
X1424792Y703742D01*
X1425042Y703825D01*
X1425292Y703783D01*
X1425500Y703617D01*
X1425917Y702783D01*
X1426208Y702408D01*
X1426625Y702158D01*
X1427000Y702075D01*
Y703825D01*
G01Y706050D02*
X1426958Y706342D01*
X1426833Y706675D01*
X1426625Y706883D01*
X1426333Y706967D01*
X1426042Y706883D01*
X1425792Y706633D01*
X1425667Y706258D01*
Y705842D01*
X1425583Y705592D01*
X1425375Y705383D01*
X1425083Y705300D01*
X1424792Y705425D01*
X1424583Y705717D01*
X1424500Y706050D01*
X1424583Y706383D01*
X1424792Y706675D01*
X1425083Y706800D01*
X1425375Y706717D01*
X1425583Y706508D01*
X1425667Y706258D01*
Y705842D01*
X1425792Y705467D01*
X1426042Y705217D01*
X1426333Y705133D01*
X1426625Y705217D01*
X1426833Y705425D01*
X1426958Y705758D01*
X1427000Y706050D01*
G01Y709150D02*
X1426958Y709442D01*
X1426833Y709775D01*
X1426625Y709983D01*
X1426333Y710067D01*
X1426042Y709983D01*
X1425792Y709733D01*
X1425667Y709358D01*
Y708942D01*
X1425583Y708692D01*
X1425375Y708483D01*
X1425083Y708400D01*
X1424792Y708525D01*
X1424583Y708817D01*
X1424500Y709150D01*
X1424583Y709483D01*
X1424792Y709775D01*
X1425083Y709900D01*
X1425375Y709817D01*
X1425583Y709608D01*
X1425667Y709358D01*
Y708942D01*
X1425792Y708567D01*
X1426042Y708317D01*
X1426333Y708233D01*
X1426625Y708317D01*
X1426833Y708525D01*
X1426958Y708858D01*
X1427000Y709150D01*
G01X1421208Y723767D02*
X1421083Y723517D01*
X1421000Y723225D01*
Y722892D01*
X1421125Y722517D01*
X1421333Y722225D01*
X1421583Y722017D01*
X1422000Y721850D01*
X1422375Y721808D01*
X1422750Y721892D01*
X1423000Y722017D01*
X1423250Y722267D01*
X1423417Y722558D01*
X1423500Y722850D01*
Y723142D01*
X1423417Y723433D01*
X1423292Y723683D01*
X1423125Y723892D01*
G01X1421417Y725158D02*
X1421167Y725408D01*
X1421042Y725700D01*
X1421000Y726033D01*
X1421083Y726450D01*
X1421292Y726742D01*
X1421542Y726825D01*
X1421792Y726783D01*
X1422000Y726617D01*
X1422417Y725783D01*
X1422708Y725408D01*
X1423125Y725158D01*
X1423500Y725075D01*
Y726825D01*
G01Y729050D02*
X1423458Y729342D01*
X1423333Y729675D01*
X1423125Y729883D01*
X1422833Y729967D01*
X1422542Y729883D01*
X1422292Y729633D01*
X1422167Y729258D01*
Y728842D01*
X1422083Y728592D01*
X1421875Y728383D01*
X1421583Y728300D01*
X1421292Y728425D01*
X1421083Y728717D01*
X1421000Y729050D01*
X1421083Y729383D01*
X1421292Y729675D01*
X1421583Y729800D01*
X1421875Y729717D01*
X1422083Y729508D01*
X1422167Y729258D01*
Y728842D01*
X1422292Y728467D01*
X1422542Y728217D01*
X1422833Y728133D01*
X1423125Y728217D01*
X1423333Y728425D01*
X1423458Y728758D01*
X1423500Y729050D01*
G01Y732067D02*
X1422958Y732150D01*
X1422500Y732275D01*
X1422083Y732442D01*
X1421625Y732650D01*
X1421000Y732983D01*
Y731317D01*
G01X1396681Y779748D02*
Y782248D01*
G01X1398431D02*
Y779748D01*
G01Y780998D02*
X1396681D01*
G01X1399739Y779748D02*
Y782248D01*
X1400573D01*
X1400906Y782123D01*
X1401156Y781956D01*
X1401364Y781706D01*
X1401531Y781415D01*
X1401573Y780998D01*
X1401531Y780581D01*
X1401364Y780290D01*
X1401156Y780040D01*
X1400906Y779873D01*
X1400573Y779748D01*
X1399739D01*
G01X1402839D02*
Y782248D01*
X1403673D01*
X1404006Y782123D01*
X1404256Y781956D01*
X1404464Y781706D01*
X1404631Y781415D01*
X1404673Y780998D01*
X1404631Y780581D01*
X1404464Y780290D01*
X1404256Y780040D01*
X1404006Y779873D01*
X1403673Y779748D01*
X1402839D01*
G01X1405981Y780081D02*
X1406314Y779873D01*
X1406689Y779748D01*
X1407023D01*
X1407356Y779873D01*
X1407606Y780081D01*
X1407731Y780373D01*
X1407648Y780665D01*
X1407439Y780915D01*
X1407064Y781081D01*
X1406564Y781165D01*
X1406273Y781331D01*
X1406148Y781623D01*
X1406231Y781915D01*
X1406439Y782123D01*
X1406731Y782248D01*
X1407023D01*
X1407314Y782165D01*
X1407564Y781956D01*
G01X1408914Y779748D02*
X1409956Y782248D01*
X1410998Y779748D01*
G01X1410623Y780623D02*
X1409289D01*
G01X1412181Y780081D02*
X1412514Y779873D01*
X1412889Y779748D01*
X1413223D01*
X1413556Y779873D01*
X1413806Y780081D01*
X1413931Y780373D01*
X1413848Y780665D01*
X1413639Y780915D01*
X1413264Y781081D01*
X1412764Y781165D01*
X1412473Y781331D01*
X1412348Y781623D01*
X1412431Y781915D01*
X1412639Y782123D01*
X1412931Y782248D01*
X1413223D01*
X1413514Y782165D01*
X1413764Y781956D01*
G01X1416156Y779748D02*
Y782248D01*
X1415656Y781748D01*
G01Y779748D02*
X1416656D01*
G01X1418548Y780040D02*
X1418839Y779831D01*
X1419173Y779748D01*
X1419506Y779831D01*
X1419798Y780081D01*
X1420006Y780456D01*
X1420089Y780831D01*
Y781290D01*
X1420006Y781665D01*
X1419798Y781998D01*
X1419548Y782165D01*
X1419256Y782248D01*
X1418923Y782165D01*
X1418673Y781998D01*
X1418506Y781748D01*
X1418423Y781415D01*
X1418506Y781123D01*
X1418714Y780831D01*
X1418964Y780665D01*
X1419256Y780623D01*
X1419589Y780706D01*
X1419839Y780915D01*
X1420089Y781290D01*
G01X1389006Y1127004D02*
X1394056D01*
Y1225704D01*
X1418706D01*
Y1041304D01*
X1394056D01*
Y1100004D01*
X1389006D01*
Y1127004D01*
G01X1423333Y1080400D02*
X1423291Y1080067D01*
X1423125Y1079775D01*
X1422875Y1079525D01*
X1422583Y1079358D01*
X1422250Y1079275D01*
X1421916D01*
X1421583Y1079358D01*
X1421291Y1079525D01*
X1421041Y1079775D01*
X1420875Y1080067D01*
X1420833Y1080400D01*
X1420875Y1080733D01*
X1421041Y1081025D01*
X1421291Y1081275D01*
X1421583Y1081442D01*
X1421916Y1081525D01*
X1422250D01*
X1422583Y1081442D01*
X1422875Y1081275D01*
X1423125Y1081025D01*
X1423291Y1080733D01*
X1423333Y1080400D01*
G01X1422666Y1080733D02*
X1423333Y1081233D01*
G01Y1084000D02*
X1420833D01*
X1422625Y1082458D01*
Y1084542D01*
G01X1422833Y1085683D02*
X1423125Y1085933D01*
X1423291Y1086267D01*
X1423333Y1086642D01*
X1423291Y1086975D01*
X1423083Y1087308D01*
X1422833Y1087517D01*
X1422583Y1087558D01*
X1422291Y1087475D01*
X1422083Y1087183D01*
X1422000Y1086892D01*
Y1086517D01*
G01Y1086892D02*
X1421875Y1087142D01*
X1421666Y1087350D01*
X1421416Y1087433D01*
X1421166Y1087350D01*
X1420958Y1087142D01*
X1420833Y1086767D01*
X1420875Y1086392D01*
X1421041Y1086017D01*
G01X1425013Y1089373D02*
Y1077973D01*
G01D02*
X1438413D01*
G01Y1089373D02*
X1425013D01*
G01X1424017Y1137500D02*
Y1140000D01*
X1425058D01*
X1425392Y1139875D01*
X1425600Y1139708D01*
X1425683Y1139375D01*
X1425600Y1139042D01*
X1425350Y1138833D01*
X1425058Y1138708D01*
X1424017D01*
G01X1425058D02*
X1425683Y1137500D01*
G01X1427158Y1139583D02*
X1427408Y1139833D01*
X1427700Y1139958D01*
X1428033Y1140000D01*
X1428450Y1139917D01*
X1428742Y1139708D01*
X1428825Y1139458D01*
X1428783Y1139208D01*
X1428617Y1139000D01*
X1427783Y1138583D01*
X1427408Y1138292D01*
X1427158Y1137875D01*
X1427075Y1137500D01*
X1428825D01*
G01X1430342Y1137792D02*
X1430633Y1137583D01*
X1430967Y1137500D01*
X1431300Y1137583D01*
X1431592Y1137833D01*
X1431800Y1138208D01*
X1431883Y1138583D01*
Y1139042D01*
X1431800Y1139417D01*
X1431592Y1139750D01*
X1431342Y1139917D01*
X1431050Y1140000D01*
X1430717Y1139917D01*
X1430467Y1139750D01*
X1430300Y1139500D01*
X1430217Y1139167D01*
X1430300Y1138875D01*
X1430508Y1138583D01*
X1430758Y1138417D01*
X1431050Y1138375D01*
X1431383Y1138458D01*
X1431633Y1138667D01*
X1431883Y1139042D01*
G01X1434150Y1140000D02*
X1433817Y1139917D01*
X1433567Y1139708D01*
X1433400Y1139458D01*
X1433275Y1139125D01*
X1433233Y1138750D01*
X1433275Y1138375D01*
X1433400Y1138042D01*
X1433567Y1137792D01*
X1433817Y1137583D01*
X1434150Y1137500D01*
X1434483Y1137583D01*
X1434733Y1137792D01*
X1434900Y1138042D01*
X1435025Y1138375D01*
X1435067Y1138750D01*
X1435025Y1139125D01*
X1434900Y1139458D01*
X1434733Y1139708D01*
X1434483Y1139917D01*
X1434150Y1140000D01*
G01X1438013Y1150173D02*
Y1142173D01*
X1420413D01*
Y1150173D01*
X1438013D01*
G01X1424708Y1153267D02*
X1424583Y1153017D01*
X1424500Y1152725D01*
Y1152392D01*
X1424625Y1152017D01*
X1424833Y1151725D01*
X1425083Y1151517D01*
X1425500Y1151350D01*
X1425875Y1151308D01*
X1426250Y1151392D01*
X1426500Y1151517D01*
X1426750Y1151767D01*
X1426917Y1152058D01*
X1427000Y1152350D01*
Y1152642D01*
X1426917Y1152933D01*
X1426792Y1153183D01*
X1426625Y1153392D01*
G01X1427000Y1155450D02*
X1424500D01*
X1425000Y1154950D01*
G01X1427000D02*
Y1155950D01*
G01X1426500Y1157633D02*
X1426792Y1157883D01*
X1426958Y1158217D01*
X1427000Y1158592D01*
X1426958Y1158925D01*
X1426750Y1159258D01*
X1426500Y1159467D01*
X1426250Y1159508D01*
X1425958Y1159425D01*
X1425750Y1159133D01*
X1425667Y1158842D01*
Y1158467D01*
G01Y1158842D02*
X1425542Y1159092D01*
X1425333Y1159300D01*
X1425083Y1159383D01*
X1424833Y1159300D01*
X1424625Y1159092D01*
X1424500Y1158717D01*
X1424542Y1158342D01*
X1424708Y1157967D01*
G01X1424917Y1160858D02*
X1424667Y1161108D01*
X1424542Y1161400D01*
X1424500Y1161733D01*
X1424583Y1162150D01*
X1424792Y1162442D01*
X1425042Y1162525D01*
X1425292Y1162483D01*
X1425500Y1162317D01*
X1425917Y1161483D01*
X1426208Y1161108D01*
X1426625Y1160858D01*
X1427000Y1160775D01*
Y1162525D01*
G01X1380017Y1169667D02*
Y1172167D01*
X1381058D01*
X1381392Y1172042D01*
X1381600Y1171875D01*
X1381683Y1171542D01*
X1381600Y1171209D01*
X1381350Y1171000D01*
X1381058Y1170875D01*
X1380017D01*
G01X1381058D02*
X1381683Y1169667D01*
G01X1383158Y1171750D02*
X1383408Y1172000D01*
X1383700Y1172125D01*
X1384033Y1172167D01*
X1384450Y1172084D01*
X1384742Y1171875D01*
X1384825Y1171625D01*
X1384783Y1171375D01*
X1384617Y1171167D01*
X1383783Y1170750D01*
X1383408Y1170459D01*
X1383158Y1170042D01*
X1383075Y1169667D01*
X1384825D01*
G01X1386342Y1169959D02*
X1386633Y1169750D01*
X1386967Y1169667D01*
X1387300Y1169750D01*
X1387592Y1170000D01*
X1387800Y1170375D01*
X1387883Y1170750D01*
Y1171209D01*
X1387800Y1171584D01*
X1387592Y1171917D01*
X1387342Y1172084D01*
X1387050Y1172167D01*
X1386717Y1172084D01*
X1386467Y1171917D01*
X1386300Y1171667D01*
X1386217Y1171334D01*
X1386300Y1171042D01*
X1386508Y1170750D01*
X1386758Y1170584D01*
X1387050Y1170542D01*
X1387383Y1170625D01*
X1387633Y1170834D01*
X1387883Y1171209D01*
G01X1389233Y1170042D02*
X1389483Y1169834D01*
X1389775Y1169709D01*
X1390150Y1169667D01*
X1390525Y1169750D01*
X1390817Y1169917D01*
X1391025Y1170209D01*
X1391067Y1170542D01*
X1390983Y1170875D01*
X1390775Y1171084D01*
X1390483Y1171250D01*
X1390192Y1171292D01*
X1389900Y1171250D01*
X1389525Y1171084D01*
X1389650Y1172167D01*
X1390775D01*
G01X1421208Y1176267D02*
X1421083Y1176017D01*
X1421000Y1175725D01*
Y1175392D01*
X1421125Y1175017D01*
X1421333Y1174725D01*
X1421583Y1174517D01*
X1422000Y1174350D01*
X1422375Y1174308D01*
X1422750Y1174392D01*
X1423000Y1174517D01*
X1423250Y1174767D01*
X1423417Y1175058D01*
X1423500Y1175350D01*
Y1175642D01*
X1423417Y1175933D01*
X1423292Y1176183D01*
X1423125Y1176392D01*
G01X1423500Y1178450D02*
X1421000D01*
X1421500Y1177950D01*
G01X1423500D02*
Y1178950D01*
G01X1423000Y1180633D02*
X1423292Y1180883D01*
X1423458Y1181217D01*
X1423500Y1181592D01*
X1423458Y1181925D01*
X1423250Y1182258D01*
X1423000Y1182467D01*
X1422750Y1182508D01*
X1422458Y1182425D01*
X1422250Y1182133D01*
X1422167Y1181842D01*
Y1181467D01*
G01Y1181842D02*
X1422042Y1182092D01*
X1421833Y1182300D01*
X1421583Y1182383D01*
X1421333Y1182300D01*
X1421125Y1182092D01*
X1421000Y1181717D01*
X1421042Y1181342D01*
X1421208Y1180967D01*
G01X1423500Y1184650D02*
X1421000D01*
X1421500Y1184150D01*
G01X1423500D02*
Y1185150D01*
G01X1395325Y1232000D02*
Y1234500D01*
G01X1397075D02*
Y1232000D01*
G01Y1233250D02*
X1395325D01*
G01X1398383Y1232000D02*
Y1234500D01*
X1399217D01*
X1399550Y1234375D01*
X1399800Y1234208D01*
X1400008Y1233958D01*
X1400175Y1233667D01*
X1400217Y1233250D01*
X1400175Y1232833D01*
X1400008Y1232542D01*
X1399800Y1232292D01*
X1399550Y1232125D01*
X1399217Y1232000D01*
X1398383D01*
G01X1401483D02*
Y1234500D01*
X1402317D01*
X1402650Y1234375D01*
X1402900Y1234208D01*
X1403108Y1233958D01*
X1403275Y1233667D01*
X1403317Y1233250D01*
X1403275Y1232833D01*
X1403108Y1232542D01*
X1402900Y1232292D01*
X1402650Y1232125D01*
X1402317Y1232000D01*
X1401483D01*
G01X1404625Y1232333D02*
X1404958Y1232125D01*
X1405333Y1232000D01*
X1405667D01*
X1406000Y1232125D01*
X1406250Y1232333D01*
X1406375Y1232625D01*
X1406292Y1232917D01*
X1406083Y1233167D01*
X1405708Y1233333D01*
X1405208Y1233417D01*
X1404917Y1233583D01*
X1404792Y1233875D01*
X1404875Y1234167D01*
X1405083Y1234375D01*
X1405375Y1234500D01*
X1405667D01*
X1405958Y1234417D01*
X1406208Y1234208D01*
G01X1407558Y1232000D02*
X1408600Y1234500D01*
X1409642Y1232000D01*
G01X1409267Y1232875D02*
X1407933D01*
G01X1410825Y1232333D02*
X1411158Y1232125D01*
X1411533Y1232000D01*
X1411867D01*
X1412200Y1232125D01*
X1412450Y1232333D01*
X1412575Y1232625D01*
X1412492Y1232917D01*
X1412283Y1233167D01*
X1411908Y1233333D01*
X1411408Y1233417D01*
X1411117Y1233583D01*
X1410992Y1233875D01*
X1411075Y1234167D01*
X1411283Y1234375D01*
X1411575Y1234500D01*
X1411867D01*
X1412158Y1234417D01*
X1412408Y1234208D01*
G01X1414717Y1232000D02*
X1414800Y1232542D01*
X1414925Y1233000D01*
X1415092Y1233417D01*
X1415300Y1233875D01*
X1415633Y1234500D01*
X1413967D01*
G01X1440834Y150517D02*
X1438334D01*
Y151558D01*
X1438459Y151892D01*
X1438626Y152100D01*
X1438959Y152183D01*
X1439292Y152100D01*
X1439501Y151850D01*
X1439626Y151558D01*
Y150517D01*
G01Y151558D02*
X1440834Y152183D01*
G01Y154450D02*
X1440792Y154742D01*
X1440667Y155075D01*
X1440459Y155283D01*
X1440167Y155367D01*
X1439876Y155283D01*
X1439626Y155033D01*
X1439501Y154658D01*
Y154242D01*
X1439417Y153992D01*
X1439209Y153783D01*
X1438917Y153700D01*
X1438626Y153825D01*
X1438417Y154117D01*
X1438334Y154450D01*
X1438417Y154783D01*
X1438626Y155075D01*
X1438917Y155200D01*
X1439209Y155117D01*
X1439417Y154908D01*
X1439501Y154658D01*
Y154242D01*
X1439626Y153867D01*
X1439876Y153617D01*
X1440167Y153533D01*
X1440459Y153617D01*
X1440667Y153825D01*
X1440792Y154158D01*
X1440834Y154450D01*
G01X1440459Y156633D02*
X1440667Y156883D01*
X1440792Y157175D01*
X1440834Y157550D01*
X1440751Y157925D01*
X1440584Y158217D01*
X1440292Y158425D01*
X1439959Y158467D01*
X1439626Y158383D01*
X1439417Y158175D01*
X1439251Y157883D01*
X1439209Y157592D01*
X1439251Y157300D01*
X1439417Y156925D01*
X1438334Y157050D01*
Y158175D01*
G01X1440834Y160650D02*
X1438334D01*
X1438834Y160150D01*
G01X1440834D02*
Y161150D01*
G01X1434213Y163961D02*
X1438213D01*
Y171361D01*
G01X1447334Y151017D02*
X1444834D01*
Y152058D01*
X1444959Y152392D01*
X1445126Y152600D01*
X1445459Y152683D01*
X1445792Y152600D01*
X1446001Y152350D01*
X1446126Y152058D01*
Y151017D01*
G01Y152058D02*
X1447334Y152683D01*
G01Y154950D02*
X1447292Y155242D01*
X1447167Y155575D01*
X1446959Y155783D01*
X1446667Y155867D01*
X1446376Y155783D01*
X1446126Y155533D01*
X1446001Y155158D01*
Y154742D01*
X1445917Y154492D01*
X1445709Y154283D01*
X1445417Y154200D01*
X1445126Y154325D01*
X1444917Y154617D01*
X1444834Y154950D01*
X1444917Y155283D01*
X1445126Y155575D01*
X1445417Y155700D01*
X1445709Y155617D01*
X1445917Y155408D01*
X1446001Y155158D01*
Y154742D01*
X1446126Y154367D01*
X1446376Y154117D01*
X1446667Y154033D01*
X1446959Y154117D01*
X1447167Y154325D01*
X1447292Y154658D01*
X1447334Y154950D01*
G01X1446959Y157133D02*
X1447167Y157383D01*
X1447292Y157675D01*
X1447334Y158050D01*
X1447251Y158425D01*
X1447084Y158717D01*
X1446792Y158925D01*
X1446459Y158967D01*
X1446126Y158883D01*
X1445917Y158675D01*
X1445751Y158383D01*
X1445709Y158092D01*
X1445751Y157800D01*
X1445917Y157425D01*
X1444834Y157550D01*
Y158675D01*
G01X1446834Y160233D02*
X1447126Y160483D01*
X1447292Y160817D01*
X1447334Y161192D01*
X1447292Y161525D01*
X1447084Y161858D01*
X1446834Y162067D01*
X1446584Y162108D01*
X1446292Y162025D01*
X1446084Y161733D01*
X1446001Y161442D01*
Y161067D01*
G01Y161442D02*
X1445876Y161692D01*
X1445667Y161900D01*
X1445417Y161983D01*
X1445167Y161900D01*
X1444959Y161692D01*
X1444834Y161317D01*
X1444876Y160942D01*
X1445042Y160567D01*
G01X1444213Y163961D02*
X1448213D01*
Y171361D01*
G01X1433334Y149517D02*
X1430834D01*
Y150558D01*
X1430959Y150892D01*
X1431126Y151100D01*
X1431459Y151183D01*
X1431792Y151100D01*
X1432001Y150850D01*
X1432126Y150558D01*
Y149517D01*
G01Y150558D02*
X1433334Y151183D01*
G01Y153450D02*
X1433292Y153742D01*
X1433167Y154075D01*
X1432959Y154283D01*
X1432667Y154367D01*
X1432376Y154283D01*
X1432126Y154033D01*
X1432001Y153658D01*
Y153242D01*
X1431917Y152992D01*
X1431709Y152783D01*
X1431417Y152700D01*
X1431126Y152825D01*
X1430917Y153117D01*
X1430834Y153450D01*
X1430917Y153783D01*
X1431126Y154075D01*
X1431417Y154200D01*
X1431709Y154117D01*
X1431917Y153908D01*
X1432001Y153658D01*
Y153242D01*
X1432126Y152867D01*
X1432376Y152617D01*
X1432667Y152533D01*
X1432959Y152617D01*
X1433167Y152825D01*
X1433292Y153158D01*
X1433334Y153450D01*
G01X1432959Y155633D02*
X1433167Y155883D01*
X1433292Y156175D01*
X1433334Y156550D01*
X1433251Y156925D01*
X1433084Y157217D01*
X1432792Y157425D01*
X1432459Y157467D01*
X1432126Y157383D01*
X1431917Y157175D01*
X1431751Y156883D01*
X1431709Y156592D01*
X1431751Y156300D01*
X1431917Y155925D01*
X1430834Y156050D01*
Y157175D01*
G01X1432959Y158733D02*
X1433167Y158983D01*
X1433292Y159275D01*
X1433334Y159650D01*
X1433251Y160025D01*
X1433084Y160317D01*
X1432792Y160525D01*
X1432459Y160567D01*
X1432126Y160483D01*
X1431917Y160275D01*
X1431751Y159983D01*
X1431709Y159692D01*
X1431751Y159400D01*
X1431917Y159025D01*
X1430834Y159150D01*
Y160275D01*
G01X1433713Y171361D02*
X1429713D01*
Y163961D01*
G01X1464230Y189161D02*
Y191661D01*
X1465271D01*
X1465605Y191536D01*
X1465813Y191369D01*
X1465896Y191036D01*
X1465813Y190703D01*
X1465563Y190494D01*
X1465271Y190369D01*
X1464230D01*
G01X1465271D02*
X1465896Y189161D01*
G01X1468163D02*
X1468455Y189203D01*
X1468788Y189328D01*
X1468996Y189536D01*
X1469080Y189828D01*
X1468996Y190119D01*
X1468746Y190369D01*
X1468371Y190494D01*
X1467955D01*
X1467705Y190578D01*
X1467496Y190786D01*
X1467413Y191078D01*
X1467538Y191369D01*
X1467830Y191578D01*
X1468163Y191661D01*
X1468496Y191578D01*
X1468788Y191369D01*
X1468913Y191078D01*
X1468830Y190786D01*
X1468621Y190578D01*
X1468371Y190494D01*
X1467955D01*
X1467580Y190369D01*
X1467330Y190119D01*
X1467246Y189828D01*
X1467330Y189536D01*
X1467538Y189328D01*
X1467871Y189203D01*
X1468163Y189161D01*
G01X1470346Y189536D02*
X1470596Y189328D01*
X1470888Y189203D01*
X1471263Y189161D01*
X1471638Y189244D01*
X1471930Y189411D01*
X1472138Y189703D01*
X1472180Y190036D01*
X1472096Y190369D01*
X1471888Y190578D01*
X1471596Y190744D01*
X1471305Y190786D01*
X1471013Y190744D01*
X1470638Y190578D01*
X1470763Y191661D01*
X1471888D01*
G01X1474363D02*
X1474030Y191578D01*
X1473780Y191369D01*
X1473613Y191119D01*
X1473488Y190786D01*
X1473446Y190411D01*
X1473488Y190036D01*
X1473613Y189703D01*
X1473780Y189453D01*
X1474030Y189244D01*
X1474363Y189161D01*
X1474696Y189244D01*
X1474946Y189453D01*
X1475113Y189703D01*
X1475238Y190036D01*
X1475280Y190411D01*
X1475238Y190786D01*
X1475113Y191119D01*
X1474946Y191369D01*
X1474696Y191578D01*
X1474363Y191661D01*
G01X1437913Y189161D02*
Y193161D01*
X1430513D01*
G01X1461459Y171625D02*
X1458959D01*
Y172666D01*
X1459084Y173000D01*
X1459251Y173208D01*
X1459584Y173291D01*
X1459917Y173208D01*
X1460126Y172958D01*
X1460251Y172666D01*
Y171625D01*
G01Y172666D02*
X1461459Y173291D01*
G01Y175558D02*
X1461417Y175850D01*
X1461292Y176183D01*
X1461084Y176391D01*
X1460792Y176475D01*
X1460501Y176391D01*
X1460251Y176141D01*
X1460126Y175766D01*
Y175350D01*
X1460042Y175100D01*
X1459834Y174891D01*
X1459542Y174808D01*
X1459251Y174933D01*
X1459042Y175225D01*
X1458959Y175558D01*
X1459042Y175891D01*
X1459251Y176183D01*
X1459542Y176308D01*
X1459834Y176225D01*
X1460042Y176016D01*
X1460126Y175766D01*
Y175350D01*
X1460251Y174975D01*
X1460501Y174725D01*
X1460792Y174641D01*
X1461084Y174725D01*
X1461292Y174933D01*
X1461417Y175266D01*
X1461459Y175558D01*
G01X1461084Y177741D02*
X1461292Y177991D01*
X1461417Y178283D01*
X1461459Y178658D01*
X1461376Y179033D01*
X1461209Y179325D01*
X1460917Y179533D01*
X1460584Y179575D01*
X1460251Y179491D01*
X1460042Y179283D01*
X1459876Y178991D01*
X1459834Y178700D01*
X1459876Y178408D01*
X1460042Y178033D01*
X1458959Y178158D01*
Y179283D01*
G01X1460417Y180966D02*
X1460126Y181258D01*
X1459959Y181508D01*
X1459876Y181841D01*
X1459959Y182133D01*
X1460126Y182341D01*
X1460376Y182508D01*
X1460667Y182550D01*
X1460917Y182508D01*
X1461167Y182341D01*
X1461376Y182091D01*
X1461459Y181800D01*
X1461376Y181466D01*
X1461126Y181175D01*
X1460751Y181008D01*
X1460334Y180966D01*
X1459792Y181050D01*
X1459501Y181175D01*
X1459209Y181383D01*
X1459001Y181675D01*
X1458959Y181966D01*
X1459042Y182258D01*
X1459251Y182466D01*
G01X1448713Y176361D02*
X1452713D01*
Y183761D01*
G01X1451513Y196661D02*
Y192661D01*
X1458913D01*
G01X1457259Y171625D02*
X1454759D01*
Y172666D01*
X1454884Y173000D01*
X1455051Y173208D01*
X1455384Y173291D01*
X1455717Y173208D01*
X1455926Y172958D01*
X1456051Y172666D01*
Y171625D01*
G01Y172666D02*
X1457259Y173291D01*
G01Y175558D02*
X1457217Y175850D01*
X1457092Y176183D01*
X1456884Y176391D01*
X1456592Y176475D01*
X1456301Y176391D01*
X1456051Y176141D01*
X1455926Y175766D01*
Y175350D01*
X1455842Y175100D01*
X1455634Y174891D01*
X1455342Y174808D01*
X1455051Y174933D01*
X1454842Y175225D01*
X1454759Y175558D01*
X1454842Y175891D01*
X1455051Y176183D01*
X1455342Y176308D01*
X1455634Y176225D01*
X1455842Y176016D01*
X1455926Y175766D01*
Y175350D01*
X1456051Y174975D01*
X1456301Y174725D01*
X1456592Y174641D01*
X1456884Y174725D01*
X1457092Y174933D01*
X1457217Y175266D01*
X1457259Y175558D01*
G01X1456217Y177866D02*
X1455926Y178158D01*
X1455759Y178408D01*
X1455676Y178741D01*
X1455759Y179033D01*
X1455926Y179241D01*
X1456176Y179408D01*
X1456467Y179450D01*
X1456717Y179408D01*
X1456967Y179241D01*
X1457176Y178991D01*
X1457259Y178700D01*
X1457176Y178366D01*
X1456926Y178075D01*
X1456551Y177908D01*
X1456134Y177866D01*
X1455592Y177950D01*
X1455301Y178075D01*
X1455009Y178283D01*
X1454801Y178575D01*
X1454759Y178866D01*
X1454842Y179158D01*
X1455051Y179366D01*
G01X1454759Y181758D02*
X1454842Y181425D01*
X1455051Y181175D01*
X1455301Y181008D01*
X1455634Y180883D01*
X1456009Y180841D01*
X1456384Y180883D01*
X1456717Y181008D01*
X1456967Y181175D01*
X1457176Y181425D01*
X1457259Y181758D01*
X1457176Y182091D01*
X1456967Y182341D01*
X1456717Y182508D01*
X1456384Y182633D01*
X1456009Y182675D01*
X1455634Y182633D01*
X1455301Y182508D01*
X1455051Y182341D01*
X1454842Y182091D01*
X1454759Y181758D01*
G01X1444013Y176361D02*
X1448013D01*
Y183761D01*
G01X1438413Y172461D02*
Y183861D01*
G01X1460713Y184661D02*
X1444613D01*
G01X1460713Y191661D02*
Y184661D01*
G01X1444613Y191661D02*
X1460713D01*
G01X1444613Y184661D02*
Y191661D01*
G01X1437113Y218961D02*
Y199761D01*
X1448313D01*
Y218961D01*
X1437113D01*
Y218561D01*
G01X1465980Y195553D02*
X1465730Y195678D01*
X1465438Y195761D01*
X1465105D01*
X1464730Y195636D01*
X1464438Y195428D01*
X1464230Y195178D01*
X1464063Y194761D01*
X1464021Y194386D01*
X1464105Y194011D01*
X1464230Y193761D01*
X1464480Y193511D01*
X1464771Y193344D01*
X1465063Y193261D01*
X1465355D01*
X1465646Y193344D01*
X1465896Y193469D01*
X1466105Y193636D01*
G01X1468663Y193261D02*
Y195761D01*
X1467121Y193969D01*
X1469205D01*
G01X1470346Y193636D02*
X1470596Y193428D01*
X1470888Y193303D01*
X1471263Y193261D01*
X1471638Y193344D01*
X1471930Y193511D01*
X1472138Y193803D01*
X1472180Y194136D01*
X1472096Y194469D01*
X1471888Y194678D01*
X1471596Y194844D01*
X1471305Y194886D01*
X1471013Y194844D01*
X1470638Y194678D01*
X1470763Y195761D01*
X1471888D01*
G01X1474363Y193261D02*
Y195761D01*
X1473863Y195261D01*
G01Y193261D02*
X1474863D01*
G01X1463730Y222661D02*
Y225161D01*
X1464771D01*
X1465105Y225036D01*
X1465313Y224869D01*
X1465396Y224536D01*
X1465313Y224203D01*
X1465063Y223994D01*
X1464771Y223869D01*
X1463730D01*
G01X1464771D02*
X1465396Y222661D01*
G01X1467663D02*
X1467955Y222703D01*
X1468288Y222828D01*
X1468496Y223036D01*
X1468580Y223328D01*
X1468496Y223619D01*
X1468246Y223869D01*
X1467871Y223994D01*
X1467455D01*
X1467205Y224078D01*
X1466996Y224286D01*
X1466913Y224578D01*
X1467038Y224869D01*
X1467330Y225078D01*
X1467663Y225161D01*
X1467996Y225078D01*
X1468288Y224869D01*
X1468413Y224578D01*
X1468330Y224286D01*
X1468121Y224078D01*
X1467871Y223994D01*
X1467455D01*
X1467080Y223869D01*
X1466830Y223619D01*
X1466746Y223328D01*
X1466830Y223036D01*
X1467038Y222828D01*
X1467371Y222703D01*
X1467663Y222661D01*
G01X1469846Y223036D02*
X1470096Y222828D01*
X1470388Y222703D01*
X1470763Y222661D01*
X1471138Y222744D01*
X1471430Y222911D01*
X1471638Y223203D01*
X1471680Y223536D01*
X1471596Y223869D01*
X1471388Y224078D01*
X1471096Y224244D01*
X1470805Y224286D01*
X1470513Y224244D01*
X1470138Y224078D01*
X1470263Y225161D01*
X1471388D01*
G01X1473780Y222661D02*
X1473863Y223203D01*
X1473988Y223661D01*
X1474155Y224078D01*
X1474363Y224536D01*
X1474696Y225161D01*
X1473030D01*
G01X1461413Y221661D02*
Y225661D01*
X1454013D01*
G01X1428713Y250361D02*
Y255861D01*
G01X1436713Y250361D02*
X1428713D01*
G01X1436713Y255861D02*
Y250361D01*
G01X1451350Y260000D02*
X1451017Y260042D01*
X1450725Y260208D01*
X1450475Y260458D01*
X1450308Y260750D01*
X1450225Y261083D01*
Y261417D01*
X1450308Y261750D01*
X1450475Y262042D01*
X1450725Y262292D01*
X1451017Y262458D01*
X1451350Y262500D01*
X1451683Y262458D01*
X1451975Y262292D01*
X1452225Y262042D01*
X1452392Y261750D01*
X1452475Y261417D01*
Y261083D01*
X1452392Y260750D01*
X1452225Y260458D01*
X1451975Y260208D01*
X1451683Y260042D01*
X1451350Y260000D01*
G01X1451683Y260667D02*
X1452183Y260000D01*
G01X1454450D02*
Y262500D01*
X1453950Y262000D01*
G01Y260000D02*
X1454950D01*
G01X1457550D02*
X1457842Y260042D01*
X1458175Y260167D01*
X1458383Y260375D01*
X1458467Y260667D01*
X1458383Y260958D01*
X1458133Y261208D01*
X1457758Y261333D01*
X1457342D01*
X1457092Y261417D01*
X1456883Y261625D01*
X1456800Y261917D01*
X1456925Y262208D01*
X1457217Y262417D01*
X1457550Y262500D01*
X1457883Y262417D01*
X1458175Y262208D01*
X1458300Y261917D01*
X1458217Y261625D01*
X1458008Y261417D01*
X1457758Y261333D01*
X1457342D01*
X1456967Y261208D01*
X1456717Y260958D01*
X1456633Y260667D01*
X1456717Y260375D01*
X1456925Y260167D01*
X1457258Y260042D01*
X1457550Y260000D01*
G01X1460650D02*
X1460942Y260042D01*
X1461275Y260167D01*
X1461483Y260375D01*
X1461567Y260667D01*
X1461483Y260958D01*
X1461233Y261208D01*
X1460858Y261333D01*
X1460442D01*
X1460192Y261417D01*
X1459983Y261625D01*
X1459900Y261917D01*
X1460025Y262208D01*
X1460317Y262417D01*
X1460650Y262500D01*
X1460983Y262417D01*
X1461275Y262208D01*
X1461400Y261917D01*
X1461317Y261625D01*
X1461108Y261417D01*
X1460858Y261333D01*
X1460442D01*
X1460067Y261208D01*
X1459817Y260958D01*
X1459733Y260667D01*
X1459817Y260375D01*
X1460025Y260167D01*
X1460358Y260042D01*
X1460650Y260000D01*
G01X1439513Y246161D02*
X1441613Y244361D01*
X1439513Y242161D01*
G01X1439413Y238561D02*
X1458613D01*
Y249761D01*
X1439413D01*
Y238561D01*
X1439813D01*
G01X1429350Y220500D02*
X1429017Y220542D01*
X1428725Y220708D01*
X1428475Y220958D01*
X1428308Y221250D01*
X1428225Y221583D01*
Y221917D01*
X1428308Y222250D01*
X1428475Y222542D01*
X1428725Y222792D01*
X1429017Y222958D01*
X1429350Y223000D01*
X1429683Y222958D01*
X1429975Y222792D01*
X1430225Y222542D01*
X1430392Y222250D01*
X1430475Y221917D01*
Y221583D01*
X1430392Y221250D01*
X1430225Y220958D01*
X1429975Y220708D01*
X1429683Y220542D01*
X1429350Y220500D01*
G01X1429683Y221167D02*
X1430183Y220500D01*
G01X1432450D02*
Y223000D01*
X1431950Y222500D01*
G01Y220500D02*
X1432950D01*
G01X1435550D02*
X1435842Y220542D01*
X1436175Y220667D01*
X1436383Y220875D01*
X1436467Y221167D01*
X1436383Y221458D01*
X1436133Y221708D01*
X1435758Y221833D01*
X1435342D01*
X1435092Y221917D01*
X1434883Y222125D01*
X1434800Y222417D01*
X1434925Y222708D01*
X1435217Y222917D01*
X1435550Y223000D01*
X1435883Y222917D01*
X1436175Y222708D01*
X1436300Y222417D01*
X1436217Y222125D01*
X1436008Y221917D01*
X1435758Y221833D01*
X1435342D01*
X1434967Y221708D01*
X1434717Y221458D01*
X1434633Y221167D01*
X1434717Y220875D01*
X1434925Y220667D01*
X1435258Y220542D01*
X1435550Y220500D01*
G01X1437733Y220875D02*
X1437983Y220667D01*
X1438275Y220542D01*
X1438650Y220500D01*
X1439025Y220583D01*
X1439317Y220750D01*
X1439525Y221042D01*
X1439567Y221375D01*
X1439483Y221708D01*
X1439275Y221917D01*
X1438983Y222083D01*
X1438692Y222125D01*
X1438400Y222083D01*
X1438025Y221917D01*
X1438150Y223000D01*
X1439275D01*
G01X1444713Y218861D02*
X1442913Y216761D01*
X1440713Y218861D01*
G01X1465480Y229053D02*
X1465230Y229178D01*
X1464938Y229261D01*
X1464605D01*
X1464230Y229136D01*
X1463938Y228928D01*
X1463730Y228678D01*
X1463563Y228261D01*
X1463521Y227886D01*
X1463605Y227511D01*
X1463730Y227261D01*
X1463980Y227011D01*
X1464271Y226844D01*
X1464563Y226761D01*
X1464855D01*
X1465146Y226844D01*
X1465396Y226969D01*
X1465605Y227136D01*
G01X1468163Y226761D02*
Y229261D01*
X1466621Y227469D01*
X1468705D01*
G01X1469846Y227136D02*
X1470096Y226928D01*
X1470388Y226803D01*
X1470763Y226761D01*
X1471138Y226844D01*
X1471430Y227011D01*
X1471638Y227303D01*
X1471680Y227636D01*
X1471596Y227969D01*
X1471388Y228178D01*
X1471096Y228344D01*
X1470805Y228386D01*
X1470513Y228344D01*
X1470138Y228178D01*
X1470263Y229261D01*
X1471388D01*
G01X1473071Y228844D02*
X1473321Y229094D01*
X1473613Y229219D01*
X1473946Y229261D01*
X1474363Y229178D01*
X1474655Y228969D01*
X1474738Y228719D01*
X1474696Y228469D01*
X1474530Y228261D01*
X1473696Y227844D01*
X1473321Y227553D01*
X1473071Y227136D01*
X1472988Y226761D01*
X1474738D01*
G01X1438517Y265500D02*
Y268000D01*
X1439558D01*
X1439892Y267875D01*
X1440100Y267708D01*
X1440183Y267375D01*
X1440100Y267042D01*
X1439850Y266833D01*
X1439558Y266708D01*
X1438517D01*
G01X1439558D02*
X1440183Y265500D01*
G01X1442450D02*
X1442742Y265542D01*
X1443075Y265667D01*
X1443283Y265875D01*
X1443367Y266167D01*
X1443283Y266458D01*
X1443033Y266708D01*
X1442658Y266833D01*
X1442242D01*
X1441992Y266917D01*
X1441783Y267125D01*
X1441700Y267417D01*
X1441825Y267708D01*
X1442117Y267917D01*
X1442450Y268000D01*
X1442783Y267917D01*
X1443075Y267708D01*
X1443200Y267417D01*
X1443117Y267125D01*
X1442908Y266917D01*
X1442658Y266833D01*
X1442242D01*
X1441867Y266708D01*
X1441617Y266458D01*
X1441533Y266167D01*
X1441617Y265875D01*
X1441825Y265667D01*
X1442158Y265542D01*
X1442450Y265500D01*
G01X1446050D02*
Y268000D01*
X1444508Y266208D01*
X1446592D01*
G01X1449150Y265500D02*
Y268000D01*
X1447608Y266208D01*
X1449692D01*
G01X1446347Y277425D02*
Y269425D01*
X1428747D01*
Y277425D01*
X1446347D01*
G01X1450542Y288767D02*
X1450417Y288517D01*
X1450334Y288225D01*
Y287892D01*
X1450459Y287517D01*
X1450667Y287225D01*
X1450917Y287017D01*
X1451334Y286850D01*
X1451709Y286808D01*
X1452084Y286892D01*
X1452334Y287017D01*
X1452584Y287267D01*
X1452751Y287558D01*
X1452834Y287850D01*
Y288142D01*
X1452751Y288433D01*
X1452626Y288683D01*
X1452459Y288892D01*
G01X1452834Y291450D02*
X1450334D01*
X1452126Y289908D01*
Y291992D01*
G01X1452834Y294550D02*
X1450334D01*
X1452126Y293008D01*
Y295092D01*
G01X1452834Y297150D02*
X1452792Y297442D01*
X1452667Y297775D01*
X1452459Y297983D01*
X1452167Y298067D01*
X1451876Y297983D01*
X1451626Y297733D01*
X1451501Y297358D01*
Y296942D01*
X1451417Y296692D01*
X1451209Y296483D01*
X1450917Y296400D01*
X1450626Y296525D01*
X1450417Y296817D01*
X1450334Y297150D01*
X1450417Y297483D01*
X1450626Y297775D01*
X1450917Y297900D01*
X1451209Y297817D01*
X1451417Y297608D01*
X1451501Y297358D01*
Y296942D01*
X1451626Y296567D01*
X1451876Y296317D01*
X1452167Y296233D01*
X1452459Y296317D01*
X1452667Y296525D01*
X1452792Y296858D01*
X1452834Y297150D01*
G01X1446708Y288767D02*
X1446583Y288517D01*
X1446500Y288225D01*
Y287892D01*
X1446625Y287517D01*
X1446833Y287225D01*
X1447083Y287017D01*
X1447500Y286850D01*
X1447875Y286808D01*
X1448250Y286892D01*
X1448500Y287017D01*
X1448750Y287267D01*
X1448917Y287558D01*
X1449000Y287850D01*
Y288142D01*
X1448917Y288433D01*
X1448792Y288683D01*
X1448625Y288892D01*
G01X1449000Y291450D02*
X1446500D01*
X1448292Y289908D01*
Y291992D01*
G01X1449000Y294550D02*
X1446500D01*
X1448292Y293008D01*
Y295092D01*
G01X1449000Y297067D02*
X1448458Y297150D01*
X1448000Y297275D01*
X1447583Y297442D01*
X1447125Y297650D01*
X1446500Y297983D01*
Y296317D01*
G01X1436713Y267961D02*
Y262461D01*
G01X1428713Y267961D02*
X1436713D01*
G01X1428713Y262461D02*
Y267961D01*
G01X1442708Y288767D02*
X1442583Y288517D01*
X1442500Y288225D01*
Y287892D01*
X1442625Y287517D01*
X1442833Y287225D01*
X1443083Y287017D01*
X1443500Y286850D01*
X1443875Y286808D01*
X1444250Y286892D01*
X1444500Y287017D01*
X1444750Y287267D01*
X1444917Y287558D01*
X1445000Y287850D01*
Y288142D01*
X1444917Y288433D01*
X1444792Y288683D01*
X1444625Y288892D01*
G01X1445000Y291450D02*
X1442500D01*
X1444292Y289908D01*
Y291992D01*
G01X1444625Y293133D02*
X1444833Y293383D01*
X1444958Y293675D01*
X1445000Y294050D01*
X1444917Y294425D01*
X1444750Y294717D01*
X1444458Y294925D01*
X1444125Y294967D01*
X1443792Y294883D01*
X1443583Y294675D01*
X1443417Y294383D01*
X1443375Y294092D01*
X1443417Y293800D01*
X1443583Y293425D01*
X1442500Y293550D01*
Y294675D01*
G01Y297150D02*
X1442583Y296817D01*
X1442792Y296567D01*
X1443042Y296400D01*
X1443375Y296275D01*
X1443750Y296233D01*
X1444125Y296275D01*
X1444458Y296400D01*
X1444708Y296567D01*
X1444917Y296817D01*
X1445000Y297150D01*
X1444917Y297483D01*
X1444708Y297733D01*
X1444458Y297900D01*
X1444125Y298025D01*
X1443750Y298067D01*
X1443375Y298025D01*
X1443042Y297900D01*
X1442792Y297733D01*
X1442583Y297483D01*
X1442500Y297150D01*
G01X1464300Y477017D02*
X1461800D01*
Y478058D01*
X1461925Y478392D01*
X1462092Y478600D01*
X1462425Y478683D01*
X1462758Y478600D01*
X1462967Y478350D01*
X1463092Y478058D01*
Y477017D01*
G01Y478058D02*
X1464300Y478683D01*
G01X1463925Y480033D02*
X1464133Y480283D01*
X1464258Y480575D01*
X1464300Y480950D01*
X1464217Y481325D01*
X1464050Y481617D01*
X1463758Y481825D01*
X1463425Y481867D01*
X1463092Y481783D01*
X1462883Y481575D01*
X1462717Y481283D01*
X1462675Y480992D01*
X1462717Y480700D01*
X1462883Y480325D01*
X1461800Y480450D01*
Y481575D01*
G01X1463800Y483133D02*
X1464092Y483383D01*
X1464258Y483717D01*
X1464300Y484092D01*
X1464258Y484425D01*
X1464050Y484758D01*
X1463800Y484967D01*
X1463550Y485008D01*
X1463258Y484925D01*
X1463050Y484633D01*
X1462967Y484342D01*
Y483967D01*
G01Y484342D02*
X1462842Y484592D01*
X1462633Y484800D01*
X1462383Y484883D01*
X1462133Y484800D01*
X1461925Y484592D01*
X1461800Y484217D01*
X1461842Y483842D01*
X1462008Y483467D01*
G01X1464300Y487650D02*
X1461800D01*
X1463592Y486108D01*
Y488192D01*
G01X1461085Y501185D02*
X1465085D01*
Y508585D01*
G01X1448801Y485871D02*
X1448468Y485913D01*
X1448176Y486079D01*
X1447926Y486329D01*
X1447759Y486621D01*
X1447676Y486954D01*
Y487288D01*
X1447759Y487621D01*
X1447926Y487913D01*
X1448176Y488163D01*
X1448468Y488329D01*
X1448801Y488371D01*
X1449134Y488329D01*
X1449426Y488163D01*
X1449676Y487913D01*
X1449843Y487621D01*
X1449926Y487288D01*
Y486954D01*
X1449843Y486621D01*
X1449676Y486329D01*
X1449426Y486079D01*
X1449134Y485913D01*
X1448801Y485871D01*
G01X1449134Y486538D02*
X1449634Y485871D01*
G01X1451109Y487954D02*
X1451359Y488204D01*
X1451651Y488329D01*
X1451984Y488371D01*
X1452401Y488288D01*
X1452693Y488079D01*
X1452776Y487829D01*
X1452734Y487579D01*
X1452568Y487371D01*
X1451734Y486954D01*
X1451359Y486663D01*
X1451109Y486246D01*
X1451026Y485871D01*
X1452776D01*
G01X1455001D02*
X1455293Y485913D01*
X1455626Y486038D01*
X1455834Y486246D01*
X1455918Y486538D01*
X1455834Y486829D01*
X1455584Y487079D01*
X1455209Y487204D01*
X1454793D01*
X1454543Y487288D01*
X1454334Y487496D01*
X1454251Y487788D01*
X1454376Y488079D01*
X1454668Y488288D01*
X1455001Y488371D01*
X1455334Y488288D01*
X1455626Y488079D01*
X1455751Y487788D01*
X1455668Y487496D01*
X1455459Y487288D01*
X1455209Y487204D01*
X1454793D01*
X1454418Y487079D01*
X1454168Y486829D01*
X1454084Y486538D01*
X1454168Y486246D01*
X1454376Y486038D01*
X1454709Y485913D01*
X1455001Y485871D01*
G01X1457184Y486371D02*
X1457434Y486079D01*
X1457768Y485913D01*
X1458143Y485871D01*
X1458476Y485913D01*
X1458809Y486121D01*
X1459018Y486371D01*
X1459059Y486621D01*
X1458976Y486913D01*
X1458684Y487121D01*
X1458393Y487204D01*
X1458018D01*
G01X1458393D02*
X1458643Y487329D01*
X1458851Y487538D01*
X1458934Y487788D01*
X1458851Y488038D01*
X1458643Y488246D01*
X1458268Y488371D01*
X1457893Y488329D01*
X1457518Y488163D01*
G01X1459951Y495871D02*
Y509871D01*
G01X1446951Y495871D02*
X1459951D01*
G01X1446951Y509871D02*
Y495871D01*
G01X1467830Y485768D02*
X1467497Y485810D01*
X1467205Y485976D01*
X1466955Y486226D01*
X1466788Y486518D01*
X1466705Y486851D01*
Y487185D01*
X1466788Y487518D01*
X1466955Y487810D01*
X1467205Y488060D01*
X1467497Y488226D01*
X1467830Y488268D01*
X1468163Y488226D01*
X1468455Y488060D01*
X1468705Y487810D01*
X1468872Y487518D01*
X1468955Y487185D01*
Y486851D01*
X1468872Y486518D01*
X1468705Y486226D01*
X1468455Y485976D01*
X1468163Y485810D01*
X1467830Y485768D01*
G01X1468163Y486435D02*
X1468663Y485768D01*
G01X1470138Y487851D02*
X1470388Y488101D01*
X1470680Y488226D01*
X1471013Y488268D01*
X1471430Y488185D01*
X1471722Y487976D01*
X1471805Y487726D01*
X1471763Y487476D01*
X1471597Y487268D01*
X1470763Y486851D01*
X1470388Y486560D01*
X1470138Y486143D01*
X1470055Y485768D01*
X1471805D01*
G01X1474530D02*
Y488268D01*
X1472988Y486476D01*
X1475072D01*
G01X1477047Y485768D02*
X1477130Y486310D01*
X1477255Y486768D01*
X1477422Y487185D01*
X1477630Y487643D01*
X1477963Y488268D01*
X1476297D01*
G01X1465980Y495768D02*
X1478980D01*
G01X1465980Y509768D02*
Y495768D01*
G01X1428442Y498867D02*
X1428317Y498617D01*
X1428234Y498325D01*
Y497992D01*
X1428359Y497617D01*
X1428567Y497325D01*
X1428817Y497117D01*
X1429234Y496950D01*
X1429609Y496908D01*
X1429984Y496992D01*
X1430234Y497117D01*
X1430484Y497367D01*
X1430651Y497658D01*
X1430734Y497950D01*
Y498242D01*
X1430651Y498533D01*
X1430526Y498783D01*
X1430359Y498992D01*
G01Y500133D02*
X1430567Y500383D01*
X1430692Y500675D01*
X1430734Y501050D01*
X1430651Y501425D01*
X1430484Y501717D01*
X1430192Y501925D01*
X1429859Y501967D01*
X1429526Y501883D01*
X1429317Y501675D01*
X1429151Y501383D01*
X1429109Y501092D01*
X1429151Y500800D01*
X1429317Y500425D01*
X1428234Y500550D01*
Y501675D01*
G01X1429692Y503358D02*
X1429401Y503650D01*
X1429234Y503900D01*
X1429151Y504233D01*
X1429234Y504525D01*
X1429401Y504733D01*
X1429651Y504900D01*
X1429942Y504942D01*
X1430192Y504900D01*
X1430442Y504733D01*
X1430651Y504483D01*
X1430734Y504192D01*
X1430651Y503858D01*
X1430401Y503567D01*
X1430026Y503400D01*
X1429609Y503358D01*
X1429067Y503442D01*
X1428776Y503567D01*
X1428484Y503775D01*
X1428276Y504067D01*
X1428234Y504358D01*
X1428317Y504650D01*
X1428526Y504858D01*
G01X1430734Y507167D02*
X1430192Y507250D01*
X1429734Y507375D01*
X1429317Y507542D01*
X1428859Y507750D01*
X1428234Y508083D01*
Y506417D01*
G01X1428142Y481067D02*
X1428017Y480817D01*
X1427934Y480525D01*
Y480192D01*
X1428059Y479817D01*
X1428267Y479525D01*
X1428517Y479317D01*
X1428934Y479150D01*
X1429309Y479108D01*
X1429684Y479192D01*
X1429934Y479317D01*
X1430184Y479567D01*
X1430351Y479858D01*
X1430434Y480150D01*
Y480442D01*
X1430351Y480733D01*
X1430226Y480983D01*
X1430059Y481192D01*
G01Y482333D02*
X1430267Y482583D01*
X1430392Y482875D01*
X1430434Y483250D01*
X1430351Y483625D01*
X1430184Y483917D01*
X1429892Y484125D01*
X1429559Y484167D01*
X1429226Y484083D01*
X1429017Y483875D01*
X1428851Y483583D01*
X1428809Y483292D01*
X1428851Y483000D01*
X1429017Y482625D01*
X1427934Y482750D01*
Y483875D01*
G01X1429392Y485558D02*
X1429101Y485850D01*
X1428934Y486100D01*
X1428851Y486433D01*
X1428934Y486725D01*
X1429101Y486933D01*
X1429351Y487100D01*
X1429642Y487142D01*
X1429892Y487100D01*
X1430142Y486933D01*
X1430351Y486683D01*
X1430434Y486392D01*
X1430351Y486058D01*
X1430101Y485767D01*
X1429726Y485600D01*
X1429309Y485558D01*
X1428767Y485642D01*
X1428476Y485767D01*
X1428184Y485975D01*
X1427976Y486267D01*
X1427934Y486558D01*
X1428017Y486850D01*
X1428226Y487058D01*
G01X1429392Y488658D02*
X1429101Y488950D01*
X1428934Y489200D01*
X1428851Y489533D01*
X1428934Y489825D01*
X1429101Y490033D01*
X1429351Y490200D01*
X1429642Y490242D01*
X1429892Y490200D01*
X1430142Y490033D01*
X1430351Y489783D01*
X1430434Y489492D01*
X1430351Y489158D01*
X1430101Y488867D01*
X1429726Y488700D01*
X1429309Y488658D01*
X1428767Y488742D01*
X1428476Y488867D01*
X1428184Y489075D01*
X1427976Y489367D01*
X1427934Y489658D01*
X1428017Y489950D01*
X1428226Y490158D01*
G01X1472700Y530800D02*
X1468700D01*
Y523400D01*
G01X1440900Y524100D02*
Y528100D01*
X1433500D01*
G01X1437200Y523800D02*
X1433200D01*
Y516400D01*
G01X1446500Y528100D02*
Y524100D01*
X1453900D01*
G01X1450261Y523734D02*
X1446261D01*
Y516334D01*
G01X1454500Y528100D02*
Y524100D01*
X1461900D01*
G01X1458439Y523766D02*
X1454439D01*
Y516366D01*
G01X1459951Y509871D02*
X1446951D01*
G01X1478980Y509768D02*
X1465980D01*
G01X1458187Y534650D02*
Y536650D01*
G01X1473150Y544680D02*
X1470150D01*
G01X1441250Y546648D02*
X1444250D01*
G01X1471050Y540750D02*
Y535750D01*
X1466050D01*
G01X1427000Y542100D02*
Y538100D01*
X1434400D01*
G01X1444700Y593067D02*
X1442200D01*
Y594108D01*
X1442325Y594442D01*
X1442492Y594650D01*
X1442825Y594733D01*
X1443158Y594650D01*
X1443367Y594400D01*
X1443492Y594108D01*
Y593067D01*
G01Y594108D02*
X1444700Y594733D01*
G01Y597000D02*
X1442200D01*
X1442700Y596500D01*
G01X1444700D02*
Y597500D01*
G01X1442200Y600100D02*
X1442283Y599767D01*
X1442492Y599517D01*
X1442742Y599350D01*
X1443075Y599225D01*
X1443450Y599183D01*
X1443825Y599225D01*
X1444158Y599350D01*
X1444408Y599517D01*
X1444617Y599767D01*
X1444700Y600100D01*
X1444617Y600433D01*
X1444408Y600683D01*
X1444158Y600850D01*
X1443825Y600975D01*
X1443450Y601017D01*
X1443075Y600975D01*
X1442742Y600850D01*
X1442492Y600683D01*
X1442283Y600433D01*
X1442200Y600100D01*
G01X1444700Y603200D02*
X1444658Y603492D01*
X1444533Y603825D01*
X1444325Y604033D01*
X1444033Y604117D01*
X1443742Y604033D01*
X1443492Y603783D01*
X1443367Y603408D01*
Y602992D01*
X1443283Y602742D01*
X1443075Y602533D01*
X1442783Y602450D01*
X1442492Y602575D01*
X1442283Y602867D01*
X1442200Y603200D01*
X1442283Y603533D01*
X1442492Y603825D01*
X1442783Y603950D01*
X1443075Y603867D01*
X1443283Y603658D01*
X1443367Y603408D01*
Y602992D01*
X1443492Y602617D01*
X1443742Y602367D01*
X1444033Y602283D01*
X1444325Y602367D01*
X1444533Y602575D01*
X1444658Y602908D01*
X1444700Y603200D01*
G01Y606800D02*
X1442200D01*
X1443992Y605258D01*
Y607342D01*
G01X1449700Y577800D02*
X1445700D01*
Y570400D01*
G01X1476700Y577800D02*
X1472700D01*
Y570400D01*
G01X1449200Y593067D02*
X1446700D01*
Y594108D01*
X1446825Y594442D01*
X1446992Y594650D01*
X1447325Y594733D01*
X1447658Y594650D01*
X1447867Y594400D01*
X1447992Y594108D01*
Y593067D01*
G01Y594108D02*
X1449200Y594733D01*
G01Y597000D02*
X1446700D01*
X1447200Y596500D01*
G01X1449200D02*
Y597500D01*
G01X1446700Y600100D02*
X1446783Y599767D01*
X1446992Y599517D01*
X1447242Y599350D01*
X1447575Y599225D01*
X1447950Y599183D01*
X1448325Y599225D01*
X1448658Y599350D01*
X1448908Y599517D01*
X1449117Y599767D01*
X1449200Y600100D01*
X1449117Y600433D01*
X1448908Y600683D01*
X1448658Y600850D01*
X1448325Y600975D01*
X1447950Y601017D01*
X1447575Y600975D01*
X1447242Y600850D01*
X1446992Y600683D01*
X1446783Y600433D01*
X1446700Y600100D01*
G01X1449200Y603200D02*
X1449158Y603492D01*
X1449033Y603825D01*
X1448825Y604033D01*
X1448533Y604117D01*
X1448242Y604033D01*
X1447992Y603783D01*
X1447867Y603408D01*
Y602992D01*
X1447783Y602742D01*
X1447575Y602533D01*
X1447283Y602450D01*
X1446992Y602575D01*
X1446783Y602867D01*
X1446700Y603200D01*
X1446783Y603533D01*
X1446992Y603825D01*
X1447283Y603950D01*
X1447575Y603867D01*
X1447783Y603658D01*
X1447867Y603408D01*
Y602992D01*
X1447992Y602617D01*
X1448242Y602367D01*
X1448533Y602283D01*
X1448825Y602367D01*
X1449033Y602575D01*
X1449158Y602908D01*
X1449200Y603200D01*
G01Y606300D02*
X1449158Y606592D01*
X1449033Y606925D01*
X1448825Y607133D01*
X1448533Y607217D01*
X1448242Y607133D01*
X1447992Y606883D01*
X1447867Y606508D01*
Y606092D01*
X1447783Y605842D01*
X1447575Y605633D01*
X1447283Y605550D01*
X1446992Y605675D01*
X1446783Y605967D01*
X1446700Y606300D01*
X1446783Y606633D01*
X1446992Y606925D01*
X1447283Y607050D01*
X1447575Y606967D01*
X1447783Y606758D01*
X1447867Y606508D01*
Y606092D01*
X1447992Y605717D01*
X1448242Y605467D01*
X1448533Y605383D01*
X1448825Y605467D01*
X1449033Y605675D01*
X1449158Y606008D01*
X1449200Y606300D01*
G01X1450200Y570400D02*
X1454200D01*
Y577800D01*
G01X1468700Y570400D02*
X1472700D01*
Y577800D01*
G01X1438162Y591801D02*
X1443362D01*
G01X1438162Y584801D02*
X1445962D01*
G01X1438162Y591801D02*
Y584801D01*
G01X1451562Y591801D02*
X1442862D01*
G01X1451562Y584801D02*
Y591801D01*
G01X1445162Y584801D02*
X1451562D01*
G01X1440500Y592967D02*
X1438000D01*
Y594008D01*
X1438125Y594342D01*
X1438292Y594550D01*
X1438625Y594633D01*
X1438958Y594550D01*
X1439167Y594300D01*
X1439292Y594008D01*
Y592967D01*
G01Y594008D02*
X1440500Y594633D01*
G01Y596900D02*
X1438000D01*
X1438500Y596400D01*
G01X1440500D02*
Y597400D01*
G01Y600000D02*
X1438000D01*
X1438500Y599500D01*
G01X1440500D02*
Y600500D01*
G01X1438000Y603100D02*
X1438083Y602767D01*
X1438292Y602517D01*
X1438542Y602350D01*
X1438875Y602225D01*
X1439250Y602183D01*
X1439625Y602225D01*
X1439958Y602350D01*
X1440208Y602517D01*
X1440417Y602767D01*
X1440500Y603100D01*
X1440417Y603433D01*
X1440208Y603683D01*
X1439958Y603850D01*
X1439625Y603975D01*
X1439250Y604017D01*
X1438875Y603975D01*
X1438542Y603850D01*
X1438292Y603683D01*
X1438083Y603433D01*
X1438000Y603100D01*
G01X1440000Y605283D02*
X1440292Y605533D01*
X1440458Y605867D01*
X1440500Y606242D01*
X1440458Y606575D01*
X1440250Y606908D01*
X1440000Y607117D01*
X1439750Y607158D01*
X1439458Y607075D01*
X1439250Y606783D01*
X1439167Y606492D01*
Y606117D01*
G01Y606492D02*
X1439042Y606742D01*
X1438833Y606950D01*
X1438583Y607033D01*
X1438333Y606950D01*
X1438125Y606742D01*
X1438000Y606367D01*
X1438042Y605992D01*
X1438208Y605617D01*
G01X1438131Y570715D02*
Y575915D01*
G01X1445131Y570715D02*
Y578515D01*
G01X1438131Y570715D02*
X1445131D01*
G01X1438131Y584115D02*
Y575415D01*
G01X1445131Y584115D02*
X1438131D01*
G01X1445131Y577715D02*
Y584115D01*
G01X1466483Y567500D02*
Y565708D01*
X1466650Y565333D01*
X1466983Y565083D01*
X1467400Y565000D01*
X1467817Y565083D01*
X1468150Y565333D01*
X1468317Y565708D01*
Y567500D01*
G01X1469708Y567083D02*
X1469958Y567333D01*
X1470250Y567458D01*
X1470583Y567500D01*
X1471000Y567417D01*
X1471292Y567208D01*
X1471375Y566958D01*
X1471333Y566708D01*
X1471167Y566500D01*
X1470333Y566083D01*
X1469958Y565792D01*
X1469708Y565375D01*
X1469625Y565000D01*
X1471375D01*
G01X1474100D02*
Y567500D01*
X1472558Y565708D01*
X1474642D01*
G01X1458187Y565550D02*
Y562550D01*
G01X1442250Y556488D02*
X1444250D01*
G01X1472150Y554520D02*
X1470150D01*
G01X1443350Y558450D02*
Y563450D01*
X1448350D01*
G01X1471050Y558450D02*
Y563450D01*
X1466050D01*
G01X1430200Y565100D02*
Y578100D01*
G01X1473708Y584267D02*
X1473583Y584017D01*
X1473500Y583725D01*
Y583392D01*
X1473625Y583017D01*
X1473833Y582725D01*
X1474083Y582517D01*
X1474500Y582350D01*
X1474875Y582308D01*
X1475250Y582392D01*
X1475500Y582517D01*
X1475750Y582767D01*
X1475917Y583058D01*
X1476000Y583350D01*
Y583642D01*
X1475917Y583933D01*
X1475792Y584183D01*
X1475625Y584392D01*
G01Y585533D02*
X1475833Y585783D01*
X1475958Y586075D01*
X1476000Y586450D01*
X1475917Y586825D01*
X1475750Y587117D01*
X1475458Y587325D01*
X1475125Y587367D01*
X1474792Y587283D01*
X1474583Y587075D01*
X1474417Y586783D01*
X1474375Y586492D01*
X1474417Y586200D01*
X1474583Y585825D01*
X1473500Y585950D01*
Y587075D01*
G01X1474958Y588758D02*
X1474667Y589050D01*
X1474500Y589300D01*
X1474417Y589633D01*
X1474500Y589925D01*
X1474667Y590133D01*
X1474917Y590300D01*
X1475208Y590342D01*
X1475458Y590300D01*
X1475708Y590133D01*
X1475917Y589883D01*
X1476000Y589592D01*
X1475917Y589258D01*
X1475667Y588967D01*
X1475292Y588800D01*
X1474875Y588758D01*
X1474333Y588842D01*
X1474042Y588967D01*
X1473750Y589175D01*
X1473542Y589467D01*
X1473500Y589758D01*
X1473583Y590050D01*
X1473792Y590258D01*
G01X1473500Y592650D02*
X1473583Y592317D01*
X1473792Y592067D01*
X1474042Y591900D01*
X1474375Y591775D01*
X1474750Y591733D01*
X1475125Y591775D01*
X1475458Y591900D01*
X1475708Y592067D01*
X1475917Y592317D01*
X1476000Y592650D01*
X1475917Y592983D01*
X1475708Y593233D01*
X1475458Y593400D01*
X1475125Y593525D01*
X1474750Y593567D01*
X1474375Y593525D01*
X1474042Y593400D01*
X1473792Y593233D01*
X1473583Y592983D01*
X1473500Y592650D01*
G01X1431000Y583967D02*
X1428500D01*
Y585008D01*
X1428625Y585342D01*
X1428792Y585550D01*
X1429125Y585633D01*
X1429458Y585550D01*
X1429667Y585300D01*
X1429792Y585008D01*
Y583967D01*
G01Y585008D02*
X1431000Y585633D01*
G01Y587900D02*
X1428500D01*
X1429000Y587400D01*
G01X1431000D02*
Y588400D01*
G01X1428500Y591000D02*
X1428583Y590667D01*
X1428792Y590417D01*
X1429042Y590250D01*
X1429375Y590125D01*
X1429750Y590083D01*
X1430125Y590125D01*
X1430458Y590250D01*
X1430708Y590417D01*
X1430917Y590667D01*
X1431000Y591000D01*
X1430917Y591333D01*
X1430708Y591583D01*
X1430458Y591750D01*
X1430125Y591875D01*
X1429750Y591917D01*
X1429375Y591875D01*
X1429042Y591750D01*
X1428792Y591583D01*
X1428583Y591333D01*
X1428500Y591000D01*
G01X1431000Y594017D02*
X1430458Y594100D01*
X1430000Y594225D01*
X1429583Y594392D01*
X1429125Y594600D01*
X1428500Y594933D01*
Y593267D01*
G01X1431000Y597200D02*
X1428500D01*
X1429000Y596700D01*
G01X1431000D02*
Y597700D01*
G01X1435200Y560900D02*
X1439200D01*
Y568300D01*
G01X1469908Y584367D02*
X1469783Y584117D01*
X1469700Y583825D01*
Y583492D01*
X1469825Y583117D01*
X1470033Y582825D01*
X1470283Y582617D01*
X1470700Y582450D01*
X1471075Y582408D01*
X1471450Y582492D01*
X1471700Y582617D01*
X1471950Y582867D01*
X1472117Y583158D01*
X1472200Y583450D01*
Y583742D01*
X1472117Y584033D01*
X1471992Y584283D01*
X1471825Y584492D01*
G01Y585633D02*
X1472033Y585883D01*
X1472158Y586175D01*
X1472200Y586550D01*
X1472117Y586925D01*
X1471950Y587217D01*
X1471658Y587425D01*
X1471325Y587467D01*
X1470992Y587383D01*
X1470783Y587175D01*
X1470617Y586883D01*
X1470575Y586592D01*
X1470617Y586300D01*
X1470783Y585925D01*
X1469700Y586050D01*
Y587175D01*
G01X1471825Y588733D02*
X1472033Y588983D01*
X1472158Y589275D01*
X1472200Y589650D01*
X1472117Y590025D01*
X1471950Y590317D01*
X1471658Y590525D01*
X1471325Y590567D01*
X1470992Y590483D01*
X1470783Y590275D01*
X1470617Y589983D01*
X1470575Y589692D01*
X1470617Y589400D01*
X1470783Y589025D01*
X1469700Y589150D01*
Y590275D01*
G01X1472200Y592750D02*
X1472158Y593042D01*
X1472033Y593375D01*
X1471825Y593583D01*
X1471533Y593667D01*
X1471242Y593583D01*
X1470992Y593333D01*
X1470867Y592958D01*
Y592542D01*
X1470783Y592292D01*
X1470575Y592083D01*
X1470283Y592000D01*
X1469992Y592125D01*
X1469783Y592417D01*
X1469700Y592750D01*
X1469783Y593083D01*
X1469992Y593375D01*
X1470283Y593500D01*
X1470575Y593417D01*
X1470783Y593208D01*
X1470867Y592958D01*
Y592542D01*
X1470992Y592167D01*
X1471242Y591917D01*
X1471533Y591833D01*
X1471825Y591917D01*
X1472033Y592125D01*
X1472158Y592458D01*
X1472200Y592750D01*
G01X1463230Y642417D02*
Y644917D01*
X1464271D01*
X1464605Y644792D01*
X1464813Y644625D01*
X1464896Y644292D01*
X1464813Y643959D01*
X1464563Y643750D01*
X1464271Y643625D01*
X1463230D01*
G01X1464271D02*
X1464896Y642417D01*
G01X1466246Y642792D02*
X1466496Y642584D01*
X1466788Y642459D01*
X1467163Y642417D01*
X1467538Y642500D01*
X1467830Y642667D01*
X1468038Y642959D01*
X1468080Y643292D01*
X1467996Y643625D01*
X1467788Y643834D01*
X1467496Y644000D01*
X1467205Y644042D01*
X1466913Y644000D01*
X1466538Y643834D01*
X1466663Y644917D01*
X1467788D01*
G01X1470180Y642417D02*
X1470263Y642959D01*
X1470388Y643417D01*
X1470555Y643834D01*
X1470763Y644292D01*
X1471096Y644917D01*
X1469430D01*
G01X1473863Y642417D02*
Y644917D01*
X1472321Y643125D01*
X1474405D01*
G01X1437913Y641917D02*
Y645917D01*
X1430513D01*
G01X1434213Y616717D02*
X1438213D01*
Y624117D01*
G01X1449517Y621000D02*
Y623500D01*
X1450558D01*
X1450892Y623375D01*
X1451100Y623208D01*
X1451183Y622875D01*
X1451100Y622542D01*
X1450850Y622333D01*
X1450558Y622208D01*
X1449517D01*
G01X1450558D02*
X1451183Y621000D01*
G01X1452533Y621375D02*
X1452783Y621167D01*
X1453075Y621042D01*
X1453450Y621000D01*
X1453825Y621083D01*
X1454117Y621250D01*
X1454325Y621542D01*
X1454367Y621875D01*
X1454283Y622208D01*
X1454075Y622417D01*
X1453783Y622583D01*
X1453492Y622625D01*
X1453200Y622583D01*
X1452825Y622417D01*
X1452950Y623500D01*
X1454075D01*
G01X1456467Y621000D02*
X1456550Y621542D01*
X1456675Y622000D01*
X1456842Y622417D01*
X1457050Y622875D01*
X1457383Y623500D01*
X1455717D01*
G01X1459567Y621000D02*
X1459650Y621542D01*
X1459775Y622000D01*
X1459942Y622417D01*
X1460150Y622875D01*
X1460483Y623500D01*
X1458817D01*
G01X1444213Y616717D02*
X1448213D01*
Y624117D01*
G01X1433713D02*
X1429713D01*
Y616717D01*
G01X1460713Y625334D02*
X1458213D01*
Y626375D01*
X1458338Y626709D01*
X1458505Y626917D01*
X1458838Y627000D01*
X1459171Y626917D01*
X1459380Y626667D01*
X1459505Y626375D01*
Y625334D01*
G01Y626375D02*
X1460713Y627000D01*
G01X1460338Y628350D02*
X1460546Y628600D01*
X1460671Y628892D01*
X1460713Y629267D01*
X1460630Y629642D01*
X1460463Y629934D01*
X1460171Y630142D01*
X1459838Y630184D01*
X1459505Y630100D01*
X1459296Y629892D01*
X1459130Y629600D01*
X1459088Y629309D01*
X1459130Y629017D01*
X1459296Y628642D01*
X1458213Y628767D01*
Y629892D01*
G01X1460713Y632367D02*
X1460671Y632659D01*
X1460546Y632992D01*
X1460338Y633200D01*
X1460046Y633284D01*
X1459755Y633200D01*
X1459505Y632950D01*
X1459380Y632575D01*
Y632159D01*
X1459296Y631909D01*
X1459088Y631700D01*
X1458796Y631617D01*
X1458505Y631742D01*
X1458296Y632034D01*
X1458213Y632367D01*
X1458296Y632700D01*
X1458505Y632992D01*
X1458796Y633117D01*
X1459088Y633034D01*
X1459296Y632825D01*
X1459380Y632575D01*
Y632159D01*
X1459505Y631784D01*
X1459755Y631534D01*
X1460046Y631450D01*
X1460338Y631534D01*
X1460546Y631742D01*
X1460671Y632075D01*
X1460713Y632367D01*
G01Y635467D02*
X1458213D01*
X1458713Y634967D01*
G01X1460713D02*
Y635967D01*
G01X1448713Y629117D02*
X1452713D01*
Y636517D01*
G01X1451513Y649417D02*
Y645417D01*
X1458913D01*
G01X1456793Y625370D02*
X1454293D01*
Y626411D01*
X1454418Y626745D01*
X1454585Y626953D01*
X1454918Y627036D01*
X1455251Y626953D01*
X1455460Y626703D01*
X1455585Y626411D01*
Y625370D01*
G01Y626411D02*
X1456793Y627036D01*
G01X1456418Y628386D02*
X1456626Y628636D01*
X1456751Y628928D01*
X1456793Y629303D01*
X1456710Y629678D01*
X1456543Y629970D01*
X1456251Y630178D01*
X1455918Y630220D01*
X1455585Y630136D01*
X1455376Y629928D01*
X1455210Y629636D01*
X1455168Y629345D01*
X1455210Y629053D01*
X1455376Y628678D01*
X1454293Y628803D01*
Y629928D01*
G01X1456793Y632403D02*
X1456751Y632695D01*
X1456626Y633028D01*
X1456418Y633236D01*
X1456126Y633320D01*
X1455835Y633236D01*
X1455585Y632986D01*
X1455460Y632611D01*
Y632195D01*
X1455376Y631945D01*
X1455168Y631736D01*
X1454876Y631653D01*
X1454585Y631778D01*
X1454376Y632070D01*
X1454293Y632403D01*
X1454376Y632736D01*
X1454585Y633028D01*
X1454876Y633153D01*
X1455168Y633070D01*
X1455376Y632861D01*
X1455460Y632611D01*
Y632195D01*
X1455585Y631820D01*
X1455835Y631570D01*
X1456126Y631486D01*
X1456418Y631570D01*
X1456626Y631778D01*
X1456751Y632111D01*
X1456793Y632403D01*
G01Y636003D02*
X1454293D01*
X1456085Y634461D01*
Y636545D01*
G01X1444013Y629117D02*
X1448013D01*
Y636517D01*
G01X1438413Y625217D02*
Y636617D01*
G01X1460713Y637417D02*
X1444613D01*
G01X1460713Y644417D02*
Y637417D01*
G01X1444613Y644417D02*
X1460713D01*
G01X1444613Y637417D02*
Y644417D01*
G01X1438517Y608500D02*
Y611000D01*
X1439558D01*
X1439892Y610875D01*
X1440100Y610708D01*
X1440183Y610375D01*
X1440100Y610042D01*
X1439850Y609833D01*
X1439558Y609708D01*
X1438517D01*
G01X1439558D02*
X1440183Y608500D01*
G01X1442450D02*
Y611000D01*
X1441950Y610500D01*
G01Y608500D02*
X1442950D01*
G01X1446050D02*
Y611000D01*
X1444508Y609208D01*
X1446592D01*
G01X1449150Y608500D02*
Y611000D01*
X1447608Y609208D01*
X1449692D01*
G01X1453267Y610792D02*
X1453017Y610917D01*
X1452725Y611000D01*
X1452392D01*
X1452017Y610875D01*
X1451725Y610667D01*
X1451517Y610417D01*
X1451350Y610000D01*
X1451308Y609625D01*
X1451392Y609250D01*
X1451517Y609000D01*
X1451767Y608750D01*
X1452058Y608583D01*
X1452350Y608500D01*
X1452642D01*
X1452933Y608583D01*
X1453183Y608708D01*
X1453392Y608875D01*
G01X1454533D02*
X1454783Y608667D01*
X1455075Y608542D01*
X1455450Y608500D01*
X1455825Y608583D01*
X1456117Y608750D01*
X1456325Y609042D01*
X1456367Y609375D01*
X1456283Y609708D01*
X1456075Y609917D01*
X1455783Y610083D01*
X1455492Y610125D01*
X1455200Y610083D01*
X1454825Y609917D01*
X1454950Y611000D01*
X1456075D01*
G01X1457758Y609542D02*
X1458050Y609833D01*
X1458300Y610000D01*
X1458633Y610083D01*
X1458925Y610000D01*
X1459133Y609833D01*
X1459300Y609583D01*
X1459342Y609292D01*
X1459300Y609042D01*
X1459133Y608792D01*
X1458883Y608583D01*
X1458592Y608500D01*
X1458258Y608583D01*
X1457967Y608833D01*
X1457800Y609208D01*
X1457758Y609625D01*
X1457842Y610167D01*
X1457967Y610458D01*
X1458175Y610750D01*
X1458467Y610958D01*
X1458758Y611000D01*
X1459050Y610917D01*
X1459258Y610708D01*
G01X1461650Y608500D02*
X1461942Y608542D01*
X1462275Y608667D01*
X1462483Y608875D01*
X1462567Y609167D01*
X1462483Y609458D01*
X1462233Y609708D01*
X1461858Y609833D01*
X1461442D01*
X1461192Y609917D01*
X1460983Y610125D01*
X1460900Y610417D01*
X1461025Y610708D01*
X1461317Y610917D01*
X1461650Y611000D01*
X1461983Y610917D01*
X1462275Y610708D01*
X1462400Y610417D01*
X1462317Y610125D01*
X1462108Y609917D01*
X1461858Y609833D01*
X1461442D01*
X1461067Y609708D01*
X1460817Y609458D01*
X1460733Y609167D01*
X1460817Y608875D01*
X1461025Y608667D01*
X1461358Y608542D01*
X1461650Y608500D01*
G01X1464980Y648809D02*
X1464730Y648934D01*
X1464438Y649017D01*
X1464105D01*
X1463730Y648892D01*
X1463438Y648684D01*
X1463230Y648434D01*
X1463063Y648017D01*
X1463021Y647642D01*
X1463105Y647267D01*
X1463230Y647017D01*
X1463480Y646767D01*
X1463771Y646600D01*
X1464063Y646517D01*
X1464355D01*
X1464646Y646600D01*
X1464896Y646725D01*
X1465105Y646892D01*
G01X1466371Y648600D02*
X1466621Y648850D01*
X1466913Y648975D01*
X1467246Y649017D01*
X1467663Y648934D01*
X1467955Y648725D01*
X1468038Y648475D01*
X1467996Y648225D01*
X1467830Y648017D01*
X1466996Y647600D01*
X1466621Y647309D01*
X1466371Y646892D01*
X1466288Y646517D01*
X1468038D01*
G01X1469555Y646809D02*
X1469846Y646600D01*
X1470180Y646517D01*
X1470513Y646600D01*
X1470805Y646850D01*
X1471013Y647225D01*
X1471096Y647600D01*
Y648059D01*
X1471013Y648434D01*
X1470805Y648767D01*
X1470555Y648934D01*
X1470263Y649017D01*
X1469930Y648934D01*
X1469680Y648767D01*
X1469513Y648517D01*
X1469430Y648184D01*
X1469513Y647892D01*
X1469721Y647600D01*
X1469971Y647434D01*
X1470263Y647392D01*
X1470596Y647475D01*
X1470846Y647684D01*
X1471096Y648059D01*
G01X1472446Y646892D02*
X1472696Y646684D01*
X1472988Y646559D01*
X1473363Y646517D01*
X1473738Y646600D01*
X1474030Y646767D01*
X1474238Y647059D01*
X1474280Y647392D01*
X1474196Y647725D01*
X1473988Y647934D01*
X1473696Y648100D01*
X1473405Y648142D01*
X1473113Y648100D01*
X1472738Y647934D01*
X1472863Y649017D01*
X1473988D01*
G01X1463230Y674917D02*
Y677417D01*
X1464271D01*
X1464605Y677292D01*
X1464813Y677125D01*
X1464896Y676792D01*
X1464813Y676459D01*
X1464563Y676250D01*
X1464271Y676125D01*
X1463230D01*
G01X1464271D02*
X1464896Y674917D01*
G01X1466246Y675292D02*
X1466496Y675084D01*
X1466788Y674959D01*
X1467163Y674917D01*
X1467538Y675000D01*
X1467830Y675167D01*
X1468038Y675459D01*
X1468080Y675792D01*
X1467996Y676125D01*
X1467788Y676334D01*
X1467496Y676500D01*
X1467205Y676542D01*
X1466913Y676500D01*
X1466538Y676334D01*
X1466663Y677417D01*
X1467788D01*
G01X1470263Y674917D02*
X1470555Y674959D01*
X1470888Y675084D01*
X1471096Y675292D01*
X1471180Y675584D01*
X1471096Y675875D01*
X1470846Y676125D01*
X1470471Y676250D01*
X1470055D01*
X1469805Y676334D01*
X1469596Y676542D01*
X1469513Y676834D01*
X1469638Y677125D01*
X1469930Y677334D01*
X1470263Y677417D01*
X1470596Y677334D01*
X1470888Y677125D01*
X1471013Y676834D01*
X1470930Y676542D01*
X1470721Y676334D01*
X1470471Y676250D01*
X1470055D01*
X1469680Y676125D01*
X1469430Y675875D01*
X1469346Y675584D01*
X1469430Y675292D01*
X1469638Y675084D01*
X1469971Y674959D01*
X1470263Y674917D01*
G01X1472571Y677000D02*
X1472821Y677250D01*
X1473113Y677375D01*
X1473446Y677417D01*
X1473863Y677334D01*
X1474155Y677125D01*
X1474238Y676875D01*
X1474196Y676625D01*
X1474030Y676417D01*
X1473196Y676000D01*
X1472821Y675709D01*
X1472571Y675292D01*
X1472488Y674917D01*
X1474238D01*
G01X1461413Y674417D02*
Y678417D01*
X1454013D01*
G01X1439513Y698917D02*
X1441613Y697117D01*
X1439513Y694917D01*
G01X1439413Y691317D02*
X1458613D01*
Y702517D01*
X1439413D01*
Y691317D01*
X1439813D01*
G01X1429350Y673500D02*
X1429017Y673542D01*
X1428725Y673708D01*
X1428475Y673958D01*
X1428308Y674250D01*
X1428225Y674583D01*
Y674917D01*
X1428308Y675250D01*
X1428475Y675542D01*
X1428725Y675792D01*
X1429017Y675958D01*
X1429350Y676000D01*
X1429683Y675958D01*
X1429975Y675792D01*
X1430225Y675542D01*
X1430392Y675250D01*
X1430475Y674917D01*
Y674583D01*
X1430392Y674250D01*
X1430225Y673958D01*
X1429975Y673708D01*
X1429683Y673542D01*
X1429350Y673500D01*
G01X1429683Y674167D02*
X1430183Y673500D01*
G01X1432450D02*
Y676000D01*
X1431950Y675500D01*
G01Y673500D02*
X1432950D01*
G01X1435550D02*
Y676000D01*
X1435050Y675500D01*
G01Y673500D02*
X1436050D01*
G01X1437733Y674000D02*
X1437983Y673708D01*
X1438317Y673542D01*
X1438692Y673500D01*
X1439025Y673542D01*
X1439358Y673750D01*
X1439567Y674000D01*
X1439608Y674250D01*
X1439525Y674542D01*
X1439233Y674750D01*
X1438942Y674833D01*
X1438567D01*
G01X1438942D02*
X1439192Y674958D01*
X1439400Y675167D01*
X1439483Y675417D01*
X1439400Y675667D01*
X1439192Y675875D01*
X1438817Y676000D01*
X1438442Y675958D01*
X1438067Y675792D01*
G01X1444713Y671617D02*
X1442913Y669517D01*
X1440713Y671617D01*
G01X1437113Y671717D02*
Y652517D01*
X1448313D01*
Y671717D01*
X1437113D01*
Y671317D01*
G01X1464980Y681309D02*
X1464730Y681434D01*
X1464438Y681517D01*
X1464105D01*
X1463730Y681392D01*
X1463438Y681184D01*
X1463230Y680934D01*
X1463063Y680517D01*
X1463021Y680142D01*
X1463105Y679767D01*
X1463230Y679517D01*
X1463480Y679267D01*
X1463771Y679100D01*
X1464063Y679017D01*
X1464355D01*
X1464646Y679100D01*
X1464896Y679225D01*
X1465105Y679392D01*
G01X1466371Y681100D02*
X1466621Y681350D01*
X1466913Y681475D01*
X1467246Y681517D01*
X1467663Y681434D01*
X1467955Y681225D01*
X1468038Y680975D01*
X1467996Y680725D01*
X1467830Y680517D01*
X1466996Y680100D01*
X1466621Y679809D01*
X1466371Y679392D01*
X1466288Y679017D01*
X1468038D01*
G01X1469555Y679309D02*
X1469846Y679100D01*
X1470180Y679017D01*
X1470513Y679100D01*
X1470805Y679350D01*
X1471013Y679725D01*
X1471096Y680100D01*
Y680559D01*
X1471013Y680934D01*
X1470805Y681267D01*
X1470555Y681434D01*
X1470263Y681517D01*
X1469930Y681434D01*
X1469680Y681267D01*
X1469513Y681017D01*
X1469430Y680684D01*
X1469513Y680392D01*
X1469721Y680100D01*
X1469971Y679934D01*
X1470263Y679892D01*
X1470596Y679975D01*
X1470846Y680184D01*
X1471096Y680559D01*
G01X1472571Y680059D02*
X1472863Y680350D01*
X1473113Y680517D01*
X1473446Y680600D01*
X1473738Y680517D01*
X1473946Y680350D01*
X1474113Y680100D01*
X1474155Y679809D01*
X1474113Y679559D01*
X1473946Y679309D01*
X1473696Y679100D01*
X1473405Y679017D01*
X1473071Y679100D01*
X1472780Y679350D01*
X1472613Y679725D01*
X1472571Y680142D01*
X1472655Y680684D01*
X1472780Y680975D01*
X1472988Y681267D01*
X1473280Y681475D01*
X1473571Y681517D01*
X1473863Y681434D01*
X1474071Y681225D01*
G01X1440017Y718500D02*
Y721000D01*
X1441058D01*
X1441392Y720875D01*
X1441600Y720708D01*
X1441683Y720375D01*
X1441600Y720042D01*
X1441350Y719833D01*
X1441058Y719708D01*
X1440017D01*
G01X1441058D02*
X1441683Y718500D01*
G01X1443033Y718875D02*
X1443283Y718667D01*
X1443575Y718542D01*
X1443950Y718500D01*
X1444325Y718583D01*
X1444617Y718750D01*
X1444825Y719042D01*
X1444867Y719375D01*
X1444783Y719708D01*
X1444575Y719917D01*
X1444283Y720083D01*
X1443992Y720125D01*
X1443700Y720083D01*
X1443325Y719917D01*
X1443450Y721000D01*
X1444575D01*
G01X1446258Y719542D02*
X1446550Y719833D01*
X1446800Y720000D01*
X1447133Y720083D01*
X1447425Y720000D01*
X1447633Y719833D01*
X1447800Y719583D01*
X1447842Y719292D01*
X1447800Y719042D01*
X1447633Y718792D01*
X1447383Y718583D01*
X1447092Y718500D01*
X1446758Y718583D01*
X1446467Y718833D01*
X1446300Y719208D01*
X1446258Y719625D01*
X1446342Y720167D01*
X1446467Y720458D01*
X1446675Y720750D01*
X1446967Y720958D01*
X1447258Y721000D01*
X1447550Y720917D01*
X1447758Y720708D01*
G01X1450150Y718500D02*
X1450442Y718542D01*
X1450775Y718667D01*
X1450983Y718875D01*
X1451067Y719167D01*
X1450983Y719458D01*
X1450733Y719708D01*
X1450358Y719833D01*
X1449942D01*
X1449692Y719917D01*
X1449483Y720125D01*
X1449400Y720417D01*
X1449525Y720708D01*
X1449817Y720917D01*
X1450150Y721000D01*
X1450483Y720917D01*
X1450775Y720708D01*
X1450900Y720417D01*
X1450817Y720125D01*
X1450608Y719917D01*
X1450358Y719833D01*
X1449942D01*
X1449567Y719708D01*
X1449317Y719458D01*
X1449233Y719167D01*
X1449317Y718875D01*
X1449525Y718667D01*
X1449858Y718542D01*
X1450150Y718500D01*
G01X1446465Y730005D02*
Y722005D01*
X1428865D01*
Y730005D01*
X1446465D01*
G01X1449708Y741767D02*
X1449583Y741517D01*
X1449500Y741225D01*
Y740892D01*
X1449625Y740517D01*
X1449833Y740225D01*
X1450083Y740017D01*
X1450500Y739850D01*
X1450875Y739808D01*
X1451250Y739892D01*
X1451500Y740017D01*
X1451750Y740267D01*
X1451917Y740558D01*
X1452000Y740850D01*
Y741142D01*
X1451917Y741433D01*
X1451792Y741683D01*
X1451625Y741892D01*
G01X1449917Y743158D02*
X1449667Y743408D01*
X1449542Y743700D01*
X1449500Y744033D01*
X1449583Y744450D01*
X1449792Y744742D01*
X1450042Y744825D01*
X1450292Y744783D01*
X1450500Y744617D01*
X1450917Y743783D01*
X1451208Y743408D01*
X1451625Y743158D01*
X1452000Y743075D01*
Y744825D01*
G01X1451708Y746342D02*
X1451917Y746633D01*
X1452000Y746967D01*
X1451917Y747300D01*
X1451667Y747592D01*
X1451292Y747800D01*
X1450917Y747883D01*
X1450458D01*
X1450083Y747800D01*
X1449750Y747592D01*
X1449583Y747342D01*
X1449500Y747050D01*
X1449583Y746717D01*
X1449750Y746467D01*
X1450000Y746300D01*
X1450333Y746217D01*
X1450625Y746300D01*
X1450917Y746508D01*
X1451083Y746758D01*
X1451125Y747050D01*
X1451042Y747383D01*
X1450833Y747633D01*
X1450458Y747883D01*
G01X1449917Y749358D02*
X1449667Y749608D01*
X1449542Y749900D01*
X1449500Y750233D01*
X1449583Y750650D01*
X1449792Y750942D01*
X1450042Y751025D01*
X1450292Y750983D01*
X1450500Y750817D01*
X1450917Y749983D01*
X1451208Y749608D01*
X1451625Y749358D01*
X1452000Y749275D01*
Y751025D01*
G01X1445708Y741767D02*
X1445583Y741517D01*
X1445500Y741225D01*
Y740892D01*
X1445625Y740517D01*
X1445833Y740225D01*
X1446083Y740017D01*
X1446500Y739850D01*
X1446875Y739808D01*
X1447250Y739892D01*
X1447500Y740017D01*
X1447750Y740267D01*
X1447917Y740558D01*
X1448000Y740850D01*
Y741142D01*
X1447917Y741433D01*
X1447792Y741683D01*
X1447625Y741892D01*
G01X1445917Y743158D02*
X1445667Y743408D01*
X1445542Y743700D01*
X1445500Y744033D01*
X1445583Y744450D01*
X1445792Y744742D01*
X1446042Y744825D01*
X1446292Y744783D01*
X1446500Y744617D01*
X1446917Y743783D01*
X1447208Y743408D01*
X1447625Y743158D01*
X1448000Y743075D01*
Y744825D01*
G01X1447708Y746342D02*
X1447917Y746633D01*
X1448000Y746967D01*
X1447917Y747300D01*
X1447667Y747592D01*
X1447292Y747800D01*
X1446917Y747883D01*
X1446458D01*
X1446083Y747800D01*
X1445750Y747592D01*
X1445583Y747342D01*
X1445500Y747050D01*
X1445583Y746717D01*
X1445750Y746467D01*
X1446000Y746300D01*
X1446333Y746217D01*
X1446625Y746300D01*
X1446917Y746508D01*
X1447083Y746758D01*
X1447125Y747050D01*
X1447042Y747383D01*
X1446833Y747633D01*
X1446458Y747883D01*
G01X1448000Y750150D02*
X1445500D01*
X1446000Y749650D01*
G01X1448000D02*
Y750650D01*
G01X1428713Y703117D02*
Y708617D01*
G01X1436713Y703117D02*
X1428713D01*
G01X1436713Y708617D02*
Y703117D01*
G01Y720717D02*
Y715217D01*
G01X1428713Y720717D02*
X1436713D01*
G01X1428713Y715217D02*
Y720717D01*
G01X1451350Y712000D02*
X1451017Y712042D01*
X1450725Y712208D01*
X1450475Y712458D01*
X1450308Y712750D01*
X1450225Y713083D01*
Y713417D01*
X1450308Y713750D01*
X1450475Y714042D01*
X1450725Y714292D01*
X1451017Y714458D01*
X1451350Y714500D01*
X1451683Y714458D01*
X1451975Y714292D01*
X1452225Y714042D01*
X1452392Y713750D01*
X1452475Y713417D01*
Y713083D01*
X1452392Y712750D01*
X1452225Y712458D01*
X1451975Y712208D01*
X1451683Y712042D01*
X1451350Y712000D01*
G01X1451683Y712667D02*
X1452183Y712000D01*
G01X1454450D02*
Y714500D01*
X1453950Y714000D01*
G01Y712000D02*
X1454950D01*
G01X1457550D02*
Y714500D01*
X1457050Y714000D01*
G01Y712000D02*
X1458050D01*
G01X1459858Y713042D02*
X1460150Y713333D01*
X1460400Y713500D01*
X1460733Y713583D01*
X1461025Y713500D01*
X1461233Y713333D01*
X1461400Y713083D01*
X1461442Y712792D01*
X1461400Y712542D01*
X1461233Y712292D01*
X1460983Y712083D01*
X1460692Y712000D01*
X1460358Y712083D01*
X1460067Y712333D01*
X1459900Y712708D01*
X1459858Y713125D01*
X1459942Y713667D01*
X1460067Y713958D01*
X1460275Y714250D01*
X1460567Y714458D01*
X1460858Y714500D01*
X1461150Y714417D01*
X1461358Y714208D01*
G01X1441708Y741767D02*
X1441583Y741517D01*
X1441500Y741225D01*
Y740892D01*
X1441625Y740517D01*
X1441833Y740225D01*
X1442083Y740017D01*
X1442500Y739850D01*
X1442875Y739808D01*
X1443250Y739892D01*
X1443500Y740017D01*
X1443750Y740267D01*
X1443917Y740558D01*
X1444000Y740850D01*
Y741142D01*
X1443917Y741433D01*
X1443792Y741683D01*
X1443625Y741892D01*
G01X1441917Y743158D02*
X1441667Y743408D01*
X1441542Y743700D01*
X1441500Y744033D01*
X1441583Y744450D01*
X1441792Y744742D01*
X1442042Y744825D01*
X1442292Y744783D01*
X1442500Y744617D01*
X1442917Y743783D01*
X1443208Y743408D01*
X1443625Y743158D01*
X1444000Y743075D01*
Y744825D01*
G01X1443708Y746342D02*
X1443917Y746633D01*
X1444000Y746967D01*
X1443917Y747300D01*
X1443667Y747592D01*
X1443292Y747800D01*
X1442917Y747883D01*
X1442458D01*
X1442083Y747800D01*
X1441750Y747592D01*
X1441583Y747342D01*
X1441500Y747050D01*
X1441583Y746717D01*
X1441750Y746467D01*
X1442000Y746300D01*
X1442333Y746217D01*
X1442625Y746300D01*
X1442917Y746508D01*
X1443083Y746758D01*
X1443125Y747050D01*
X1443042Y747383D01*
X1442833Y747633D01*
X1442458Y747883D01*
G01X1444000Y750650D02*
X1441500D01*
X1443292Y749108D01*
Y751192D01*
G01X1470275Y972263D02*
Y974763D01*
X1471316D01*
X1471650Y974638D01*
X1471858Y974471D01*
X1471941Y974138D01*
X1471858Y973805D01*
X1471608Y973596D01*
X1471316Y973471D01*
X1470275D01*
G01X1471316D02*
X1471941Y972263D01*
G01X1474708D02*
Y974763D01*
X1473166Y972971D01*
X1475250D01*
G01X1477308Y972263D02*
X1477600Y972305D01*
X1477933Y972430D01*
X1478141Y972638D01*
X1478225Y972930D01*
X1478141Y973221D01*
X1477891Y973471D01*
X1477516Y973596D01*
X1477100D01*
X1476850Y973680D01*
X1476641Y973888D01*
X1476558Y974180D01*
X1476683Y974471D01*
X1476975Y974680D01*
X1477308Y974763D01*
X1477641Y974680D01*
X1477933Y974471D01*
X1478058Y974180D01*
X1477975Y973888D01*
X1477766Y973680D01*
X1477516Y973596D01*
X1477100D01*
X1476725Y973471D01*
X1476475Y973221D01*
X1476391Y972930D01*
X1476475Y972638D01*
X1476683Y972430D01*
X1477016Y972305D01*
X1477308Y972263D01*
G01X1479616Y973305D02*
X1479908Y973596D01*
X1480158Y973763D01*
X1480491Y973846D01*
X1480783Y973763D01*
X1480991Y973596D01*
X1481158Y973346D01*
X1481200Y973055D01*
X1481158Y972805D01*
X1480991Y972555D01*
X1480741Y972346D01*
X1480450Y972263D01*
X1480116Y972346D01*
X1479825Y972596D01*
X1479658Y972971D01*
X1479616Y973388D01*
X1479700Y973930D01*
X1479825Y974221D01*
X1480033Y974513D01*
X1480325Y974721D01*
X1480616Y974763D01*
X1480908Y974680D01*
X1481116Y974471D01*
G01X1478458Y963763D02*
Y967763D01*
X1471058D01*
G01X1456234Y972383D02*
Y974883D01*
X1457275D01*
X1457609Y974758D01*
X1457817Y974591D01*
X1457900Y974258D01*
X1457817Y973925D01*
X1457567Y973716D01*
X1457275Y973591D01*
X1456234D01*
G01X1457275D02*
X1457900Y972383D01*
G01X1460667D02*
Y974883D01*
X1459125Y973091D01*
X1461209D01*
G01X1463267Y972383D02*
X1463559Y972425D01*
X1463892Y972550D01*
X1464100Y972758D01*
X1464184Y973050D01*
X1464100Y973341D01*
X1463850Y973591D01*
X1463475Y973716D01*
X1463059D01*
X1462809Y973800D01*
X1462600Y974008D01*
X1462517Y974300D01*
X1462642Y974591D01*
X1462934Y974800D01*
X1463267Y974883D01*
X1463600Y974800D01*
X1463892Y974591D01*
X1464017Y974300D01*
X1463934Y974008D01*
X1463725Y973800D01*
X1463475Y973716D01*
X1463059D01*
X1462684Y973591D01*
X1462434Y973341D01*
X1462350Y973050D01*
X1462434Y972758D01*
X1462642Y972550D01*
X1462975Y972425D01*
X1463267Y972383D01*
G01X1466867D02*
Y974883D01*
X1465325Y973091D01*
X1467409D01*
G01X1464417Y963883D02*
Y967883D01*
X1457017D01*
G01X1458173Y944861D02*
X1457840Y944903D01*
X1457548Y945069D01*
X1457298Y945319D01*
X1457131Y945611D01*
X1457048Y945944D01*
Y946278D01*
X1457131Y946611D01*
X1457298Y946903D01*
X1457548Y947153D01*
X1457840Y947319D01*
X1458173Y947361D01*
X1458506Y947319D01*
X1458798Y947153D01*
X1459048Y946903D01*
X1459215Y946611D01*
X1459298Y946278D01*
Y945944D01*
X1459215Y945611D01*
X1459048Y945319D01*
X1458798Y945069D01*
X1458506Y944903D01*
X1458173Y944861D01*
G01X1458506Y945528D02*
X1459006Y944861D01*
G01X1460481Y946944D02*
X1460731Y947194D01*
X1461023Y947319D01*
X1461356Y947361D01*
X1461773Y947278D01*
X1462065Y947069D01*
X1462148Y946819D01*
X1462106Y946569D01*
X1461940Y946361D01*
X1461106Y945944D01*
X1460731Y945653D01*
X1460481Y945236D01*
X1460398Y944861D01*
X1462148D01*
G01X1464290D02*
X1464373Y945403D01*
X1464498Y945861D01*
X1464665Y946278D01*
X1464873Y946736D01*
X1465206Y947361D01*
X1463540D01*
G01X1467473Y944861D02*
Y947361D01*
X1466973Y946861D01*
G01Y944861D02*
X1467973D01*
G01X1469323Y948861D02*
Y962861D01*
G01X1456323Y948861D02*
X1469323D01*
G01X1456323Y962861D02*
Y948861D01*
G01X1469323Y962861D02*
X1456323D01*
G01X1472365Y944902D02*
X1472032Y944944D01*
X1471740Y945110D01*
X1471490Y945360D01*
X1471323Y945652D01*
X1471240Y945985D01*
Y946319D01*
X1471323Y946652D01*
X1471490Y946944D01*
X1471740Y947194D01*
X1472032Y947360D01*
X1472365Y947402D01*
X1472698Y947360D01*
X1472990Y947194D01*
X1473240Y946944D01*
X1473407Y946652D01*
X1473490Y946319D01*
Y945985D01*
X1473407Y945652D01*
X1473240Y945360D01*
X1472990Y945110D01*
X1472698Y944944D01*
X1472365Y944902D01*
G01X1472698Y945569D02*
X1473198Y944902D01*
G01X1474673Y946985D02*
X1474923Y947235D01*
X1475215Y947360D01*
X1475548Y947402D01*
X1475965Y947319D01*
X1476257Y947110D01*
X1476340Y946860D01*
X1476298Y946610D01*
X1476132Y946402D01*
X1475298Y945985D01*
X1474923Y945694D01*
X1474673Y945277D01*
X1474590Y944902D01*
X1476340D01*
G01X1477648Y945402D02*
X1477898Y945110D01*
X1478232Y944944D01*
X1478607Y944902D01*
X1478940Y944944D01*
X1479273Y945152D01*
X1479482Y945402D01*
X1479523Y945652D01*
X1479440Y945944D01*
X1479148Y946152D01*
X1478857Y946235D01*
X1478482D01*
G01X1478857D02*
X1479107Y946360D01*
X1479315Y946569D01*
X1479398Y946819D01*
X1479315Y947069D01*
X1479107Y947277D01*
X1478732Y947402D01*
X1478357Y947360D01*
X1477982Y947194D01*
G01X1480748Y945277D02*
X1480998Y945069D01*
X1481290Y944944D01*
X1481665Y944902D01*
X1482040Y944985D01*
X1482332Y945152D01*
X1482540Y945444D01*
X1482582Y945777D01*
X1482498Y946110D01*
X1482290Y946319D01*
X1481998Y946485D01*
X1481707Y946527D01*
X1481415Y946485D01*
X1481040Y946319D01*
X1481165Y947402D01*
X1482290D01*
G01X1470515Y948902D02*
X1483515D01*
G01X1470515Y962902D02*
Y948902D01*
G01X1483515Y962902D02*
X1470515D01*
G01X1461213Y1077090D02*
X1458713D01*
Y1078131D01*
X1458838Y1078465D01*
X1459005Y1078673D01*
X1459338Y1078756D01*
X1459671Y1078673D01*
X1459880Y1078423D01*
X1460005Y1078131D01*
Y1077090D01*
G01Y1078131D02*
X1461213Y1078756D01*
G01X1460713Y1080106D02*
X1461005Y1080356D01*
X1461171Y1080690D01*
X1461213Y1081065D01*
X1461171Y1081398D01*
X1460963Y1081731D01*
X1460713Y1081940D01*
X1460463Y1081981D01*
X1460171Y1081898D01*
X1459963Y1081606D01*
X1459880Y1081315D01*
Y1080940D01*
G01Y1081315D02*
X1459755Y1081565D01*
X1459546Y1081773D01*
X1459296Y1081856D01*
X1459046Y1081773D01*
X1458838Y1081565D01*
X1458713Y1081190D01*
X1458755Y1080815D01*
X1458921Y1080440D01*
G01X1458713Y1084123D02*
X1458796Y1083790D01*
X1459005Y1083540D01*
X1459255Y1083373D01*
X1459588Y1083248D01*
X1459963Y1083206D01*
X1460338Y1083248D01*
X1460671Y1083373D01*
X1460921Y1083540D01*
X1461130Y1083790D01*
X1461213Y1084123D01*
X1461130Y1084456D01*
X1460921Y1084706D01*
X1460671Y1084873D01*
X1460338Y1084998D01*
X1459963Y1085040D01*
X1459588Y1084998D01*
X1459255Y1084873D01*
X1459005Y1084706D01*
X1458796Y1084456D01*
X1458713Y1084123D01*
G01X1460838Y1086306D02*
X1461046Y1086556D01*
X1461171Y1086848D01*
X1461213Y1087223D01*
X1461130Y1087598D01*
X1460963Y1087890D01*
X1460671Y1088098D01*
X1460338Y1088140D01*
X1460005Y1088056D01*
X1459796Y1087848D01*
X1459630Y1087556D01*
X1459588Y1087265D01*
X1459630Y1086973D01*
X1459796Y1086598D01*
X1458713Y1086723D01*
Y1087848D01*
G01X1448713Y1081873D02*
X1452713D01*
Y1089273D01*
G01X1456513Y1077090D02*
X1454013D01*
Y1078131D01*
X1454138Y1078465D01*
X1454305Y1078673D01*
X1454638Y1078756D01*
X1454971Y1078673D01*
X1455180Y1078423D01*
X1455305Y1078131D01*
Y1077090D01*
G01Y1078131D02*
X1456513Y1078756D01*
G01X1456013Y1080106D02*
X1456305Y1080356D01*
X1456471Y1080690D01*
X1456513Y1081065D01*
X1456471Y1081398D01*
X1456263Y1081731D01*
X1456013Y1081940D01*
X1455763Y1081981D01*
X1455471Y1081898D01*
X1455263Y1081606D01*
X1455180Y1081315D01*
Y1080940D01*
G01Y1081315D02*
X1455055Y1081565D01*
X1454846Y1081773D01*
X1454596Y1081856D01*
X1454346Y1081773D01*
X1454138Y1081565D01*
X1454013Y1081190D01*
X1454055Y1080815D01*
X1454221Y1080440D01*
G01X1454013Y1084123D02*
X1454096Y1083790D01*
X1454305Y1083540D01*
X1454555Y1083373D01*
X1454888Y1083248D01*
X1455263Y1083206D01*
X1455638Y1083248D01*
X1455971Y1083373D01*
X1456221Y1083540D01*
X1456430Y1083790D01*
X1456513Y1084123D01*
X1456430Y1084456D01*
X1456221Y1084706D01*
X1455971Y1084873D01*
X1455638Y1084998D01*
X1455263Y1085040D01*
X1454888Y1084998D01*
X1454555Y1084873D01*
X1454305Y1084706D01*
X1454096Y1084456D01*
X1454013Y1084123D01*
G01X1456513Y1087223D02*
X1456471Y1087515D01*
X1456346Y1087848D01*
X1456138Y1088056D01*
X1455846Y1088140D01*
X1455555Y1088056D01*
X1455305Y1087806D01*
X1455180Y1087431D01*
Y1087015D01*
X1455096Y1086765D01*
X1454888Y1086556D01*
X1454596Y1086473D01*
X1454305Y1086598D01*
X1454096Y1086890D01*
X1454013Y1087223D01*
X1454096Y1087556D01*
X1454305Y1087848D01*
X1454596Y1087973D01*
X1454888Y1087890D01*
X1455096Y1087681D01*
X1455180Y1087431D01*
Y1087015D01*
X1455305Y1086640D01*
X1455555Y1086390D01*
X1455846Y1086306D01*
X1456138Y1086390D01*
X1456346Y1086598D01*
X1456471Y1086931D01*
X1456513Y1087223D01*
G01X1444013Y1081873D02*
X1448013D01*
Y1089273D01*
G01X1437213Y1055190D02*
X1434713D01*
Y1056231D01*
X1434838Y1056565D01*
X1435005Y1056773D01*
X1435338Y1056856D01*
X1435671Y1056773D01*
X1435880Y1056523D01*
X1436005Y1056231D01*
Y1055190D01*
G01Y1056231D02*
X1437213Y1056856D01*
G01X1435130Y1058331D02*
X1434880Y1058581D01*
X1434755Y1058873D01*
X1434713Y1059206D01*
X1434796Y1059623D01*
X1435005Y1059915D01*
X1435255Y1059998D01*
X1435505Y1059956D01*
X1435713Y1059790D01*
X1436130Y1058956D01*
X1436421Y1058581D01*
X1436838Y1058331D01*
X1437213Y1058248D01*
Y1059998D01*
G01X1436921Y1061515D02*
X1437130Y1061806D01*
X1437213Y1062140D01*
X1437130Y1062473D01*
X1436880Y1062765D01*
X1436505Y1062973D01*
X1436130Y1063056D01*
X1435671D01*
X1435296Y1062973D01*
X1434963Y1062765D01*
X1434796Y1062515D01*
X1434713Y1062223D01*
X1434796Y1061890D01*
X1434963Y1061640D01*
X1435213Y1061473D01*
X1435546Y1061390D01*
X1435838Y1061473D01*
X1436130Y1061681D01*
X1436296Y1061931D01*
X1436338Y1062223D01*
X1436255Y1062556D01*
X1436046Y1062806D01*
X1435671Y1063056D01*
G01X1436921Y1064615D02*
X1437130Y1064906D01*
X1437213Y1065240D01*
X1437130Y1065573D01*
X1436880Y1065865D01*
X1436505Y1066073D01*
X1436130Y1066156D01*
X1435671D01*
X1435296Y1066073D01*
X1434963Y1065865D01*
X1434796Y1065615D01*
X1434713Y1065323D01*
X1434796Y1064990D01*
X1434963Y1064740D01*
X1435213Y1064573D01*
X1435546Y1064490D01*
X1435838Y1064573D01*
X1436130Y1064781D01*
X1436296Y1065031D01*
X1436338Y1065323D01*
X1436255Y1065656D01*
X1436046Y1065906D01*
X1435671Y1066156D01*
G01X1434213Y1069473D02*
X1438213D01*
Y1076873D01*
G01X1452500Y1066517D02*
X1450000D01*
Y1067558D01*
X1450125Y1067892D01*
X1450292Y1068100D01*
X1450625Y1068183D01*
X1450958Y1068100D01*
X1451167Y1067850D01*
X1451292Y1067558D01*
Y1066517D01*
G01Y1067558D02*
X1452500Y1068183D01*
G01X1452000Y1069533D02*
X1452292Y1069783D01*
X1452458Y1070117D01*
X1452500Y1070492D01*
X1452458Y1070825D01*
X1452250Y1071158D01*
X1452000Y1071367D01*
X1451750Y1071408D01*
X1451458Y1071325D01*
X1451250Y1071033D01*
X1451167Y1070742D01*
Y1070367D01*
G01Y1070742D02*
X1451042Y1070992D01*
X1450833Y1071200D01*
X1450583Y1071283D01*
X1450333Y1071200D01*
X1450125Y1070992D01*
X1450000Y1070617D01*
X1450042Y1070242D01*
X1450208Y1069867D01*
G01X1450000Y1073550D02*
X1450083Y1073217D01*
X1450292Y1072967D01*
X1450542Y1072800D01*
X1450875Y1072675D01*
X1451250Y1072633D01*
X1451625Y1072675D01*
X1451958Y1072800D01*
X1452208Y1072967D01*
X1452417Y1073217D01*
X1452500Y1073550D01*
X1452417Y1073883D01*
X1452208Y1074133D01*
X1451958Y1074300D01*
X1451625Y1074425D01*
X1451250Y1074467D01*
X1450875Y1074425D01*
X1450542Y1074300D01*
X1450292Y1074133D01*
X1450083Y1073883D01*
X1450000Y1073550D01*
G01X1450417Y1075858D02*
X1450167Y1076108D01*
X1450042Y1076400D01*
X1450000Y1076733D01*
X1450083Y1077150D01*
X1450292Y1077442D01*
X1450542Y1077525D01*
X1450792Y1077483D01*
X1451000Y1077317D01*
X1451417Y1076483D01*
X1451708Y1076108D01*
X1452125Y1075858D01*
X1452500Y1075775D01*
Y1077525D01*
G01X1444213Y1069473D02*
X1448213D01*
Y1076873D01*
G01X1432713Y1055190D02*
X1430213D01*
Y1056231D01*
X1430338Y1056565D01*
X1430505Y1056773D01*
X1430838Y1056856D01*
X1431171Y1056773D01*
X1431380Y1056523D01*
X1431505Y1056231D01*
Y1055190D01*
G01Y1056231D02*
X1432713Y1056856D01*
G01X1432213Y1058206D02*
X1432505Y1058456D01*
X1432671Y1058790D01*
X1432713Y1059165D01*
X1432671Y1059498D01*
X1432463Y1059831D01*
X1432213Y1060040D01*
X1431963Y1060081D01*
X1431671Y1059998D01*
X1431463Y1059706D01*
X1431380Y1059415D01*
Y1059040D01*
G01Y1059415D02*
X1431255Y1059665D01*
X1431046Y1059873D01*
X1430796Y1059956D01*
X1430546Y1059873D01*
X1430338Y1059665D01*
X1430213Y1059290D01*
X1430255Y1058915D01*
X1430421Y1058540D01*
G01X1430213Y1062223D02*
X1430296Y1061890D01*
X1430505Y1061640D01*
X1430755Y1061473D01*
X1431088Y1061348D01*
X1431463Y1061306D01*
X1431838Y1061348D01*
X1432171Y1061473D01*
X1432421Y1061640D01*
X1432630Y1061890D01*
X1432713Y1062223D01*
X1432630Y1062556D01*
X1432421Y1062806D01*
X1432171Y1062973D01*
X1431838Y1063098D01*
X1431463Y1063140D01*
X1431088Y1063098D01*
X1430755Y1062973D01*
X1430505Y1062806D01*
X1430296Y1062556D01*
X1430213Y1062223D01*
G01X1432713Y1065823D02*
X1430213D01*
X1432005Y1064281D01*
Y1066365D01*
G01X1433713Y1076873D02*
X1429713D01*
Y1069473D01*
G01X1438413Y1077973D02*
Y1089373D01*
G01X1451513Y1102173D02*
Y1098173D01*
X1458913D01*
G01X1462730Y1128173D02*
Y1130673D01*
X1463771D01*
X1464105Y1130548D01*
X1464313Y1130381D01*
X1464396Y1130048D01*
X1464313Y1129715D01*
X1464063Y1129506D01*
X1463771Y1129381D01*
X1462730D01*
G01X1463771D02*
X1464396Y1128173D01*
G01X1465746Y1128673D02*
X1465996Y1128381D01*
X1466330Y1128215D01*
X1466705Y1128173D01*
X1467038Y1128215D01*
X1467371Y1128423D01*
X1467580Y1128673D01*
X1467621Y1128923D01*
X1467538Y1129215D01*
X1467246Y1129423D01*
X1466955Y1129506D01*
X1466580D01*
G01X1466955D02*
X1467205Y1129631D01*
X1467413Y1129840D01*
X1467496Y1130090D01*
X1467413Y1130340D01*
X1467205Y1130548D01*
X1466830Y1130673D01*
X1466455Y1130631D01*
X1466080Y1130465D01*
G01X1469763Y1130673D02*
X1469430Y1130590D01*
X1469180Y1130381D01*
X1469013Y1130131D01*
X1468888Y1129798D01*
X1468846Y1129423D01*
X1468888Y1129048D01*
X1469013Y1128715D01*
X1469180Y1128465D01*
X1469430Y1128256D01*
X1469763Y1128173D01*
X1470096Y1128256D01*
X1470346Y1128465D01*
X1470513Y1128715D01*
X1470638Y1129048D01*
X1470680Y1129423D01*
X1470638Y1129798D01*
X1470513Y1130131D01*
X1470346Y1130381D01*
X1470096Y1130590D01*
X1469763Y1130673D01*
G01X1472071Y1129215D02*
X1472363Y1129506D01*
X1472613Y1129673D01*
X1472946Y1129756D01*
X1473238Y1129673D01*
X1473446Y1129506D01*
X1473613Y1129256D01*
X1473655Y1128965D01*
X1473613Y1128715D01*
X1473446Y1128465D01*
X1473196Y1128256D01*
X1472905Y1128173D01*
X1472571Y1128256D01*
X1472280Y1128506D01*
X1472113Y1128881D01*
X1472071Y1129298D01*
X1472155Y1129840D01*
X1472280Y1130131D01*
X1472488Y1130423D01*
X1472780Y1130631D01*
X1473071Y1130673D01*
X1473363Y1130590D01*
X1473571Y1130381D01*
G01X1461413Y1127173D02*
Y1131173D01*
X1454013D01*
G01X1463230Y1096173D02*
Y1098673D01*
X1464271D01*
X1464605Y1098548D01*
X1464813Y1098381D01*
X1464896Y1098048D01*
X1464813Y1097715D01*
X1464563Y1097506D01*
X1464271Y1097381D01*
X1463230D01*
G01X1464271D02*
X1464896Y1096173D01*
G01X1466371Y1098256D02*
X1466621Y1098506D01*
X1466913Y1098631D01*
X1467246Y1098673D01*
X1467663Y1098590D01*
X1467955Y1098381D01*
X1468038Y1098131D01*
X1467996Y1097881D01*
X1467830Y1097673D01*
X1466996Y1097256D01*
X1466621Y1096965D01*
X1466371Y1096548D01*
X1466288Y1096173D01*
X1468038D01*
G01X1469555Y1096465D02*
X1469846Y1096256D01*
X1470180Y1096173D01*
X1470513Y1096256D01*
X1470805Y1096506D01*
X1471013Y1096881D01*
X1471096Y1097256D01*
Y1097715D01*
X1471013Y1098090D01*
X1470805Y1098423D01*
X1470555Y1098590D01*
X1470263Y1098673D01*
X1469930Y1098590D01*
X1469680Y1098423D01*
X1469513Y1098173D01*
X1469430Y1097840D01*
X1469513Y1097548D01*
X1469721Y1097256D01*
X1469971Y1097090D01*
X1470263Y1097048D01*
X1470596Y1097131D01*
X1470846Y1097340D01*
X1471096Y1097715D01*
G01X1473363Y1096173D02*
X1473655Y1096215D01*
X1473988Y1096340D01*
X1474196Y1096548D01*
X1474280Y1096840D01*
X1474196Y1097131D01*
X1473946Y1097381D01*
X1473571Y1097506D01*
X1473155D01*
X1472905Y1097590D01*
X1472696Y1097798D01*
X1472613Y1098090D01*
X1472738Y1098381D01*
X1473030Y1098590D01*
X1473363Y1098673D01*
X1473696Y1098590D01*
X1473988Y1098381D01*
X1474113Y1098090D01*
X1474030Y1097798D01*
X1473821Y1097590D01*
X1473571Y1097506D01*
X1473155D01*
X1472780Y1097381D01*
X1472530Y1097131D01*
X1472446Y1096840D01*
X1472530Y1096548D01*
X1472738Y1096340D01*
X1473071Y1096215D01*
X1473363Y1096173D01*
G01X1437913Y1094673D02*
Y1098673D01*
X1430513D01*
G01X1460713Y1090173D02*
X1444613D01*
G01X1460713Y1097173D02*
Y1090173D01*
G01X1444613Y1097173D02*
X1460713D01*
G01X1444613Y1090173D02*
Y1097173D01*
G01X1439900Y1126500D02*
X1439567Y1126542D01*
X1439275Y1126708D01*
X1439025Y1126958D01*
X1438858Y1127250D01*
X1438775Y1127583D01*
Y1127917D01*
X1438858Y1128250D01*
X1439025Y1128542D01*
X1439275Y1128792D01*
X1439567Y1128958D01*
X1439900Y1129000D01*
X1440233Y1128958D01*
X1440525Y1128792D01*
X1440775Y1128542D01*
X1440942Y1128250D01*
X1441025Y1127917D01*
Y1127583D01*
X1440942Y1127250D01*
X1440775Y1126958D01*
X1440525Y1126708D01*
X1440233Y1126542D01*
X1439900Y1126500D01*
G01X1440233Y1127167D02*
X1440733Y1126500D01*
G01X1443500D02*
Y1129000D01*
X1441958Y1127208D01*
X1444042D01*
G01X1445308Y1128583D02*
X1445558Y1128833D01*
X1445850Y1128958D01*
X1446183Y1129000D01*
X1446600Y1128917D01*
X1446892Y1128708D01*
X1446975Y1128458D01*
X1446933Y1128208D01*
X1446767Y1128000D01*
X1445933Y1127583D01*
X1445558Y1127292D01*
X1445308Y1126875D01*
X1445225Y1126500D01*
X1446975D01*
G01X1444713Y1124373D02*
X1442913Y1122273D01*
X1440713Y1124373D01*
G01X1437113Y1124473D02*
Y1105273D01*
X1448313D01*
Y1124473D01*
X1437113D01*
Y1124073D01*
G01X1464980Y1102565D02*
X1464730Y1102690D01*
X1464438Y1102773D01*
X1464105D01*
X1463730Y1102648D01*
X1463438Y1102440D01*
X1463230Y1102190D01*
X1463063Y1101773D01*
X1463021Y1101398D01*
X1463105Y1101023D01*
X1463230Y1100773D01*
X1463480Y1100523D01*
X1463771Y1100356D01*
X1464063Y1100273D01*
X1464355D01*
X1464646Y1100356D01*
X1464896Y1100481D01*
X1465105Y1100648D01*
G01X1467163Y1100273D02*
Y1102773D01*
X1466663Y1102273D01*
G01Y1100273D02*
X1467663D01*
G01X1469346Y1100773D02*
X1469596Y1100481D01*
X1469930Y1100315D01*
X1470305Y1100273D01*
X1470638Y1100315D01*
X1470971Y1100523D01*
X1471180Y1100773D01*
X1471221Y1101023D01*
X1471138Y1101315D01*
X1470846Y1101523D01*
X1470555Y1101606D01*
X1470180D01*
G01X1470555D02*
X1470805Y1101731D01*
X1471013Y1101940D01*
X1471096Y1102190D01*
X1471013Y1102440D01*
X1470805Y1102648D01*
X1470430Y1102773D01*
X1470055Y1102731D01*
X1469680Y1102565D01*
G01X1472655Y1100565D02*
X1472946Y1100356D01*
X1473280Y1100273D01*
X1473613Y1100356D01*
X1473905Y1100606D01*
X1474113Y1100981D01*
X1474196Y1101356D01*
Y1101815D01*
X1474113Y1102190D01*
X1473905Y1102523D01*
X1473655Y1102690D01*
X1473363Y1102773D01*
X1473030Y1102690D01*
X1472780Y1102523D01*
X1472613Y1102273D01*
X1472530Y1101940D01*
X1472613Y1101648D01*
X1472821Y1101356D01*
X1473071Y1101190D01*
X1473363Y1101148D01*
X1473696Y1101231D01*
X1473946Y1101440D01*
X1474196Y1101815D01*
G01X1468017Y1146000D02*
Y1148500D01*
X1469058D01*
X1469392Y1148375D01*
X1469600Y1148208D01*
X1469683Y1147875D01*
X1469600Y1147542D01*
X1469350Y1147333D01*
X1469058Y1147208D01*
X1468017D01*
G01X1469058D02*
X1469683Y1146000D01*
G01X1471033Y1146375D02*
X1471283Y1146167D01*
X1471575Y1146042D01*
X1471950Y1146000D01*
X1472325Y1146083D01*
X1472617Y1146250D01*
X1472825Y1146542D01*
X1472867Y1146875D01*
X1472783Y1147208D01*
X1472575Y1147417D01*
X1472283Y1147583D01*
X1471992Y1147625D01*
X1471700Y1147583D01*
X1471325Y1147417D01*
X1471450Y1148500D01*
X1472575D01*
G01X1474342Y1146292D02*
X1474633Y1146083D01*
X1474967Y1146000D01*
X1475300Y1146083D01*
X1475592Y1146333D01*
X1475800Y1146708D01*
X1475883Y1147083D01*
Y1147542D01*
X1475800Y1147917D01*
X1475592Y1148250D01*
X1475342Y1148417D01*
X1475050Y1148500D01*
X1474717Y1148417D01*
X1474467Y1148250D01*
X1474300Y1148000D01*
X1474217Y1147667D01*
X1474300Y1147375D01*
X1474508Y1147083D01*
X1474758Y1146917D01*
X1475050Y1146875D01*
X1475383Y1146958D01*
X1475633Y1147167D01*
X1475883Y1147542D01*
G01X1477358Y1148083D02*
X1477608Y1148333D01*
X1477900Y1148458D01*
X1478233Y1148500D01*
X1478650Y1148417D01*
X1478942Y1148208D01*
X1479025Y1147958D01*
X1478983Y1147708D01*
X1478817Y1147500D01*
X1477983Y1147083D01*
X1477608Y1146792D01*
X1477358Y1146375D01*
X1477275Y1146000D01*
X1479025D01*
G01X1446171Y1182820D02*
Y1174820D01*
X1428571D01*
Y1182820D01*
X1446171D01*
G01X1428713Y1155873D02*
Y1161373D01*
G01X1436713Y1155873D02*
X1428713D01*
G01X1436713Y1161373D02*
Y1155873D01*
G01Y1173473D02*
Y1167973D01*
G01X1428713Y1173473D02*
X1436713D01*
G01X1428713Y1167973D02*
Y1173473D01*
G01X1465500Y1144900D02*
X1465458Y1144567D01*
X1465292Y1144275D01*
X1465042Y1144025D01*
X1464750Y1143858D01*
X1464417Y1143775D01*
X1464083D01*
X1463750Y1143858D01*
X1463458Y1144025D01*
X1463208Y1144275D01*
X1463042Y1144567D01*
X1463000Y1144900D01*
X1463042Y1145233D01*
X1463208Y1145525D01*
X1463458Y1145775D01*
X1463750Y1145942D01*
X1464083Y1146025D01*
X1464417D01*
X1464750Y1145942D01*
X1465042Y1145775D01*
X1465292Y1145525D01*
X1465458Y1145233D01*
X1465500Y1144900D01*
G01X1464833Y1145233D02*
X1465500Y1145733D01*
G01Y1148500D02*
X1463000D01*
X1464792Y1146958D01*
Y1149042D01*
G01X1465500Y1151600D02*
X1463000D01*
X1464792Y1150058D01*
Y1152142D01*
G01X1439513Y1151673D02*
X1441613Y1149873D01*
X1439513Y1147673D01*
G01X1439413Y1144073D02*
X1458613D01*
Y1155273D01*
X1439413D01*
Y1144073D01*
X1439813D01*
G01X1472453Y1165544D02*
X1469953D01*
Y1166585D01*
X1470078Y1166919D01*
X1470245Y1167127D01*
X1470578Y1167210D01*
X1470911Y1167127D01*
X1471120Y1166877D01*
X1471245Y1166585D01*
Y1165544D01*
G01Y1166585D02*
X1472453Y1167210D01*
G01X1471953Y1168560D02*
X1472245Y1168810D01*
X1472411Y1169144D01*
X1472453Y1169519D01*
X1472411Y1169852D01*
X1472203Y1170185D01*
X1471953Y1170394D01*
X1471703Y1170435D01*
X1471411Y1170352D01*
X1471203Y1170060D01*
X1471120Y1169769D01*
Y1169394D01*
G01Y1169769D02*
X1470995Y1170019D01*
X1470786Y1170227D01*
X1470536Y1170310D01*
X1470286Y1170227D01*
X1470078Y1170019D01*
X1469953Y1169644D01*
X1469995Y1169269D01*
X1470161Y1168894D01*
G01X1469953Y1172577D02*
X1470036Y1172244D01*
X1470245Y1171994D01*
X1470495Y1171827D01*
X1470828Y1171702D01*
X1471203Y1171660D01*
X1471578Y1171702D01*
X1471911Y1171827D01*
X1472161Y1171994D01*
X1472370Y1172244D01*
X1472453Y1172577D01*
X1472370Y1172910D01*
X1472161Y1173160D01*
X1471911Y1173327D01*
X1471578Y1173452D01*
X1471203Y1173494D01*
X1470828Y1173452D01*
X1470495Y1173327D01*
X1470245Y1173160D01*
X1470036Y1172910D01*
X1469953Y1172577D01*
G01X1472453Y1175677D02*
X1469953D01*
X1470453Y1175177D01*
G01X1472453D02*
Y1176177D01*
G01X1464480Y1134565D02*
X1464230Y1134690D01*
X1463938Y1134773D01*
X1463605D01*
X1463230Y1134648D01*
X1462938Y1134440D01*
X1462730Y1134190D01*
X1462563Y1133773D01*
X1462521Y1133398D01*
X1462605Y1133023D01*
X1462730Y1132773D01*
X1462980Y1132523D01*
X1463271Y1132356D01*
X1463563Y1132273D01*
X1463855D01*
X1464146Y1132356D01*
X1464396Y1132481D01*
X1464605Y1132648D01*
G01X1466663Y1132273D02*
Y1134773D01*
X1466163Y1134273D01*
G01Y1132273D02*
X1467163D01*
G01X1470263D02*
Y1134773D01*
X1468721Y1132981D01*
X1470805D01*
G01X1472863Y1134773D02*
X1472530Y1134690D01*
X1472280Y1134481D01*
X1472113Y1134231D01*
X1471988Y1133898D01*
X1471946Y1133523D01*
X1471988Y1133148D01*
X1472113Y1132815D01*
X1472280Y1132565D01*
X1472530Y1132356D01*
X1472863Y1132273D01*
X1473196Y1132356D01*
X1473446Y1132565D01*
X1473613Y1132815D01*
X1473738Y1133148D01*
X1473780Y1133523D01*
X1473738Y1133898D01*
X1473613Y1134231D01*
X1473446Y1134481D01*
X1473196Y1134690D01*
X1472863Y1134773D01*
G01X1438017Y1184000D02*
Y1186500D01*
X1439058D01*
X1439392Y1186375D01*
X1439600Y1186208D01*
X1439683Y1185875D01*
X1439600Y1185542D01*
X1439350Y1185333D01*
X1439058Y1185208D01*
X1438017D01*
G01X1439058D02*
X1439683Y1184000D01*
G01X1441158Y1186083D02*
X1441408Y1186333D01*
X1441700Y1186458D01*
X1442033Y1186500D01*
X1442450Y1186417D01*
X1442742Y1186208D01*
X1442825Y1185958D01*
X1442783Y1185708D01*
X1442617Y1185500D01*
X1441783Y1185083D01*
X1441408Y1184792D01*
X1441158Y1184375D01*
X1441075Y1184000D01*
X1442825D01*
G01X1444342Y1184292D02*
X1444633Y1184083D01*
X1444967Y1184000D01*
X1445300Y1184083D01*
X1445592Y1184333D01*
X1445800Y1184708D01*
X1445883Y1185083D01*
Y1185542D01*
X1445800Y1185917D01*
X1445592Y1186250D01*
X1445342Y1186417D01*
X1445050Y1186500D01*
X1444717Y1186417D01*
X1444467Y1186250D01*
X1444300Y1186000D01*
X1444217Y1185667D01*
X1444300Y1185375D01*
X1444508Y1185083D01*
X1444758Y1184917D01*
X1445050Y1184875D01*
X1445383Y1184958D01*
X1445633Y1185167D01*
X1445883Y1185542D01*
G01X1448650Y1184000D02*
Y1186500D01*
X1447108Y1184708D01*
X1449192D01*
G01X1450042Y1193267D02*
X1449917Y1193017D01*
X1449834Y1192725D01*
Y1192392D01*
X1449959Y1192017D01*
X1450167Y1191725D01*
X1450417Y1191517D01*
X1450834Y1191350D01*
X1451209Y1191308D01*
X1451584Y1191392D01*
X1451834Y1191517D01*
X1452084Y1191767D01*
X1452251Y1192058D01*
X1452334Y1192350D01*
Y1192642D01*
X1452251Y1192933D01*
X1452126Y1193183D01*
X1451959Y1193392D01*
G01X1452334Y1195450D02*
X1449834D01*
X1450334Y1194950D01*
G01X1452334D02*
Y1195950D01*
G01X1451834Y1197633D02*
X1452126Y1197883D01*
X1452292Y1198217D01*
X1452334Y1198592D01*
X1452292Y1198925D01*
X1452084Y1199258D01*
X1451834Y1199467D01*
X1451584Y1199508D01*
X1451292Y1199425D01*
X1451084Y1199133D01*
X1451001Y1198842D01*
Y1198467D01*
G01Y1198842D02*
X1450876Y1199092D01*
X1450667Y1199300D01*
X1450417Y1199383D01*
X1450167Y1199300D01*
X1449959Y1199092D01*
X1449834Y1198717D01*
X1449876Y1198342D01*
X1450042Y1197967D01*
G01X1452334Y1201567D02*
X1451792Y1201650D01*
X1451334Y1201775D01*
X1450917Y1201942D01*
X1450459Y1202150D01*
X1449834Y1202483D01*
Y1200817D01*
G01X1446208Y1193267D02*
X1446083Y1193017D01*
X1446000Y1192725D01*
Y1192392D01*
X1446125Y1192017D01*
X1446333Y1191725D01*
X1446583Y1191517D01*
X1447000Y1191350D01*
X1447375Y1191308D01*
X1447750Y1191392D01*
X1448000Y1191517D01*
X1448250Y1191767D01*
X1448417Y1192058D01*
X1448500Y1192350D01*
Y1192642D01*
X1448417Y1192933D01*
X1448292Y1193183D01*
X1448125Y1193392D01*
G01X1448500Y1195450D02*
X1446000D01*
X1446500Y1194950D01*
G01X1448500D02*
Y1195950D01*
G01X1448000Y1197633D02*
X1448292Y1197883D01*
X1448458Y1198217D01*
X1448500Y1198592D01*
X1448458Y1198925D01*
X1448250Y1199258D01*
X1448000Y1199467D01*
X1447750Y1199508D01*
X1447458Y1199425D01*
X1447250Y1199133D01*
X1447167Y1198842D01*
Y1198467D01*
G01Y1198842D02*
X1447042Y1199092D01*
X1446833Y1199300D01*
X1446583Y1199383D01*
X1446333Y1199300D01*
X1446125Y1199092D01*
X1446000Y1198717D01*
X1446042Y1198342D01*
X1446208Y1197967D01*
G01X1448125Y1200733D02*
X1448333Y1200983D01*
X1448458Y1201275D01*
X1448500Y1201650D01*
X1448417Y1202025D01*
X1448250Y1202317D01*
X1447958Y1202525D01*
X1447625Y1202567D01*
X1447292Y1202483D01*
X1447083Y1202275D01*
X1446917Y1201983D01*
X1446875Y1201692D01*
X1446917Y1201400D01*
X1447083Y1201025D01*
X1446000Y1201150D01*
Y1202275D01*
G01X1442208Y1193267D02*
X1442083Y1193017D01*
X1442000Y1192725D01*
Y1192392D01*
X1442125Y1192017D01*
X1442333Y1191725D01*
X1442583Y1191517D01*
X1443000Y1191350D01*
X1443375Y1191308D01*
X1443750Y1191392D01*
X1444000Y1191517D01*
X1444250Y1191767D01*
X1444417Y1192058D01*
X1444500Y1192350D01*
Y1192642D01*
X1444417Y1192933D01*
X1444292Y1193183D01*
X1444125Y1193392D01*
G01X1444500Y1195450D02*
X1442000D01*
X1442500Y1194950D01*
G01X1444500D02*
Y1195950D01*
G01X1444000Y1197633D02*
X1444292Y1197883D01*
X1444458Y1198217D01*
X1444500Y1198592D01*
X1444458Y1198925D01*
X1444250Y1199258D01*
X1444000Y1199467D01*
X1443750Y1199508D01*
X1443458Y1199425D01*
X1443250Y1199133D01*
X1443167Y1198842D01*
Y1198467D01*
G01Y1198842D02*
X1443042Y1199092D01*
X1442833Y1199300D01*
X1442583Y1199383D01*
X1442333Y1199300D01*
X1442125Y1199092D01*
X1442000Y1198717D01*
X1442042Y1198342D01*
X1442208Y1197967D01*
G01X1444500Y1201650D02*
X1444458Y1201942D01*
X1444333Y1202275D01*
X1444125Y1202483D01*
X1443833Y1202567D01*
X1443542Y1202483D01*
X1443292Y1202233D01*
X1443167Y1201858D01*
Y1201442D01*
X1443083Y1201192D01*
X1442875Y1200983D01*
X1442583Y1200900D01*
X1442292Y1201025D01*
X1442083Y1201317D01*
X1442000Y1201650D01*
X1442083Y1201983D01*
X1442292Y1202275D01*
X1442583Y1202400D01*
X1442875Y1202317D01*
X1443083Y1202108D01*
X1443167Y1201858D01*
Y1201442D01*
X1443292Y1201067D01*
X1443542Y1200817D01*
X1443833Y1200733D01*
X1444125Y1200817D01*
X1444333Y1201025D01*
X1444458Y1201358D01*
X1444500Y1201650D01*
G01X1469832Y1653028D02*
Y1657028D01*
X1469032Y1656228D01*
G01Y1653028D02*
X1470632D01*
G01X1513218Y221492D02*
X1518268D01*
Y320192D01*
X1542918D01*
Y135792D01*
X1518268D01*
Y194492D01*
X1513218D01*
Y221492D01*
G01X1478230Y193161D02*
Y195661D01*
X1479271D01*
X1479605Y195536D01*
X1479813Y195369D01*
X1479896Y195036D01*
X1479813Y194703D01*
X1479563Y194494D01*
X1479271Y194369D01*
X1478230D01*
G01X1479271D02*
X1479896Y193161D01*
G01X1482163D02*
X1482455Y193203D01*
X1482788Y193328D01*
X1482996Y193536D01*
X1483080Y193828D01*
X1482996Y194119D01*
X1482746Y194369D01*
X1482371Y194494D01*
X1481955D01*
X1481705Y194578D01*
X1481496Y194786D01*
X1481413Y195078D01*
X1481538Y195369D01*
X1481830Y195578D01*
X1482163Y195661D01*
X1482496Y195578D01*
X1482788Y195369D01*
X1482913Y195078D01*
X1482830Y194786D01*
X1482621Y194578D01*
X1482371Y194494D01*
X1481955D01*
X1481580Y194369D01*
X1481330Y194119D01*
X1481246Y193828D01*
X1481330Y193536D01*
X1481538Y193328D01*
X1481871Y193203D01*
X1482163Y193161D01*
G01X1484346Y193536D02*
X1484596Y193328D01*
X1484888Y193203D01*
X1485263Y193161D01*
X1485638Y193244D01*
X1485930Y193411D01*
X1486138Y193703D01*
X1486180Y194036D01*
X1486096Y194369D01*
X1485888Y194578D01*
X1485596Y194744D01*
X1485305Y194786D01*
X1485013Y194744D01*
X1484638Y194578D01*
X1484763Y195661D01*
X1485888D01*
G01X1487655Y193453D02*
X1487946Y193244D01*
X1488280Y193161D01*
X1488613Y193244D01*
X1488905Y193494D01*
X1489113Y193869D01*
X1489196Y194244D01*
Y194703D01*
X1489113Y195078D01*
X1488905Y195411D01*
X1488655Y195578D01*
X1488363Y195661D01*
X1488030Y195578D01*
X1487780Y195411D01*
X1487613Y195161D01*
X1487530Y194828D01*
X1487613Y194536D01*
X1487821Y194244D01*
X1488071Y194078D01*
X1488363Y194036D01*
X1488696Y194119D01*
X1488946Y194328D01*
X1489196Y194703D01*
G01X1478483Y189500D02*
Y192000D01*
X1479317D01*
X1479650Y191875D01*
X1479900Y191708D01*
X1480108Y191458D01*
X1480275Y191167D01*
X1480317Y190750D01*
X1480275Y190333D01*
X1480108Y190042D01*
X1479900Y189792D01*
X1479650Y189625D01*
X1479317Y189500D01*
X1478483D01*
G01X1481583Y190000D02*
X1481833Y189708D01*
X1482167Y189542D01*
X1482542Y189500D01*
X1482875Y189542D01*
X1483208Y189750D01*
X1483417Y190000D01*
X1483458Y190250D01*
X1483375Y190542D01*
X1483083Y190750D01*
X1482792Y190833D01*
X1482417D01*
G01X1482792D02*
X1483042Y190958D01*
X1483250Y191167D01*
X1483333Y191417D01*
X1483250Y191667D01*
X1483042Y191875D01*
X1482667Y192000D01*
X1482292Y191958D01*
X1481917Y191792D01*
G01X1485600Y189500D02*
Y192000D01*
X1485100Y191500D01*
G01Y189500D02*
X1486100D01*
G01X1495470Y171684D02*
X1495220Y171809D01*
X1494928Y171892D01*
X1494595D01*
X1494220Y171767D01*
X1493928Y171559D01*
X1493720Y171309D01*
X1493553Y170892D01*
X1493511Y170517D01*
X1493595Y170142D01*
X1493720Y169892D01*
X1493970Y169642D01*
X1494261Y169475D01*
X1494553Y169392D01*
X1494845D01*
X1495136Y169475D01*
X1495386Y169600D01*
X1495595Y169767D01*
G01X1498153Y169392D02*
Y171892D01*
X1496611Y170100D01*
X1498695D01*
G01X1499836Y169767D02*
X1500086Y169559D01*
X1500378Y169434D01*
X1500753Y169392D01*
X1501128Y169475D01*
X1501420Y169642D01*
X1501628Y169934D01*
X1501670Y170267D01*
X1501586Y170600D01*
X1501378Y170809D01*
X1501086Y170975D01*
X1500795Y171017D01*
X1500503Y170975D01*
X1500128Y170809D01*
X1500253Y171892D01*
X1501378D01*
G01X1502936Y169767D02*
X1503186Y169559D01*
X1503478Y169434D01*
X1503853Y169392D01*
X1504228Y169475D01*
X1504520Y169642D01*
X1504728Y169934D01*
X1504770Y170267D01*
X1504686Y170600D01*
X1504478Y170809D01*
X1504186Y170975D01*
X1503895Y171017D01*
X1503603Y170975D01*
X1503228Y170809D01*
X1503353Y171892D01*
X1504478D01*
G01X1495267Y175792D02*
X1495017Y175917D01*
X1494725Y176000D01*
X1494392D01*
X1494017Y175875D01*
X1493725Y175667D01*
X1493517Y175417D01*
X1493350Y175000D01*
X1493308Y174625D01*
X1493392Y174250D01*
X1493517Y174000D01*
X1493767Y173750D01*
X1494058Y173583D01*
X1494350Y173500D01*
X1494642D01*
X1494933Y173583D01*
X1495183Y173708D01*
X1495392Y173875D01*
G01X1497950Y173500D02*
Y176000D01*
X1496408Y174208D01*
X1498492D01*
G01X1499633Y173875D02*
X1499883Y173667D01*
X1500175Y173542D01*
X1500550Y173500D01*
X1500925Y173583D01*
X1501217Y173750D01*
X1501425Y174042D01*
X1501467Y174375D01*
X1501383Y174708D01*
X1501175Y174917D01*
X1500883Y175083D01*
X1500592Y175125D01*
X1500300Y175083D01*
X1499925Y174917D01*
X1500050Y176000D01*
X1501175D01*
G01X1504150Y173500D02*
Y176000D01*
X1502608Y174208D01*
X1504692D01*
G01X1484517Y244100D02*
Y246600D01*
X1485558D01*
X1485892Y246475D01*
X1486100Y246308D01*
X1486183Y245975D01*
X1486100Y245642D01*
X1485850Y245433D01*
X1485558Y245308D01*
X1484517D01*
G01X1485558D02*
X1486183Y244100D01*
G01X1488450D02*
X1488742Y244142D01*
X1489075Y244267D01*
X1489283Y244475D01*
X1489367Y244767D01*
X1489283Y245058D01*
X1489033Y245308D01*
X1488658Y245433D01*
X1488242D01*
X1487992Y245517D01*
X1487783Y245725D01*
X1487700Y246017D01*
X1487825Y246308D01*
X1488117Y246517D01*
X1488450Y246600D01*
X1488783Y246517D01*
X1489075Y246308D01*
X1489200Y246017D01*
X1489117Y245725D01*
X1488908Y245517D01*
X1488658Y245433D01*
X1488242D01*
X1487867Y245308D01*
X1487617Y245058D01*
X1487533Y244767D01*
X1487617Y244475D01*
X1487825Y244267D01*
X1488158Y244142D01*
X1488450Y244100D01*
G01X1490758Y245142D02*
X1491050Y245433D01*
X1491300Y245600D01*
X1491633Y245683D01*
X1491925Y245600D01*
X1492133Y245433D01*
X1492300Y245183D01*
X1492342Y244892D01*
X1492300Y244642D01*
X1492133Y244392D01*
X1491883Y244183D01*
X1491592Y244100D01*
X1491258Y244183D01*
X1490967Y244433D01*
X1490800Y244808D01*
X1490758Y245225D01*
X1490842Y245767D01*
X1490967Y246058D01*
X1491175Y246350D01*
X1491467Y246558D01*
X1491758Y246600D01*
X1492050Y246517D01*
X1492258Y246308D01*
G01X1493858Y245142D02*
X1494150Y245433D01*
X1494400Y245600D01*
X1494733Y245683D01*
X1495025Y245600D01*
X1495233Y245433D01*
X1495400Y245183D01*
X1495442Y244892D01*
X1495400Y244642D01*
X1495233Y244392D01*
X1494983Y244183D01*
X1494692Y244100D01*
X1494358Y244183D01*
X1494067Y244433D01*
X1493900Y244808D01*
X1493858Y245225D01*
X1493942Y245767D01*
X1494067Y246058D01*
X1494275Y246350D01*
X1494567Y246558D01*
X1494858Y246600D01*
X1495150Y246517D01*
X1495358Y246308D01*
G01X1497825Y246661D02*
Y242661D01*
X1505225D01*
G01X1482517Y255000D02*
Y257500D01*
X1483558D01*
X1483892Y257375D01*
X1484100Y257208D01*
X1484183Y256875D01*
X1484100Y256542D01*
X1483850Y256333D01*
X1483558Y256208D01*
X1482517D01*
G01X1483558D02*
X1484183Y255000D01*
G01X1486450D02*
X1486742Y255042D01*
X1487075Y255167D01*
X1487283Y255375D01*
X1487367Y255667D01*
X1487283Y255958D01*
X1487033Y256208D01*
X1486658Y256333D01*
X1486242D01*
X1485992Y256417D01*
X1485783Y256625D01*
X1485700Y256917D01*
X1485825Y257208D01*
X1486117Y257417D01*
X1486450Y257500D01*
X1486783Y257417D01*
X1487075Y257208D01*
X1487200Y256917D01*
X1487117Y256625D01*
X1486908Y256417D01*
X1486658Y256333D01*
X1486242D01*
X1485867Y256208D01*
X1485617Y255958D01*
X1485533Y255667D01*
X1485617Y255375D01*
X1485825Y255167D01*
X1486158Y255042D01*
X1486450Y255000D01*
G01X1489467D02*
X1489550Y255542D01*
X1489675Y256000D01*
X1489842Y256417D01*
X1490050Y256875D01*
X1490383Y257500D01*
X1488717D01*
G01X1492650D02*
X1492317Y257417D01*
X1492067Y257208D01*
X1491900Y256958D01*
X1491775Y256625D01*
X1491733Y256250D01*
X1491775Y255875D01*
X1491900Y255542D01*
X1492067Y255292D01*
X1492317Y255083D01*
X1492650Y255000D01*
X1492983Y255083D01*
X1493233Y255292D01*
X1493400Y255542D01*
X1493525Y255875D01*
X1493567Y256250D01*
X1493525Y256625D01*
X1493400Y256958D01*
X1493233Y257208D01*
X1492983Y257417D01*
X1492650Y257500D01*
G01X1486267Y242292D02*
X1486017Y242417D01*
X1485725Y242500D01*
X1485392D01*
X1485017Y242375D01*
X1484725Y242167D01*
X1484517Y241917D01*
X1484350Y241500D01*
X1484308Y241125D01*
X1484392Y240750D01*
X1484517Y240500D01*
X1484767Y240250D01*
X1485058Y240083D01*
X1485350Y240000D01*
X1485642D01*
X1485933Y240083D01*
X1486183Y240208D01*
X1486392Y240375D01*
G01X1488950Y240000D02*
Y242500D01*
X1487408Y240708D01*
X1489492D01*
G01X1490633Y240375D02*
X1490883Y240167D01*
X1491175Y240042D01*
X1491550Y240000D01*
X1491925Y240083D01*
X1492217Y240250D01*
X1492425Y240542D01*
X1492467Y240875D01*
X1492383Y241208D01*
X1492175Y241417D01*
X1491883Y241583D01*
X1491592Y241625D01*
X1491300Y241583D01*
X1490925Y241417D01*
X1491050Y242500D01*
X1492175D01*
G01X1494650Y240000D02*
X1494942Y240042D01*
X1495275Y240167D01*
X1495483Y240375D01*
X1495567Y240667D01*
X1495483Y240958D01*
X1495233Y241208D01*
X1494858Y241333D01*
X1494442D01*
X1494192Y241417D01*
X1493983Y241625D01*
X1493900Y241917D01*
X1494025Y242208D01*
X1494317Y242417D01*
X1494650Y242500D01*
X1494983Y242417D01*
X1495275Y242208D01*
X1495400Y241917D01*
X1495317Y241625D01*
X1495108Y241417D01*
X1494858Y241333D01*
X1494442D01*
X1494067Y241208D01*
X1493817Y240958D01*
X1493733Y240667D01*
X1493817Y240375D01*
X1494025Y240167D01*
X1494358Y240042D01*
X1494650Y240000D01*
G01X1482300Y267166D02*
Y264666D01*
G01X1481342Y267166D02*
X1483258D01*
G01X1484567Y264666D02*
Y267166D01*
X1485567D01*
X1485900Y267041D01*
X1486150Y266749D01*
X1486233Y266416D01*
X1486150Y266083D01*
X1485942Y265833D01*
X1485567Y265708D01*
X1484567D01*
G01X1488500Y264666D02*
Y267166D01*
X1488000Y266666D01*
G01Y264666D02*
X1489000D01*
G01X1490808Y265708D02*
X1491100Y265999D01*
X1491350Y266166D01*
X1491683Y266249D01*
X1491975Y266166D01*
X1492183Y265999D01*
X1492350Y265749D01*
X1492392Y265458D01*
X1492350Y265208D01*
X1492183Y264958D01*
X1491933Y264749D01*
X1491642Y264666D01*
X1491308Y264749D01*
X1491017Y264999D01*
X1490850Y265374D01*
X1490808Y265791D01*
X1490892Y266333D01*
X1491017Y266624D01*
X1491225Y266916D01*
X1491517Y267124D01*
X1491808Y267166D01*
X1492100Y267083D01*
X1492308Y266874D01*
G01X1493908Y266749D02*
X1494158Y266999D01*
X1494450Y267124D01*
X1494783Y267166D01*
X1495200Y267083D01*
X1495492Y266874D01*
X1495575Y266624D01*
X1495533Y266374D01*
X1495367Y266166D01*
X1494533Y265749D01*
X1494158Y265458D01*
X1493908Y265041D01*
X1493825Y264666D01*
X1495575D01*
G01X1518393Y329492D02*
Y331992D01*
G01X1520143D02*
Y329492D01*
G01Y330742D02*
X1518393D01*
G01X1521451Y329492D02*
Y331992D01*
X1522285D01*
X1522618Y331867D01*
X1522868Y331700D01*
X1523076Y331450D01*
X1523243Y331159D01*
X1523285Y330742D01*
X1523243Y330325D01*
X1523076Y330034D01*
X1522868Y329784D01*
X1522618Y329617D01*
X1522285Y329492D01*
X1521451D01*
G01X1524551D02*
Y331992D01*
X1525385D01*
X1525718Y331867D01*
X1525968Y331700D01*
X1526176Y331450D01*
X1526343Y331159D01*
X1526385Y330742D01*
X1526343Y330325D01*
X1526176Y330034D01*
X1525968Y329784D01*
X1525718Y329617D01*
X1525385Y329492D01*
X1524551D01*
G01X1527693Y329825D02*
X1528026Y329617D01*
X1528401Y329492D01*
X1528735D01*
X1529068Y329617D01*
X1529318Y329825D01*
X1529443Y330117D01*
X1529360Y330409D01*
X1529151Y330659D01*
X1528776Y330825D01*
X1528276Y330909D01*
X1527985Y331075D01*
X1527860Y331367D01*
X1527943Y331659D01*
X1528151Y331867D01*
X1528443Y331992D01*
X1528735D01*
X1529026Y331909D01*
X1529276Y331700D01*
G01X1530626Y329492D02*
X1531668Y331992D01*
X1532710Y329492D01*
G01X1532335Y330367D02*
X1531001D01*
G01X1533893Y329825D02*
X1534226Y329617D01*
X1534601Y329492D01*
X1534935D01*
X1535268Y329617D01*
X1535518Y329825D01*
X1535643Y330117D01*
X1535560Y330409D01*
X1535351Y330659D01*
X1534976Y330825D01*
X1534476Y330909D01*
X1534185Y331075D01*
X1534060Y331367D01*
X1534143Y331659D01*
X1534351Y331867D01*
X1534643Y331992D01*
X1534935D01*
X1535226Y331909D01*
X1535476Y331700D01*
G01X1536951Y329992D02*
X1537201Y329700D01*
X1537535Y329534D01*
X1537910Y329492D01*
X1538243Y329534D01*
X1538576Y329742D01*
X1538785Y329992D01*
X1538826Y330242D01*
X1538743Y330534D01*
X1538451Y330742D01*
X1538160Y330825D01*
X1537785D01*
G01X1538160D02*
X1538410Y330950D01*
X1538618Y331159D01*
X1538701Y331409D01*
X1538618Y331659D01*
X1538410Y331867D01*
X1538035Y331992D01*
X1537660Y331950D01*
X1537285Y331784D01*
G01X1540176Y331575D02*
X1540426Y331825D01*
X1540718Y331950D01*
X1541051Y331992D01*
X1541468Y331909D01*
X1541760Y331700D01*
X1541843Y331450D01*
X1541801Y331200D01*
X1541635Y330992D01*
X1540801Y330575D01*
X1540426Y330284D01*
X1540176Y329867D01*
X1540093Y329492D01*
X1541843D01*
G01X1481131Y382654D02*
Y385154D01*
X1482715D01*
G01X1482131Y383946D02*
X1481131D01*
G01X1484190Y385154D02*
Y382654D01*
X1485856D01*
G01X1488956D02*
X1487290D01*
Y385154D01*
X1488956D01*
G01X1488290Y383946D02*
X1487290D01*
G01X1490306Y382654D02*
Y385154D01*
X1491140D01*
X1491473Y385029D01*
X1491723Y384862D01*
X1491931Y384612D01*
X1492098Y384321D01*
X1492140Y383904D01*
X1492098Y383487D01*
X1491931Y383196D01*
X1491723Y382946D01*
X1491473Y382779D01*
X1491140Y382654D01*
X1490306D01*
G01X1493531Y384737D02*
X1493781Y384987D01*
X1494073Y385112D01*
X1494406Y385154D01*
X1494823Y385071D01*
X1495115Y384862D01*
X1495198Y384612D01*
X1495156Y384362D01*
X1494990Y384154D01*
X1494156Y383737D01*
X1493781Y383446D01*
X1493531Y383029D01*
X1493448Y382654D01*
X1495198D01*
G01X1497423D02*
Y385154D01*
X1496923Y384654D01*
G01Y382654D02*
X1497923D01*
G01X1484773Y366054D02*
Y377254D01*
X1493573D01*
Y366054D01*
X1484773D01*
G01X1501200Y498067D02*
X1498700D01*
Y499108D01*
X1498825Y499442D01*
X1498992Y499650D01*
X1499325Y499733D01*
X1499658Y499650D01*
X1499867Y499400D01*
X1499992Y499108D01*
Y498067D01*
G01Y499108D02*
X1501200Y499733D01*
G01Y502000D02*
X1498700D01*
X1499200Y501500D01*
G01X1501200D02*
Y502500D01*
G01X1498700Y505100D02*
X1498783Y504767D01*
X1498992Y504517D01*
X1499242Y504350D01*
X1499575Y504225D01*
X1499950Y504183D01*
X1500325Y504225D01*
X1500658Y504350D01*
X1500908Y504517D01*
X1501117Y504767D01*
X1501200Y505100D01*
X1501117Y505433D01*
X1500908Y505683D01*
X1500658Y505850D01*
X1500325Y505975D01*
X1499950Y506017D01*
X1499575Y505975D01*
X1499242Y505850D01*
X1498992Y505683D01*
X1498783Y505433D01*
X1498700Y505100D01*
G01X1500908Y507492D02*
X1501117Y507783D01*
X1501200Y508117D01*
X1501117Y508450D01*
X1500867Y508742D01*
X1500492Y508950D01*
X1500117Y509033D01*
X1499658D01*
X1499283Y508950D01*
X1498950Y508742D01*
X1498783Y508492D01*
X1498700Y508200D01*
X1498783Y507867D01*
X1498950Y507617D01*
X1499200Y507450D01*
X1499533Y507367D01*
X1499825Y507450D01*
X1500117Y507658D01*
X1500283Y507908D01*
X1500325Y508200D01*
X1500242Y508533D01*
X1500033Y508783D01*
X1499658Y509033D01*
G01X1501200Y511300D02*
X1498700D01*
X1499200Y510800D01*
G01X1501200D02*
Y511800D01*
G01X1513500Y497967D02*
X1511000D01*
Y499008D01*
X1511125Y499342D01*
X1511292Y499550D01*
X1511625Y499633D01*
X1511958Y499550D01*
X1512167Y499300D01*
X1512292Y499008D01*
Y497967D01*
G01Y499008D02*
X1513500Y499633D01*
G01Y501900D02*
X1511000D01*
X1511500Y501400D01*
G01X1513500D02*
Y502400D01*
G01X1511000Y505000D02*
X1511083Y504667D01*
X1511292Y504417D01*
X1511542Y504250D01*
X1511875Y504125D01*
X1512250Y504083D01*
X1512625Y504125D01*
X1512958Y504250D01*
X1513208Y504417D01*
X1513417Y504667D01*
X1513500Y505000D01*
X1513417Y505333D01*
X1513208Y505583D01*
X1512958Y505750D01*
X1512625Y505875D01*
X1512250Y505917D01*
X1511875Y505875D01*
X1511542Y505750D01*
X1511292Y505583D01*
X1511083Y505333D01*
X1511000Y505000D01*
G01X1513208Y507392D02*
X1513417Y507683D01*
X1513500Y508017D01*
X1513417Y508350D01*
X1513167Y508642D01*
X1512792Y508850D01*
X1512417Y508933D01*
X1511958D01*
X1511583Y508850D01*
X1511250Y508642D01*
X1511083Y508392D01*
X1511000Y508100D01*
X1511083Y507767D01*
X1511250Y507517D01*
X1511500Y507350D01*
X1511833Y507267D01*
X1512125Y507350D01*
X1512417Y507558D01*
X1512583Y507808D01*
X1512625Y508100D01*
X1512542Y508433D01*
X1512333Y508683D01*
X1511958Y508933D01*
G01X1513000Y510283D02*
X1513292Y510533D01*
X1513458Y510867D01*
X1513500Y511242D01*
X1513458Y511575D01*
X1513250Y511908D01*
X1513000Y512117D01*
X1512750Y512158D01*
X1512458Y512075D01*
X1512250Y511783D01*
X1512167Y511492D01*
Y511117D01*
G01Y511492D02*
X1512042Y511742D01*
X1511833Y511950D01*
X1511583Y512033D01*
X1511333Y511950D01*
X1511125Y511742D01*
X1511000Y511367D01*
X1511042Y510992D01*
X1511208Y510617D01*
G01X1522000Y497967D02*
X1519500D01*
Y499008D01*
X1519625Y499342D01*
X1519792Y499550D01*
X1520125Y499633D01*
X1520458Y499550D01*
X1520667Y499300D01*
X1520792Y499008D01*
Y497967D01*
G01Y499008D02*
X1522000Y499633D01*
G01Y501900D02*
X1519500D01*
X1520000Y501400D01*
G01X1522000D02*
Y502400D01*
G01X1519500Y505000D02*
X1519583Y504667D01*
X1519792Y504417D01*
X1520042Y504250D01*
X1520375Y504125D01*
X1520750Y504083D01*
X1521125Y504125D01*
X1521458Y504250D01*
X1521708Y504417D01*
X1521917Y504667D01*
X1522000Y505000D01*
X1521917Y505333D01*
X1521708Y505583D01*
X1521458Y505750D01*
X1521125Y505875D01*
X1520750Y505917D01*
X1520375Y505875D01*
X1520042Y505750D01*
X1519792Y505583D01*
X1519583Y505333D01*
X1519500Y505000D01*
G01X1521708Y507392D02*
X1521917Y507683D01*
X1522000Y508017D01*
X1521917Y508350D01*
X1521667Y508642D01*
X1521292Y508850D01*
X1520917Y508933D01*
X1520458D01*
X1520083Y508850D01*
X1519750Y508642D01*
X1519583Y508392D01*
X1519500Y508100D01*
X1519583Y507767D01*
X1519750Y507517D01*
X1520000Y507350D01*
X1520333Y507267D01*
X1520625Y507350D01*
X1520917Y507558D01*
X1521083Y507808D01*
X1521125Y508100D01*
X1521042Y508433D01*
X1520833Y508683D01*
X1520458Y508933D01*
G01X1521625Y510283D02*
X1521833Y510533D01*
X1521958Y510825D01*
X1522000Y511200D01*
X1521917Y511575D01*
X1521750Y511867D01*
X1521458Y512075D01*
X1521125Y512117D01*
X1520792Y512033D01*
X1520583Y511825D01*
X1520417Y511533D01*
X1520375Y511242D01*
X1520417Y510950D01*
X1520583Y510575D01*
X1519500Y510700D01*
Y511825D01*
G01X1485000Y477517D02*
X1482500D01*
Y478558D01*
X1482625Y478892D01*
X1482792Y479100D01*
X1483125Y479183D01*
X1483458Y479100D01*
X1483667Y478850D01*
X1483792Y478558D01*
Y477517D01*
G01Y478558D02*
X1485000Y479183D01*
G01X1484625Y480533D02*
X1484833Y480783D01*
X1484958Y481075D01*
X1485000Y481450D01*
X1484917Y481825D01*
X1484750Y482117D01*
X1484458Y482325D01*
X1484125Y482367D01*
X1483792Y482283D01*
X1483583Y482075D01*
X1483417Y481783D01*
X1483375Y481492D01*
X1483417Y481200D01*
X1483583Y480825D01*
X1482500Y480950D01*
Y482075D01*
G01X1484500Y483633D02*
X1484792Y483883D01*
X1484958Y484217D01*
X1485000Y484592D01*
X1484958Y484925D01*
X1484750Y485258D01*
X1484500Y485467D01*
X1484250Y485508D01*
X1483958Y485425D01*
X1483750Y485133D01*
X1483667Y484842D01*
Y484467D01*
G01Y484842D02*
X1483542Y485092D01*
X1483333Y485300D01*
X1483083Y485383D01*
X1482833Y485300D01*
X1482625Y485092D01*
X1482500Y484717D01*
X1482542Y484342D01*
X1482708Y483967D01*
G01X1484708Y486942D02*
X1484917Y487233D01*
X1485000Y487567D01*
X1484917Y487900D01*
X1484667Y488192D01*
X1484292Y488400D01*
X1483917Y488483D01*
X1483458D01*
X1483083Y488400D01*
X1482750Y488192D01*
X1482583Y487942D01*
X1482500Y487650D01*
X1482583Y487317D01*
X1482750Y487067D01*
X1483000Y486900D01*
X1483333Y486817D01*
X1483625Y486900D01*
X1483917Y487108D01*
X1484083Y487358D01*
X1484125Y487650D01*
X1484042Y487983D01*
X1483833Y488233D01*
X1483458Y488483D01*
G01X1479938Y501070D02*
X1483938D01*
Y508470D01*
G01X1478980Y495768D02*
Y509768D01*
G01X1494594Y477517D02*
X1492094D01*
Y478558D01*
X1492219Y478892D01*
X1492386Y479100D01*
X1492719Y479183D01*
X1493052Y479100D01*
X1493261Y478850D01*
X1493386Y478558D01*
Y477517D01*
G01Y478558D02*
X1494594Y479183D01*
G01X1494094Y480533D02*
X1494386Y480783D01*
X1494552Y481117D01*
X1494594Y481492D01*
X1494552Y481825D01*
X1494344Y482158D01*
X1494094Y482367D01*
X1493844Y482408D01*
X1493552Y482325D01*
X1493344Y482033D01*
X1493261Y481742D01*
Y481367D01*
G01Y481742D02*
X1493136Y481992D01*
X1492927Y482200D01*
X1492677Y482283D01*
X1492427Y482200D01*
X1492219Y481992D01*
X1492094Y481617D01*
X1492136Y481242D01*
X1492302Y480867D01*
G01X1494094Y483633D02*
X1494386Y483883D01*
X1494552Y484217D01*
X1494594Y484592D01*
X1494552Y484925D01*
X1494344Y485258D01*
X1494094Y485467D01*
X1493844Y485508D01*
X1493552Y485425D01*
X1493344Y485133D01*
X1493261Y484842D01*
Y484467D01*
G01Y484842D02*
X1493136Y485092D01*
X1492927Y485300D01*
X1492677Y485383D01*
X1492427Y485300D01*
X1492219Y485092D01*
X1492094Y484717D01*
X1492136Y484342D01*
X1492302Y483967D01*
G01X1494594Y488150D02*
X1492094D01*
X1493886Y486608D01*
Y488692D01*
G01X1489594Y477517D02*
X1487094D01*
Y478558D01*
X1487219Y478892D01*
X1487386Y479100D01*
X1487719Y479183D01*
X1488052Y479100D01*
X1488261Y478850D01*
X1488386Y478558D01*
Y477517D01*
G01Y478558D02*
X1489594Y479183D01*
G01X1489094Y480533D02*
X1489386Y480783D01*
X1489552Y481117D01*
X1489594Y481492D01*
X1489552Y481825D01*
X1489344Y482158D01*
X1489094Y482367D01*
X1488844Y482408D01*
X1488552Y482325D01*
X1488344Y482033D01*
X1488261Y481742D01*
Y481367D01*
G01Y481742D02*
X1488136Y481992D01*
X1487927Y482200D01*
X1487677Y482283D01*
X1487427Y482200D01*
X1487219Y481992D01*
X1487094Y481617D01*
X1487136Y481242D01*
X1487302Y480867D01*
G01X1489094Y483633D02*
X1489386Y483883D01*
X1489552Y484217D01*
X1489594Y484592D01*
X1489552Y484925D01*
X1489344Y485258D01*
X1489094Y485467D01*
X1488844Y485508D01*
X1488552Y485425D01*
X1488344Y485133D01*
X1488261Y484842D01*
Y484467D01*
G01Y484842D02*
X1488136Y485092D01*
X1487927Y485300D01*
X1487677Y485383D01*
X1487427Y485300D01*
X1487219Y485092D01*
X1487094Y484717D01*
X1487136Y484342D01*
X1487302Y483967D01*
G01X1487511Y486858D02*
X1487261Y487108D01*
X1487136Y487400D01*
X1487094Y487733D01*
X1487177Y488150D01*
X1487386Y488442D01*
X1487636Y488525D01*
X1487886Y488483D01*
X1488094Y488317D01*
X1488511Y487483D01*
X1488802Y487108D01*
X1489219Y486858D01*
X1489594Y486775D01*
Y488525D01*
G01X1506708Y499767D02*
X1506583Y499517D01*
X1506500Y499225D01*
Y498892D01*
X1506625Y498517D01*
X1506833Y498225D01*
X1507083Y498017D01*
X1507500Y497850D01*
X1507875Y497808D01*
X1508250Y497892D01*
X1508500Y498017D01*
X1508750Y498267D01*
X1508917Y498558D01*
X1509000Y498850D01*
Y499142D01*
X1508917Y499433D01*
X1508792Y499683D01*
X1508625Y499892D01*
G01Y501033D02*
X1508833Y501283D01*
X1508958Y501575D01*
X1509000Y501950D01*
X1508917Y502325D01*
X1508750Y502617D01*
X1508458Y502825D01*
X1508125Y502867D01*
X1507792Y502783D01*
X1507583Y502575D01*
X1507417Y502283D01*
X1507375Y501992D01*
X1507417Y501700D01*
X1507583Y501325D01*
X1506500Y501450D01*
Y502575D01*
G01X1507958Y504258D02*
X1507667Y504550D01*
X1507500Y504800D01*
X1507417Y505133D01*
X1507500Y505425D01*
X1507667Y505633D01*
X1507917Y505800D01*
X1508208Y505842D01*
X1508458Y505800D01*
X1508708Y505633D01*
X1508917Y505383D01*
X1509000Y505092D01*
X1508917Y504758D01*
X1508667Y504467D01*
X1508292Y504300D01*
X1507875Y504258D01*
X1507333Y504342D01*
X1507042Y504467D01*
X1506750Y504675D01*
X1506542Y504967D01*
X1506500Y505258D01*
X1506583Y505550D01*
X1506792Y505758D01*
G01X1508500Y507233D02*
X1508792Y507483D01*
X1508958Y507817D01*
X1509000Y508192D01*
X1508958Y508525D01*
X1508750Y508858D01*
X1508500Y509067D01*
X1508250Y509108D01*
X1507958Y509025D01*
X1507750Y508733D01*
X1507667Y508442D01*
Y508067D01*
G01Y508442D02*
X1507542Y508692D01*
X1507333Y508900D01*
X1507083Y508983D01*
X1506833Y508900D01*
X1506625Y508692D01*
X1506500Y508317D01*
X1506542Y507942D01*
X1506708Y507567D01*
G01X1515208Y499767D02*
X1515083Y499517D01*
X1515000Y499225D01*
Y498892D01*
X1515125Y498517D01*
X1515333Y498225D01*
X1515583Y498017D01*
X1516000Y497850D01*
X1516375Y497808D01*
X1516750Y497892D01*
X1517000Y498017D01*
X1517250Y498267D01*
X1517417Y498558D01*
X1517500Y498850D01*
Y499142D01*
X1517417Y499433D01*
X1517292Y499683D01*
X1517125Y499892D01*
G01Y501033D02*
X1517333Y501283D01*
X1517458Y501575D01*
X1517500Y501950D01*
X1517417Y502325D01*
X1517250Y502617D01*
X1516958Y502825D01*
X1516625Y502867D01*
X1516292Y502783D01*
X1516083Y502575D01*
X1515917Y502283D01*
X1515875Y501992D01*
X1515917Y501700D01*
X1516083Y501325D01*
X1515000Y501450D01*
Y502575D01*
G01X1516458Y504258D02*
X1516167Y504550D01*
X1516000Y504800D01*
X1515917Y505133D01*
X1516000Y505425D01*
X1516167Y505633D01*
X1516417Y505800D01*
X1516708Y505842D01*
X1516958Y505800D01*
X1517208Y505633D01*
X1517417Y505383D01*
X1517500Y505092D01*
X1517417Y504758D01*
X1517167Y504467D01*
X1516792Y504300D01*
X1516375Y504258D01*
X1515833Y504342D01*
X1515542Y504467D01*
X1515250Y504675D01*
X1515042Y504967D01*
X1515000Y505258D01*
X1515083Y505550D01*
X1515292Y505758D01*
G01X1515417Y507358D02*
X1515167Y507608D01*
X1515042Y507900D01*
X1515000Y508233D01*
X1515083Y508650D01*
X1515292Y508942D01*
X1515542Y509025D01*
X1515792Y508983D01*
X1516000Y508817D01*
X1516417Y507983D01*
X1516708Y507608D01*
X1517125Y507358D01*
X1517500Y507275D01*
Y509025D01*
G01X1502708Y499767D02*
X1502583Y499517D01*
X1502500Y499225D01*
Y498892D01*
X1502625Y498517D01*
X1502833Y498225D01*
X1503083Y498017D01*
X1503500Y497850D01*
X1503875Y497808D01*
X1504250Y497892D01*
X1504500Y498017D01*
X1504750Y498267D01*
X1504917Y498558D01*
X1505000Y498850D01*
Y499142D01*
X1504917Y499433D01*
X1504792Y499683D01*
X1504625Y499892D01*
G01Y501033D02*
X1504833Y501283D01*
X1504958Y501575D01*
X1505000Y501950D01*
X1504917Y502325D01*
X1504750Y502617D01*
X1504458Y502825D01*
X1504125Y502867D01*
X1503792Y502783D01*
X1503583Y502575D01*
X1503417Y502283D01*
X1503375Y501992D01*
X1503417Y501700D01*
X1503583Y501325D01*
X1502500Y501450D01*
Y502575D01*
G01X1503958Y504258D02*
X1503667Y504550D01*
X1503500Y504800D01*
X1503417Y505133D01*
X1503500Y505425D01*
X1503667Y505633D01*
X1503917Y505800D01*
X1504208Y505842D01*
X1504458Y505800D01*
X1504708Y505633D01*
X1504917Y505383D01*
X1505000Y505092D01*
X1504917Y504758D01*
X1504667Y504467D01*
X1504292Y504300D01*
X1503875Y504258D01*
X1503333Y504342D01*
X1503042Y504467D01*
X1502750Y504675D01*
X1502542Y504967D01*
X1502500Y505258D01*
X1502583Y505550D01*
X1502792Y505758D01*
G01X1505000Y508150D02*
X1502500D01*
X1503000Y507650D01*
G01X1505000D02*
Y508650D01*
G01X1500400Y545450D02*
X1504400D01*
Y552850D01*
G01X1477334Y527967D02*
X1474834D01*
Y529008D01*
X1474959Y529342D01*
X1475126Y529550D01*
X1475459Y529633D01*
X1475792Y529550D01*
X1476001Y529300D01*
X1476126Y529008D01*
Y527967D01*
G01Y529008D02*
X1477334Y529633D01*
G01Y531900D02*
X1474834D01*
X1475334Y531400D01*
G01X1477334D02*
Y532400D01*
G01X1474834Y535000D02*
X1474917Y534667D01*
X1475126Y534417D01*
X1475376Y534250D01*
X1475709Y534125D01*
X1476084Y534083D01*
X1476459Y534125D01*
X1476792Y534250D01*
X1477042Y534417D01*
X1477251Y534667D01*
X1477334Y535000D01*
X1477251Y535333D01*
X1477042Y535583D01*
X1476792Y535750D01*
X1476459Y535875D01*
X1476084Y535917D01*
X1475709Y535875D01*
X1475376Y535750D01*
X1475126Y535583D01*
X1474917Y535333D01*
X1474834Y535000D01*
G01X1477334Y538017D02*
X1476792Y538100D01*
X1476334Y538225D01*
X1475917Y538392D01*
X1475459Y538600D01*
X1474834Y538933D01*
Y537267D01*
G01X1477334Y541700D02*
X1474834D01*
X1476626Y540158D01*
Y542242D01*
G01X1520067Y522900D02*
Y525400D01*
X1521108D01*
X1521442Y525275D01*
X1521650Y525108D01*
X1521733Y524775D01*
X1521650Y524442D01*
X1521400Y524233D01*
X1521108Y524108D01*
X1520067D01*
G01X1521108D02*
X1521733Y522900D01*
G01X1524000D02*
Y525400D01*
X1523500Y524900D01*
G01Y522900D02*
X1524500D01*
G01X1527100Y525400D02*
X1526767Y525317D01*
X1526517Y525108D01*
X1526350Y524858D01*
X1526225Y524525D01*
X1526183Y524150D01*
X1526225Y523775D01*
X1526350Y523442D01*
X1526517Y523192D01*
X1526767Y522983D01*
X1527100Y522900D01*
X1527433Y522983D01*
X1527683Y523192D01*
X1527850Y523442D01*
X1527975Y523775D01*
X1528017Y524150D01*
X1527975Y524525D01*
X1527850Y524858D01*
X1527683Y525108D01*
X1527433Y525317D01*
X1527100Y525400D01*
G01X1530117Y522900D02*
X1530200Y523442D01*
X1530325Y523900D01*
X1530492Y524317D01*
X1530700Y524775D01*
X1531033Y525400D01*
X1529367D01*
G01X1532383Y523275D02*
X1532633Y523067D01*
X1532925Y522942D01*
X1533300Y522900D01*
X1533675Y522983D01*
X1533967Y523150D01*
X1534175Y523442D01*
X1534217Y523775D01*
X1534133Y524108D01*
X1533925Y524317D01*
X1533633Y524483D01*
X1533342Y524525D01*
X1533050Y524483D01*
X1532675Y524317D01*
X1532800Y525400D01*
X1533925D01*
G01X1481400Y527900D02*
Y523900D01*
X1488800D01*
G01X1510467Y528000D02*
Y530500D01*
X1511508D01*
X1511842Y530375D01*
X1512050Y530208D01*
X1512133Y529875D01*
X1512050Y529542D01*
X1511800Y529333D01*
X1511508Y529208D01*
X1510467D01*
G01X1511508D02*
X1512133Y528000D01*
G01X1514400D02*
Y530500D01*
X1513900Y530000D01*
G01Y528000D02*
X1514900D01*
G01X1517500Y530500D02*
X1517167Y530417D01*
X1516917Y530208D01*
X1516750Y529958D01*
X1516625Y529625D01*
X1516583Y529250D01*
X1516625Y528875D01*
X1516750Y528542D01*
X1516917Y528292D01*
X1517167Y528083D01*
X1517500Y528000D01*
X1517833Y528083D01*
X1518083Y528292D01*
X1518250Y528542D01*
X1518375Y528875D01*
X1518417Y529250D01*
X1518375Y529625D01*
X1518250Y529958D01*
X1518083Y530208D01*
X1517833Y530417D01*
X1517500Y530500D01*
G01X1520600Y528000D02*
X1520892Y528042D01*
X1521225Y528167D01*
X1521433Y528375D01*
X1521517Y528667D01*
X1521433Y528958D01*
X1521183Y529208D01*
X1520808Y529333D01*
X1520392D01*
X1520142Y529417D01*
X1519933Y529625D01*
X1519850Y529917D01*
X1519975Y530208D01*
X1520267Y530417D01*
X1520600Y530500D01*
X1520933Y530417D01*
X1521225Y530208D01*
X1521350Y529917D01*
X1521267Y529625D01*
X1521058Y529417D01*
X1520808Y529333D01*
X1520392D01*
X1520017Y529208D01*
X1519767Y528958D01*
X1519683Y528667D01*
X1519767Y528375D01*
X1519975Y528167D01*
X1520308Y528042D01*
X1520600Y528000D01*
G01X1522908Y530083D02*
X1523158Y530333D01*
X1523450Y530458D01*
X1523783Y530500D01*
X1524200Y530417D01*
X1524492Y530208D01*
X1524575Y529958D01*
X1524533Y529708D01*
X1524367Y529500D01*
X1523533Y529083D01*
X1523158Y528792D01*
X1522908Y528375D01*
X1522825Y528000D01*
X1524575D01*
G01X1478400Y532900D02*
Y528900D01*
X1485800D01*
G01X1493967Y514000D02*
Y516500D01*
X1495008D01*
X1495342Y516375D01*
X1495550Y516208D01*
X1495633Y515875D01*
X1495550Y515542D01*
X1495300Y515333D01*
X1495008Y515208D01*
X1493967D01*
G01X1495008D02*
X1495633Y514000D01*
G01X1497900D02*
Y516500D01*
X1497400Y516000D01*
G01Y514000D02*
X1498400D01*
G01X1501000Y516500D02*
X1500667Y516417D01*
X1500417Y516208D01*
X1500250Y515958D01*
X1500125Y515625D01*
X1500083Y515250D01*
X1500125Y514875D01*
X1500250Y514542D01*
X1500417Y514292D01*
X1500667Y514083D01*
X1501000Y514000D01*
X1501333Y514083D01*
X1501583Y514292D01*
X1501750Y514542D01*
X1501875Y514875D01*
X1501917Y515250D01*
X1501875Y515625D01*
X1501750Y515958D01*
X1501583Y516208D01*
X1501333Y516417D01*
X1501000Y516500D01*
G01X1503392Y514292D02*
X1503683Y514083D01*
X1504017Y514000D01*
X1504350Y514083D01*
X1504642Y514333D01*
X1504850Y514708D01*
X1504933Y515083D01*
Y515542D01*
X1504850Y515917D01*
X1504642Y516250D01*
X1504392Y516417D01*
X1504100Y516500D01*
X1503767Y516417D01*
X1503517Y516250D01*
X1503350Y516000D01*
X1503267Y515667D01*
X1503350Y515375D01*
X1503558Y515083D01*
X1503808Y514917D01*
X1504100Y514875D01*
X1504433Y514958D01*
X1504683Y515167D01*
X1504933Y515542D01*
G01X1507200Y516500D02*
X1506867Y516417D01*
X1506617Y516208D01*
X1506450Y515958D01*
X1506325Y515625D01*
X1506283Y515250D01*
X1506325Y514875D01*
X1506450Y514542D01*
X1506617Y514292D01*
X1506867Y514083D01*
X1507200Y514000D01*
X1507533Y514083D01*
X1507783Y514292D01*
X1507950Y514542D01*
X1508075Y514875D01*
X1508117Y515250D01*
X1508075Y515625D01*
X1507950Y515958D01*
X1507783Y516208D01*
X1507533Y516417D01*
X1507200Y516500D01*
G01X1509967Y514000D02*
Y516500D01*
X1511008D01*
X1511342Y516375D01*
X1511550Y516208D01*
X1511633Y515875D01*
X1511550Y515542D01*
X1511300Y515333D01*
X1511008Y515208D01*
X1509967D01*
G01X1511008D02*
X1511633Y514000D01*
G01X1513900D02*
Y516500D01*
X1513400Y516000D01*
G01Y514000D02*
X1514400D01*
G01X1517000Y516500D02*
X1516667Y516417D01*
X1516417Y516208D01*
X1516250Y515958D01*
X1516125Y515625D01*
X1516083Y515250D01*
X1516125Y514875D01*
X1516250Y514542D01*
X1516417Y514292D01*
X1516667Y514083D01*
X1517000Y514000D01*
X1517333Y514083D01*
X1517583Y514292D01*
X1517750Y514542D01*
X1517875Y514875D01*
X1517917Y515250D01*
X1517875Y515625D01*
X1517750Y515958D01*
X1517583Y516208D01*
X1517333Y516417D01*
X1517000Y516500D01*
G01X1519392Y514292D02*
X1519683Y514083D01*
X1520017Y514000D01*
X1520350Y514083D01*
X1520642Y514333D01*
X1520850Y514708D01*
X1520933Y515083D01*
Y515542D01*
X1520850Y515917D01*
X1520642Y516250D01*
X1520392Y516417D01*
X1520100Y516500D01*
X1519767Y516417D01*
X1519517Y516250D01*
X1519350Y516000D01*
X1519267Y515667D01*
X1519350Y515375D01*
X1519558Y515083D01*
X1519808Y514917D01*
X1520100Y514875D01*
X1520433Y514958D01*
X1520683Y515167D01*
X1520933Y515542D01*
G01X1522408Y516083D02*
X1522658Y516333D01*
X1522950Y516458D01*
X1523283Y516500D01*
X1523700Y516417D01*
X1523992Y516208D01*
X1524075Y515958D01*
X1524033Y515708D01*
X1523867Y515500D01*
X1523033Y515083D01*
X1522658Y514792D01*
X1522408Y514375D01*
X1522325Y514000D01*
X1524075D01*
G01X1504340Y536369D02*
X1496740D01*
G01X1504340Y525569D02*
Y536369D01*
G01X1496740Y525569D02*
X1504340D01*
G01X1496740Y536369D02*
Y525569D01*
G01X1496333Y547483D02*
X1498125D01*
X1498500Y547650D01*
X1498750Y547983D01*
X1498833Y548400D01*
X1498750Y548817D01*
X1498500Y549150D01*
X1498125Y549317D01*
X1496333D01*
G01X1498333Y550583D02*
X1498625Y550833D01*
X1498791Y551167D01*
X1498833Y551542D01*
X1498791Y551875D01*
X1498583Y552208D01*
X1498333Y552417D01*
X1498083Y552458D01*
X1497791Y552375D01*
X1497583Y552083D01*
X1497500Y551792D01*
Y551417D01*
G01Y551792D02*
X1497375Y552042D01*
X1497166Y552250D01*
X1496916Y552333D01*
X1496666Y552250D01*
X1496458Y552042D01*
X1496333Y551667D01*
X1496375Y551292D01*
X1496541Y550917D01*
G01X1498833Y554600D02*
X1496333D01*
X1496833Y554100D01*
G01X1498833D02*
Y555100D01*
G01X1481158Y542775D02*
Y552775D01*
G01X1494558Y542775D02*
X1481158D01*
G01X1494558Y552775D02*
Y542775D01*
G01X1522531Y544876D02*
X1520031D01*
Y545710D01*
X1520156Y546043D01*
X1520323Y546293D01*
X1520573Y546501D01*
X1520864Y546668D01*
X1521281Y546710D01*
X1521698Y546668D01*
X1521989Y546501D01*
X1522239Y546293D01*
X1522406Y546043D01*
X1522531Y545710D01*
Y544876D01*
G01Y549393D02*
X1520031D01*
X1521823Y547851D01*
Y549935D01*
G01X1522031Y551076D02*
X1522323Y551326D01*
X1522489Y551660D01*
X1522531Y552035D01*
X1522489Y552368D01*
X1522281Y552701D01*
X1522031Y552910D01*
X1521781Y552951D01*
X1521489Y552868D01*
X1521281Y552576D01*
X1521198Y552285D01*
Y551910D01*
G01Y552285D02*
X1521073Y552535D01*
X1520864Y552743D01*
X1520614Y552826D01*
X1520364Y552743D01*
X1520156Y552535D01*
X1520031Y552160D01*
X1520073Y551785D01*
X1520239Y551410D01*
G01X1510797Y540511D02*
Y556611D01*
G01X1517797Y540511D02*
X1510797D01*
G01X1517797Y556611D02*
Y540511D01*
G01X1513218Y674248D02*
X1518268D01*
Y772948D01*
X1542918D01*
Y588548D01*
X1518268D01*
Y647248D01*
X1513218D01*
Y674248D01*
G01X1503500Y556467D02*
X1501000D01*
Y557508D01*
X1501125Y557842D01*
X1501292Y558050D01*
X1501625Y558133D01*
X1501958Y558050D01*
X1502167Y557800D01*
X1502292Y557508D01*
Y556467D01*
G01Y557508D02*
X1503500Y558133D01*
G01Y560400D02*
X1501000D01*
X1501500Y559900D01*
G01X1503500D02*
Y560900D01*
G01X1501000Y563500D02*
X1501083Y563167D01*
X1501292Y562917D01*
X1501542Y562750D01*
X1501875Y562625D01*
X1502250Y562583D01*
X1502625Y562625D01*
X1502958Y562750D01*
X1503208Y562917D01*
X1503417Y563167D01*
X1503500Y563500D01*
X1503417Y563833D01*
X1503208Y564083D01*
X1502958Y564250D01*
X1502625Y564375D01*
X1502250Y564417D01*
X1501875Y564375D01*
X1501542Y564250D01*
X1501292Y564083D01*
X1501083Y563833D01*
X1501000Y563500D01*
G01Y566600D02*
X1501083Y566267D01*
X1501292Y566017D01*
X1501542Y565850D01*
X1501875Y565725D01*
X1502250Y565683D01*
X1502625Y565725D01*
X1502958Y565850D01*
X1503208Y566017D01*
X1503417Y566267D01*
X1503500Y566600D01*
X1503417Y566933D01*
X1503208Y567183D01*
X1502958Y567350D01*
X1502625Y567475D01*
X1502250Y567517D01*
X1501875Y567475D01*
X1501542Y567350D01*
X1501292Y567183D01*
X1501083Y566933D01*
X1501000Y566600D01*
G01X1503500Y569700D02*
X1503458Y569992D01*
X1503333Y570325D01*
X1503125Y570533D01*
X1502833Y570617D01*
X1502542Y570533D01*
X1502292Y570283D01*
X1502167Y569908D01*
Y569492D01*
X1502083Y569242D01*
X1501875Y569033D01*
X1501583Y568950D01*
X1501292Y569075D01*
X1501083Y569367D01*
X1501000Y569700D01*
X1501083Y570033D01*
X1501292Y570325D01*
X1501583Y570450D01*
X1501875Y570367D01*
X1502083Y570158D01*
X1502167Y569908D01*
Y569492D01*
X1502292Y569117D01*
X1502542Y568867D01*
X1502833Y568783D01*
X1503125Y568867D01*
X1503333Y569075D01*
X1503458Y569408D01*
X1503500Y569700D01*
G01X1481567Y568400D02*
Y570900D01*
X1482608D01*
X1482942Y570775D01*
X1483150Y570608D01*
X1483233Y570275D01*
X1483150Y569942D01*
X1482900Y569733D01*
X1482608Y569608D01*
X1481567D01*
G01X1482608D02*
X1483233Y568400D01*
G01X1485500D02*
Y570900D01*
X1485000Y570400D01*
G01Y568400D02*
X1486000D01*
G01X1488600Y570900D02*
X1488267Y570817D01*
X1488017Y570608D01*
X1487850Y570358D01*
X1487725Y570025D01*
X1487683Y569650D01*
X1487725Y569275D01*
X1487850Y568942D01*
X1488017Y568692D01*
X1488267Y568483D01*
X1488600Y568400D01*
X1488933Y568483D01*
X1489183Y568692D01*
X1489350Y568942D01*
X1489475Y569275D01*
X1489517Y569650D01*
X1489475Y570025D01*
X1489350Y570358D01*
X1489183Y570608D01*
X1488933Y570817D01*
X1488600Y570900D01*
G01X1491617Y568400D02*
X1491700Y568942D01*
X1491825Y569400D01*
X1491992Y569817D01*
X1492200Y570275D01*
X1492533Y570900D01*
X1490867D01*
G01X1494008Y569442D02*
X1494300Y569733D01*
X1494550Y569900D01*
X1494883Y569983D01*
X1495175Y569900D01*
X1495383Y569733D01*
X1495550Y569483D01*
X1495592Y569192D01*
X1495550Y568942D01*
X1495383Y568692D01*
X1495133Y568483D01*
X1494842Y568400D01*
X1494508Y568483D01*
X1494217Y568733D01*
X1494050Y569108D01*
X1494008Y569525D01*
X1494092Y570067D01*
X1494217Y570358D01*
X1494425Y570650D01*
X1494717Y570858D01*
X1495008Y570900D01*
X1495300Y570817D01*
X1495508Y570608D01*
G01X1480400Y562400D02*
Y558400D01*
X1487800D01*
G01X1481567Y564100D02*
Y566600D01*
X1482608D01*
X1482942Y566475D01*
X1483150Y566308D01*
X1483233Y565975D01*
X1483150Y565642D01*
X1482900Y565433D01*
X1482608Y565308D01*
X1481567D01*
G01X1482608D02*
X1483233Y564100D01*
G01X1485500D02*
Y566600D01*
X1485000Y566100D01*
G01Y564100D02*
X1486000D01*
G01X1488600Y566600D02*
X1488267Y566517D01*
X1488017Y566308D01*
X1487850Y566058D01*
X1487725Y565725D01*
X1487683Y565350D01*
X1487725Y564975D01*
X1487850Y564642D01*
X1488017Y564392D01*
X1488267Y564183D01*
X1488600Y564100D01*
X1488933Y564183D01*
X1489183Y564392D01*
X1489350Y564642D01*
X1489475Y564975D01*
X1489517Y565350D01*
X1489475Y565725D01*
X1489350Y566058D01*
X1489183Y566308D01*
X1488933Y566517D01*
X1488600Y566600D01*
G01X1491617Y564100D02*
X1491700Y564642D01*
X1491825Y565100D01*
X1491992Y565517D01*
X1492200Y565975D01*
X1492533Y566600D01*
X1490867D01*
G01X1494717Y564100D02*
X1494800Y564642D01*
X1494925Y565100D01*
X1495092Y565517D01*
X1495300Y565975D01*
X1495633Y566600D01*
X1493967D01*
G01X1480400Y558100D02*
Y554100D01*
X1487800D01*
G01X1488200Y582567D02*
X1485700D01*
Y583608D01*
X1485825Y583942D01*
X1485992Y584150D01*
X1486325Y584233D01*
X1486658Y584150D01*
X1486867Y583900D01*
X1486992Y583608D01*
Y582567D01*
G01Y583608D02*
X1488200Y584233D01*
G01Y586500D02*
X1485700D01*
X1486200Y586000D01*
G01X1488200D02*
Y587000D01*
G01X1485700Y589600D02*
X1485783Y589267D01*
X1485992Y589017D01*
X1486242Y588850D01*
X1486575Y588725D01*
X1486950Y588683D01*
X1487325Y588725D01*
X1487658Y588850D01*
X1487908Y589017D01*
X1488117Y589267D01*
X1488200Y589600D01*
X1488117Y589933D01*
X1487908Y590183D01*
X1487658Y590350D01*
X1487325Y590475D01*
X1486950Y590517D01*
X1486575Y590475D01*
X1486242Y590350D01*
X1485992Y590183D01*
X1485783Y589933D01*
X1485700Y589600D01*
G01X1488200Y592617D02*
X1487658Y592700D01*
X1487200Y592825D01*
X1486783Y592992D01*
X1486325Y593200D01*
X1485700Y593533D01*
Y591867D01*
G01X1487908Y595092D02*
X1488117Y595383D01*
X1488200Y595717D01*
X1488117Y596050D01*
X1487867Y596342D01*
X1487492Y596550D01*
X1487117Y596633D01*
X1486658D01*
X1486283Y596550D01*
X1485950Y596342D01*
X1485783Y596092D01*
X1485700Y595800D01*
X1485783Y595467D01*
X1485950Y595217D01*
X1486200Y595050D01*
X1486533Y594967D01*
X1486825Y595050D01*
X1487117Y595258D01*
X1487283Y595508D01*
X1487325Y595800D01*
X1487242Y596133D01*
X1487033Y596383D01*
X1486658Y596633D01*
G01X1480700Y577800D02*
X1476700D01*
Y570400D01*
G01X1484200Y582567D02*
X1481700D01*
Y583608D01*
X1481825Y583942D01*
X1481992Y584150D01*
X1482325Y584233D01*
X1482658Y584150D01*
X1482867Y583900D01*
X1482992Y583608D01*
Y582567D01*
G01Y583608D02*
X1484200Y584233D01*
G01Y586500D02*
X1481700D01*
X1482200Y586000D01*
G01X1484200D02*
Y587000D01*
G01X1481700Y589600D02*
X1481783Y589267D01*
X1481992Y589017D01*
X1482242Y588850D01*
X1482575Y588725D01*
X1482950Y588683D01*
X1483325Y588725D01*
X1483658Y588850D01*
X1483908Y589017D01*
X1484117Y589267D01*
X1484200Y589600D01*
X1484117Y589933D01*
X1483908Y590183D01*
X1483658Y590350D01*
X1483325Y590475D01*
X1482950Y590517D01*
X1482575Y590475D01*
X1482242Y590350D01*
X1481992Y590183D01*
X1481783Y589933D01*
X1481700Y589600D01*
G01X1484200Y592700D02*
X1484158Y592992D01*
X1484033Y593325D01*
X1483825Y593533D01*
X1483533Y593617D01*
X1483242Y593533D01*
X1482992Y593283D01*
X1482867Y592908D01*
Y592492D01*
X1482783Y592242D01*
X1482575Y592033D01*
X1482283Y591950D01*
X1481992Y592075D01*
X1481783Y592367D01*
X1481700Y592700D01*
X1481783Y593033D01*
X1481992Y593325D01*
X1482283Y593450D01*
X1482575Y593367D01*
X1482783Y593158D01*
X1482867Y592908D01*
Y592492D01*
X1482992Y592117D01*
X1483242Y591867D01*
X1483533Y591783D01*
X1483825Y591867D01*
X1484033Y592075D01*
X1484158Y592408D01*
X1484200Y592700D01*
G01X1483825Y594883D02*
X1484033Y595133D01*
X1484158Y595425D01*
X1484200Y595800D01*
X1484117Y596175D01*
X1483950Y596467D01*
X1483658Y596675D01*
X1483325Y596717D01*
X1482992Y596633D01*
X1482783Y596425D01*
X1482617Y596133D01*
X1482575Y595842D01*
X1482617Y595550D01*
X1482783Y595175D01*
X1481700Y595300D01*
Y596425D01*
G01X1480200Y582567D02*
X1477700D01*
Y583608D01*
X1477825Y583942D01*
X1477992Y584150D01*
X1478325Y584233D01*
X1478658Y584150D01*
X1478867Y583900D01*
X1478992Y583608D01*
Y582567D01*
G01Y583608D02*
X1480200Y584233D01*
G01Y586500D02*
X1477700D01*
X1478200Y586000D01*
G01X1480200D02*
Y587000D01*
G01X1477700Y589600D02*
X1477783Y589267D01*
X1477992Y589017D01*
X1478242Y588850D01*
X1478575Y588725D01*
X1478950Y588683D01*
X1479325Y588725D01*
X1479658Y588850D01*
X1479908Y589017D01*
X1480117Y589267D01*
X1480200Y589600D01*
X1480117Y589933D01*
X1479908Y590183D01*
X1479658Y590350D01*
X1479325Y590475D01*
X1478950Y590517D01*
X1478575Y590475D01*
X1478242Y590350D01*
X1477992Y590183D01*
X1477783Y589933D01*
X1477700Y589600D01*
G01X1480200Y592700D02*
X1480158Y592992D01*
X1480033Y593325D01*
X1479825Y593533D01*
X1479533Y593617D01*
X1479242Y593533D01*
X1478992Y593283D01*
X1478867Y592908D01*
Y592492D01*
X1478783Y592242D01*
X1478575Y592033D01*
X1478283Y591950D01*
X1477992Y592075D01*
X1477783Y592367D01*
X1477700Y592700D01*
X1477783Y593033D01*
X1477992Y593325D01*
X1478283Y593450D01*
X1478575Y593367D01*
X1478783Y593158D01*
X1478867Y592908D01*
Y592492D01*
X1478992Y592117D01*
X1479242Y591867D01*
X1479533Y591783D01*
X1479825Y591867D01*
X1480033Y592075D01*
X1480158Y592408D01*
X1480200Y592700D01*
G01X1479908Y595092D02*
X1480117Y595383D01*
X1480200Y595717D01*
X1480117Y596050D01*
X1479867Y596342D01*
X1479492Y596550D01*
X1479117Y596633D01*
X1478658D01*
X1478283Y596550D01*
X1477950Y596342D01*
X1477783Y596092D01*
X1477700Y595800D01*
X1477783Y595467D01*
X1477950Y595217D01*
X1478200Y595050D01*
X1478533Y594967D01*
X1478825Y595050D01*
X1479117Y595258D01*
X1479283Y595508D01*
X1479325Y595800D01*
X1479242Y596133D01*
X1479033Y596383D01*
X1478658Y596633D01*
G01X1481158Y552775D02*
X1494558D01*
G01X1510797Y556611D02*
X1517797D01*
G01X1476517Y646000D02*
Y648500D01*
X1477558D01*
X1477892Y648375D01*
X1478100Y648208D01*
X1478183Y647875D01*
X1478100Y647542D01*
X1477850Y647333D01*
X1477558Y647208D01*
X1476517D01*
G01X1477558D02*
X1478183Y646000D01*
G01X1479533Y646375D02*
X1479783Y646167D01*
X1480075Y646042D01*
X1480450Y646000D01*
X1480825Y646083D01*
X1481117Y646250D01*
X1481325Y646542D01*
X1481367Y646875D01*
X1481283Y647208D01*
X1481075Y647417D01*
X1480783Y647583D01*
X1480492Y647625D01*
X1480200Y647583D01*
X1479825Y647417D01*
X1479950Y648500D01*
X1481075D01*
G01X1483550Y646000D02*
X1483842Y646042D01*
X1484175Y646167D01*
X1484383Y646375D01*
X1484467Y646667D01*
X1484383Y646958D01*
X1484133Y647208D01*
X1483758Y647333D01*
X1483342D01*
X1483092Y647417D01*
X1482883Y647625D01*
X1482800Y647917D01*
X1482925Y648208D01*
X1483217Y648417D01*
X1483550Y648500D01*
X1483883Y648417D01*
X1484175Y648208D01*
X1484300Y647917D01*
X1484217Y647625D01*
X1484008Y647417D01*
X1483758Y647333D01*
X1483342D01*
X1482967Y647208D01*
X1482717Y646958D01*
X1482633Y646667D01*
X1482717Y646375D01*
X1482925Y646167D01*
X1483258Y646042D01*
X1483550Y646000D01*
G01X1485733Y646500D02*
X1485983Y646208D01*
X1486317Y646042D01*
X1486692Y646000D01*
X1487025Y646042D01*
X1487358Y646250D01*
X1487567Y646500D01*
X1487608Y646750D01*
X1487525Y647042D01*
X1487233Y647250D01*
X1486942Y647333D01*
X1486567D01*
G01X1486942D02*
X1487192Y647458D01*
X1487400Y647667D01*
X1487483Y647917D01*
X1487400Y648167D01*
X1487192Y648375D01*
X1486817Y648500D01*
X1486442Y648458D01*
X1486067Y648292D01*
G01X1476696Y642417D02*
Y644917D01*
X1477530D01*
X1477863Y644792D01*
X1478113Y644625D01*
X1478321Y644375D01*
X1478488Y644084D01*
X1478530Y643667D01*
X1478488Y643250D01*
X1478321Y642959D01*
X1478113Y642709D01*
X1477863Y642542D01*
X1477530Y642417D01*
X1476696D01*
G01X1480713D02*
Y644917D01*
X1480213Y644417D01*
G01Y642417D02*
X1481213D01*
G01X1483105Y642709D02*
X1483396Y642500D01*
X1483730Y642417D01*
X1484063Y642500D01*
X1484355Y642750D01*
X1484563Y643125D01*
X1484646Y643500D01*
Y643959D01*
X1484563Y644334D01*
X1484355Y644667D01*
X1484105Y644834D01*
X1483813Y644917D01*
X1483480Y644834D01*
X1483230Y644667D01*
X1483063Y644417D01*
X1482980Y644084D01*
X1483063Y643792D01*
X1483271Y643500D01*
X1483521Y643334D01*
X1483813Y643292D01*
X1484146Y643375D01*
X1484396Y643584D01*
X1484646Y643959D01*
G01X1495970Y625440D02*
X1495720Y625565D01*
X1495428Y625648D01*
X1495095D01*
X1494720Y625523D01*
X1494428Y625315D01*
X1494220Y625065D01*
X1494053Y624648D01*
X1494011Y624273D01*
X1494095Y623898D01*
X1494220Y623648D01*
X1494470Y623398D01*
X1494761Y623231D01*
X1495053Y623148D01*
X1495345D01*
X1495636Y623231D01*
X1495886Y623356D01*
X1496095Y623523D01*
G01X1497361Y625231D02*
X1497611Y625481D01*
X1497903Y625606D01*
X1498236Y625648D01*
X1498653Y625565D01*
X1498945Y625356D01*
X1499028Y625106D01*
X1498986Y624856D01*
X1498820Y624648D01*
X1497986Y624231D01*
X1497611Y623940D01*
X1497361Y623523D01*
X1497278Y623148D01*
X1499028D01*
G01X1500545Y623440D02*
X1500836Y623231D01*
X1501170Y623148D01*
X1501503Y623231D01*
X1501795Y623481D01*
X1502003Y623856D01*
X1502086Y624231D01*
Y624690D01*
X1502003Y625065D01*
X1501795Y625398D01*
X1501545Y625565D01*
X1501253Y625648D01*
X1500920Y625565D01*
X1500670Y625398D01*
X1500503Y625148D01*
X1500420Y624815D01*
X1500503Y624523D01*
X1500711Y624231D01*
X1500961Y624065D01*
X1501253Y624023D01*
X1501586Y624106D01*
X1501836Y624315D01*
X1502086Y624690D01*
G01X1503645Y623440D02*
X1503936Y623231D01*
X1504270Y623148D01*
X1504603Y623231D01*
X1504895Y623481D01*
X1505103Y623856D01*
X1505186Y624231D01*
Y624690D01*
X1505103Y625065D01*
X1504895Y625398D01*
X1504645Y625565D01*
X1504353Y625648D01*
X1504020Y625565D01*
X1503770Y625398D01*
X1503603Y625148D01*
X1503520Y624815D01*
X1503603Y624523D01*
X1503811Y624231D01*
X1504061Y624065D01*
X1504353Y624023D01*
X1504686Y624106D01*
X1504936Y624315D01*
X1505186Y624690D01*
G01X1495767Y629792D02*
X1495517Y629917D01*
X1495225Y630000D01*
X1494892D01*
X1494517Y629875D01*
X1494225Y629667D01*
X1494017Y629417D01*
X1493850Y629000D01*
X1493808Y628625D01*
X1493892Y628250D01*
X1494017Y628000D01*
X1494267Y627750D01*
X1494558Y627583D01*
X1494850Y627500D01*
X1495142D01*
X1495433Y627583D01*
X1495683Y627708D01*
X1495892Y627875D01*
G01X1497158Y629583D02*
X1497408Y629833D01*
X1497700Y629958D01*
X1498033Y630000D01*
X1498450Y629917D01*
X1498742Y629708D01*
X1498825Y629458D01*
X1498783Y629208D01*
X1498617Y629000D01*
X1497783Y628583D01*
X1497408Y628292D01*
X1497158Y627875D01*
X1497075Y627500D01*
X1498825D01*
G01X1500342Y627792D02*
X1500633Y627583D01*
X1500967Y627500D01*
X1501300Y627583D01*
X1501592Y627833D01*
X1501800Y628208D01*
X1501883Y628583D01*
Y629042D01*
X1501800Y629417D01*
X1501592Y629750D01*
X1501342Y629917D01*
X1501050Y630000D01*
X1500717Y629917D01*
X1500467Y629750D01*
X1500300Y629500D01*
X1500217Y629167D01*
X1500300Y628875D01*
X1500508Y628583D01*
X1500758Y628417D01*
X1501050Y628375D01*
X1501383Y628458D01*
X1501633Y628667D01*
X1501883Y629042D01*
G01X1504150Y627500D02*
X1504442Y627542D01*
X1504775Y627667D01*
X1504983Y627875D01*
X1505067Y628167D01*
X1504983Y628458D01*
X1504733Y628708D01*
X1504358Y628833D01*
X1503942D01*
X1503692Y628917D01*
X1503483Y629125D01*
X1503400Y629417D01*
X1503525Y629708D01*
X1503817Y629917D01*
X1504150Y630000D01*
X1504483Y629917D01*
X1504775Y629708D01*
X1504900Y629417D01*
X1504817Y629125D01*
X1504608Y628917D01*
X1504358Y628833D01*
X1503942D01*
X1503567Y628708D01*
X1503317Y628458D01*
X1503233Y628167D01*
X1503317Y627875D01*
X1503525Y627667D01*
X1503858Y627542D01*
X1504150Y627500D01*
G01X1497725Y699517D02*
Y695517D01*
X1505125D01*
G01X1485792Y696309D02*
X1485542Y696434D01*
X1485250Y696517D01*
X1484917D01*
X1484542Y696392D01*
X1484250Y696184D01*
X1484042Y695934D01*
X1483875Y695517D01*
X1483833Y695142D01*
X1483917Y694767D01*
X1484042Y694517D01*
X1484292Y694267D01*
X1484583Y694100D01*
X1484875Y694017D01*
X1485167D01*
X1485458Y694100D01*
X1485708Y694225D01*
X1485917Y694392D01*
G01X1487058Y694517D02*
X1487308Y694225D01*
X1487642Y694059D01*
X1488017Y694017D01*
X1488350Y694059D01*
X1488683Y694267D01*
X1488892Y694517D01*
X1488933Y694767D01*
X1488850Y695059D01*
X1488558Y695267D01*
X1488267Y695350D01*
X1487892D01*
G01X1488267D02*
X1488517Y695475D01*
X1488725Y695684D01*
X1488808Y695934D01*
X1488725Y696184D01*
X1488517Y696392D01*
X1488142Y696517D01*
X1487767Y696475D01*
X1487392Y696309D01*
G01X1491075Y696517D02*
X1490742Y696434D01*
X1490492Y696225D01*
X1490325Y695975D01*
X1490200Y695642D01*
X1490158Y695267D01*
X1490200Y694892D01*
X1490325Y694559D01*
X1490492Y694309D01*
X1490742Y694100D01*
X1491075Y694017D01*
X1491408Y694100D01*
X1491658Y694309D01*
X1491825Y694559D01*
X1491950Y694892D01*
X1491992Y695267D01*
X1491950Y695642D01*
X1491825Y695975D01*
X1491658Y696225D01*
X1491408Y696434D01*
X1491075Y696517D01*
G01X1493258Y694517D02*
X1493508Y694225D01*
X1493842Y694059D01*
X1494217Y694017D01*
X1494550Y694059D01*
X1494883Y694267D01*
X1495092Y694517D01*
X1495133Y694767D01*
X1495050Y695059D01*
X1494758Y695267D01*
X1494467Y695350D01*
X1494092D01*
G01X1494467D02*
X1494717Y695475D01*
X1494925Y695684D01*
X1495008Y695934D01*
X1494925Y696184D01*
X1494717Y696392D01*
X1494342Y696517D01*
X1493967Y696475D01*
X1493592Y696309D01*
G01X1484042Y698117D02*
Y700617D01*
X1485083D01*
X1485417Y700492D01*
X1485625Y700325D01*
X1485708Y699992D01*
X1485625Y699659D01*
X1485375Y699450D01*
X1485083Y699325D01*
X1484042D01*
G01X1485083D02*
X1485708Y698117D01*
G01X1487058Y698492D02*
X1487308Y698284D01*
X1487600Y698159D01*
X1487975Y698117D01*
X1488350Y698200D01*
X1488642Y698367D01*
X1488850Y698659D01*
X1488892Y698992D01*
X1488808Y699325D01*
X1488600Y699534D01*
X1488308Y699700D01*
X1488017Y699742D01*
X1487725Y699700D01*
X1487350Y699534D01*
X1487475Y700617D01*
X1488600D01*
G01X1490367Y698409D02*
X1490658Y698200D01*
X1490992Y698117D01*
X1491325Y698200D01*
X1491617Y698450D01*
X1491825Y698825D01*
X1491908Y699200D01*
Y699659D01*
X1491825Y700034D01*
X1491617Y700367D01*
X1491367Y700534D01*
X1491075Y700617D01*
X1490742Y700534D01*
X1490492Y700367D01*
X1490325Y700117D01*
X1490242Y699784D01*
X1490325Y699492D01*
X1490533Y699200D01*
X1490783Y699034D01*
X1491075Y698992D01*
X1491408Y699075D01*
X1491658Y699284D01*
X1491908Y699659D01*
G01X1494175Y700617D02*
X1493842Y700534D01*
X1493592Y700325D01*
X1493425Y700075D01*
X1493300Y699742D01*
X1493258Y699367D01*
X1493300Y698992D01*
X1493425Y698659D01*
X1493592Y698409D01*
X1493842Y698200D01*
X1494175Y698117D01*
X1494508Y698200D01*
X1494758Y698409D01*
X1494925Y698659D01*
X1495050Y698992D01*
X1495092Y699367D01*
X1495050Y699742D01*
X1494925Y700075D01*
X1494758Y700325D01*
X1494508Y700534D01*
X1494175Y700617D01*
G01X1490800Y730166D02*
Y727666D01*
G01X1489842Y730166D02*
X1491758D01*
G01X1493067Y727666D02*
Y730166D01*
X1494067D01*
X1494400Y730041D01*
X1494650Y729749D01*
X1494733Y729416D01*
X1494650Y729083D01*
X1494442Y728833D01*
X1494067Y728708D01*
X1493067D01*
G01X1497000Y727666D02*
Y730166D01*
X1496500Y729666D01*
G01Y727666D02*
X1497500D01*
G01X1500100Y730166D02*
X1499767Y730083D01*
X1499517Y729874D01*
X1499350Y729624D01*
X1499225Y729291D01*
X1499183Y728916D01*
X1499225Y728541D01*
X1499350Y728208D01*
X1499517Y727958D01*
X1499767Y727749D01*
X1500100Y727666D01*
X1500433Y727749D01*
X1500683Y727958D01*
X1500850Y728208D01*
X1500975Y728541D01*
X1501017Y728916D01*
X1500975Y729291D01*
X1500850Y729624D01*
X1500683Y729874D01*
X1500433Y730083D01*
X1500100Y730166D01*
G01X1502408Y729749D02*
X1502658Y729999D01*
X1502950Y730124D01*
X1503283Y730166D01*
X1503700Y730083D01*
X1503992Y729874D01*
X1504075Y729624D01*
X1504033Y729374D01*
X1503867Y729166D01*
X1503033Y728749D01*
X1502658Y728458D01*
X1502408Y728041D01*
X1502325Y727666D01*
X1504075D01*
G01X1481942Y707917D02*
Y710417D01*
X1482983D01*
X1483317Y710292D01*
X1483525Y710125D01*
X1483608Y709792D01*
X1483525Y709459D01*
X1483275Y709250D01*
X1482983Y709125D01*
X1481942D01*
G01X1482983D02*
X1483608Y707917D01*
G01X1484958Y708292D02*
X1485208Y708084D01*
X1485500Y707959D01*
X1485875Y707917D01*
X1486250Y708000D01*
X1486542Y708167D01*
X1486750Y708459D01*
X1486792Y708792D01*
X1486708Y709125D01*
X1486500Y709334D01*
X1486208Y709500D01*
X1485917Y709542D01*
X1485625Y709500D01*
X1485250Y709334D01*
X1485375Y710417D01*
X1486500D01*
G01X1488267Y708209D02*
X1488558Y708000D01*
X1488892Y707917D01*
X1489225Y708000D01*
X1489517Y708250D01*
X1489725Y708625D01*
X1489808Y709000D01*
Y709459D01*
X1489725Y709834D01*
X1489517Y710167D01*
X1489267Y710334D01*
X1488975Y710417D01*
X1488642Y710334D01*
X1488392Y710167D01*
X1488225Y709917D01*
X1488142Y709584D01*
X1488225Y709292D01*
X1488433Y709000D01*
X1488683Y708834D01*
X1488975Y708792D01*
X1489308Y708875D01*
X1489558Y709084D01*
X1489808Y709459D01*
G01X1492575Y707917D02*
Y710417D01*
X1491033Y708625D01*
X1493117D01*
G01X1520893Y779748D02*
Y782248D01*
G01X1522643D02*
Y779748D01*
G01Y780998D02*
X1520893D01*
G01X1523951Y779748D02*
Y782248D01*
X1524785D01*
X1525118Y782123D01*
X1525368Y781956D01*
X1525576Y781706D01*
X1525743Y781415D01*
X1525785Y780998D01*
X1525743Y780581D01*
X1525576Y780290D01*
X1525368Y780040D01*
X1525118Y779873D01*
X1524785Y779748D01*
X1523951D01*
G01X1527051D02*
Y782248D01*
X1527885D01*
X1528218Y782123D01*
X1528468Y781956D01*
X1528676Y781706D01*
X1528843Y781415D01*
X1528885Y780998D01*
X1528843Y780581D01*
X1528676Y780290D01*
X1528468Y780040D01*
X1528218Y779873D01*
X1527885Y779748D01*
X1527051D01*
G01X1530193Y780081D02*
X1530526Y779873D01*
X1530901Y779748D01*
X1531235D01*
X1531568Y779873D01*
X1531818Y780081D01*
X1531943Y780373D01*
X1531860Y780665D01*
X1531651Y780915D01*
X1531276Y781081D01*
X1530776Y781165D01*
X1530485Y781331D01*
X1530360Y781623D01*
X1530443Y781915D01*
X1530651Y782123D01*
X1530943Y782248D01*
X1531235D01*
X1531526Y782165D01*
X1531776Y781956D01*
G01X1533126Y779748D02*
X1534168Y782248D01*
X1535210Y779748D01*
G01X1534835Y780623D02*
X1533501D01*
G01X1536393Y780081D02*
X1536726Y779873D01*
X1537101Y779748D01*
X1537435D01*
X1537768Y779873D01*
X1538018Y780081D01*
X1538143Y780373D01*
X1538060Y780665D01*
X1537851Y780915D01*
X1537476Y781081D01*
X1536976Y781165D01*
X1536685Y781331D01*
X1536560Y781623D01*
X1536643Y781915D01*
X1536851Y782123D01*
X1537143Y782248D01*
X1537435D01*
X1537726Y782165D01*
X1537976Y781956D01*
G01X1539576Y781831D02*
X1539826Y782081D01*
X1540118Y782206D01*
X1540451Y782248D01*
X1540868Y782165D01*
X1541160Y781956D01*
X1541243Y781706D01*
X1541201Y781456D01*
X1541035Y781248D01*
X1540201Y780831D01*
X1539826Y780540D01*
X1539576Y780123D01*
X1539493Y779748D01*
X1541243D01*
G01X1543468Y782248D02*
X1543135Y782165D01*
X1542885Y781956D01*
X1542718Y781706D01*
X1542593Y781373D01*
X1542551Y780998D01*
X1542593Y780623D01*
X1542718Y780290D01*
X1542885Y780040D01*
X1543135Y779831D01*
X1543468Y779748D01*
X1543801Y779831D01*
X1544051Y780040D01*
X1544218Y780290D01*
X1544343Y780623D01*
X1544385Y780998D01*
X1544343Y781373D01*
X1544218Y781706D01*
X1544051Y781956D01*
X1543801Y782165D01*
X1543468Y782248D01*
G01X1482181Y837409D02*
Y839909D01*
X1483765D01*
G01X1483181Y838701D02*
X1482181D01*
G01X1485240Y839909D02*
Y837409D01*
X1486906D01*
G01X1490006D02*
X1488340D01*
Y839909D01*
X1490006D01*
G01X1489340Y838701D02*
X1488340D01*
G01X1491356Y837409D02*
Y839909D01*
X1492190D01*
X1492523Y839784D01*
X1492773Y839617D01*
X1492981Y839367D01*
X1493148Y839076D01*
X1493190Y838659D01*
X1493148Y838242D01*
X1492981Y837951D01*
X1492773Y837701D01*
X1492523Y837534D01*
X1492190Y837409D01*
X1491356D01*
G01X1494665Y837701D02*
X1494956Y837492D01*
X1495290Y837409D01*
X1495623Y837492D01*
X1495915Y837742D01*
X1496123Y838117D01*
X1496206Y838492D01*
Y838951D01*
X1496123Y839326D01*
X1495915Y839659D01*
X1495665Y839826D01*
X1495373Y839909D01*
X1495040Y839826D01*
X1494790Y839659D01*
X1494623Y839409D01*
X1494540Y839076D01*
X1494623Y838784D01*
X1494831Y838492D01*
X1495081Y838326D01*
X1495373Y838284D01*
X1495706Y838367D01*
X1495956Y838576D01*
X1496206Y838951D01*
G01X1484773Y818809D02*
Y830009D01*
X1493573D01*
Y818809D01*
X1484773D01*
G01X1483515Y948902D02*
Y962902D01*
G01X1503594Y947772D02*
X1501094D01*
Y948813D01*
X1501219Y949147D01*
X1501386Y949355D01*
X1501719Y949438D01*
X1502052Y949355D01*
X1502261Y949105D01*
X1502386Y948813D01*
Y947772D01*
G01Y948813D02*
X1503594Y949438D01*
G01X1501511Y950913D02*
X1501261Y951163D01*
X1501136Y951455D01*
X1501094Y951788D01*
X1501177Y952205D01*
X1501386Y952497D01*
X1501636Y952580D01*
X1501886Y952538D01*
X1502094Y952372D01*
X1502511Y951538D01*
X1502802Y951163D01*
X1503219Y950913D01*
X1503594Y950830D01*
Y952580D01*
G01X1503219Y953888D02*
X1503427Y954138D01*
X1503552Y954430D01*
X1503594Y954805D01*
X1503511Y955180D01*
X1503344Y955472D01*
X1503052Y955680D01*
X1502719Y955722D01*
X1502386Y955638D01*
X1502177Y955430D01*
X1502011Y955138D01*
X1501969Y954847D01*
X1502011Y954555D01*
X1502177Y954180D01*
X1501094Y954305D01*
Y955430D01*
G01Y957905D02*
X1501177Y957572D01*
X1501386Y957322D01*
X1501636Y957155D01*
X1501969Y957030D01*
X1502344Y956988D01*
X1502719Y957030D01*
X1503052Y957155D01*
X1503302Y957322D01*
X1503511Y957572D01*
X1503594Y957905D01*
X1503511Y958238D01*
X1503302Y958488D01*
X1503052Y958655D01*
X1502719Y958780D01*
X1502344Y958822D01*
X1501969Y958780D01*
X1501636Y958655D01*
X1501386Y958488D01*
X1501177Y958238D01*
X1501094Y957905D01*
G01X1498594Y947772D02*
X1496094D01*
Y948813D01*
X1496219Y949147D01*
X1496386Y949355D01*
X1496719Y949438D01*
X1497052Y949355D01*
X1497261Y949105D01*
X1497386Y948813D01*
Y947772D01*
G01Y948813D02*
X1498594Y949438D01*
G01X1496511Y950913D02*
X1496261Y951163D01*
X1496136Y951455D01*
X1496094Y951788D01*
X1496177Y952205D01*
X1496386Y952497D01*
X1496636Y952580D01*
X1496886Y952538D01*
X1497094Y952372D01*
X1497511Y951538D01*
X1497802Y951163D01*
X1498219Y950913D01*
X1498594Y950830D01*
Y952580D01*
G01Y955305D02*
X1496094D01*
X1497886Y953763D01*
Y955847D01*
G01X1498594Y957822D02*
X1498052Y957905D01*
X1497594Y958030D01*
X1497177Y958197D01*
X1496719Y958405D01*
X1496094Y958738D01*
Y957072D01*
G01X1513218Y1127004D02*
X1518268D01*
Y1225704D01*
X1542918D01*
Y1041304D01*
X1518268D01*
Y1100004D01*
X1513218D01*
Y1127004D01*
G01X1495470Y1077696D02*
X1495220Y1077821D01*
X1494928Y1077904D01*
X1494595D01*
X1494220Y1077779D01*
X1493928Y1077571D01*
X1493720Y1077321D01*
X1493553Y1076904D01*
X1493511Y1076529D01*
X1493595Y1076154D01*
X1493720Y1075904D01*
X1493970Y1075654D01*
X1494261Y1075487D01*
X1494553Y1075404D01*
X1494845D01*
X1495136Y1075487D01*
X1495386Y1075612D01*
X1495595Y1075779D01*
G01X1497653Y1075404D02*
Y1077904D01*
X1497153Y1077404D01*
G01Y1075404D02*
X1498153D01*
G01X1501253D02*
Y1077904D01*
X1499711Y1076112D01*
X1501795D01*
G01X1502936Y1075904D02*
X1503186Y1075612D01*
X1503520Y1075446D01*
X1503895Y1075404D01*
X1504228Y1075446D01*
X1504561Y1075654D01*
X1504770Y1075904D01*
X1504811Y1076154D01*
X1504728Y1076446D01*
X1504436Y1076654D01*
X1504145Y1076737D01*
X1503770D01*
G01X1504145D02*
X1504395Y1076862D01*
X1504603Y1077071D01*
X1504686Y1077321D01*
X1504603Y1077571D01*
X1504395Y1077779D01*
X1504020Y1077904D01*
X1503645Y1077862D01*
X1503270Y1077696D01*
G01X1495267Y1081792D02*
X1495017Y1081917D01*
X1494725Y1082000D01*
X1494392D01*
X1494017Y1081875D01*
X1493725Y1081667D01*
X1493517Y1081417D01*
X1493350Y1081000D01*
X1493308Y1080625D01*
X1493392Y1080250D01*
X1493517Y1080000D01*
X1493767Y1079750D01*
X1494058Y1079583D01*
X1494350Y1079500D01*
X1494642D01*
X1494933Y1079583D01*
X1495183Y1079708D01*
X1495392Y1079875D01*
G01X1497450Y1079500D02*
Y1082000D01*
X1496950Y1081500D01*
G01Y1079500D02*
X1497950D01*
G01X1501050D02*
Y1082000D01*
X1499508Y1080208D01*
X1501592D01*
G01X1502858Y1081583D02*
X1503108Y1081833D01*
X1503400Y1081958D01*
X1503733Y1082000D01*
X1504150Y1081917D01*
X1504442Y1081708D01*
X1504525Y1081458D01*
X1504483Y1081208D01*
X1504317Y1081000D01*
X1503483Y1080583D01*
X1503108Y1080292D01*
X1502858Y1079875D01*
X1502775Y1079500D01*
X1504525D01*
G01X1476517Y1100000D02*
Y1102500D01*
X1477558D01*
X1477892Y1102375D01*
X1478100Y1102208D01*
X1478183Y1101875D01*
X1478100Y1101542D01*
X1477850Y1101333D01*
X1477558Y1101208D01*
X1476517D01*
G01X1477558D02*
X1478183Y1100000D01*
G01X1479533Y1100500D02*
X1479783Y1100208D01*
X1480117Y1100042D01*
X1480492Y1100000D01*
X1480825Y1100042D01*
X1481158Y1100250D01*
X1481367Y1100500D01*
X1481408Y1100750D01*
X1481325Y1101042D01*
X1481033Y1101250D01*
X1480742Y1101333D01*
X1480367D01*
G01X1480742D02*
X1480992Y1101458D01*
X1481200Y1101667D01*
X1481283Y1101917D01*
X1481200Y1102167D01*
X1480992Y1102375D01*
X1480617Y1102500D01*
X1480242Y1102458D01*
X1479867Y1102292D01*
G01X1483550Y1102500D02*
X1483217Y1102417D01*
X1482967Y1102208D01*
X1482800Y1101958D01*
X1482675Y1101625D01*
X1482633Y1101250D01*
X1482675Y1100875D01*
X1482800Y1100542D01*
X1482967Y1100292D01*
X1483217Y1100083D01*
X1483550Y1100000D01*
X1483883Y1100083D01*
X1484133Y1100292D01*
X1484300Y1100542D01*
X1484425Y1100875D01*
X1484467Y1101250D01*
X1484425Y1101625D01*
X1484300Y1101958D01*
X1484133Y1102208D01*
X1483883Y1102417D01*
X1483550Y1102500D01*
G01X1486567Y1100000D02*
X1486650Y1100542D01*
X1486775Y1101000D01*
X1486942Y1101417D01*
X1487150Y1101875D01*
X1487483Y1102500D01*
X1485817D01*
G01X1488017Y1112000D02*
Y1114500D01*
X1489058D01*
X1489392Y1114375D01*
X1489600Y1114208D01*
X1489683Y1113875D01*
X1489600Y1113542D01*
X1489350Y1113333D01*
X1489058Y1113208D01*
X1488017D01*
G01X1489058D02*
X1489683Y1112000D01*
G01X1491033Y1112375D02*
X1491283Y1112167D01*
X1491575Y1112042D01*
X1491950Y1112000D01*
X1492325Y1112083D01*
X1492617Y1112250D01*
X1492825Y1112542D01*
X1492867Y1112875D01*
X1492783Y1113208D01*
X1492575Y1113417D01*
X1492283Y1113583D01*
X1491992Y1113625D01*
X1491700Y1113583D01*
X1491325Y1113417D01*
X1491450Y1114500D01*
X1492575D01*
G01X1495050Y1112000D02*
X1495342Y1112042D01*
X1495675Y1112167D01*
X1495883Y1112375D01*
X1495967Y1112667D01*
X1495883Y1112958D01*
X1495633Y1113208D01*
X1495258Y1113333D01*
X1494842D01*
X1494592Y1113417D01*
X1494383Y1113625D01*
X1494300Y1113917D01*
X1494425Y1114208D01*
X1494717Y1114417D01*
X1495050Y1114500D01*
X1495383Y1114417D01*
X1495675Y1114208D01*
X1495800Y1113917D01*
X1495717Y1113625D01*
X1495508Y1113417D01*
X1495258Y1113333D01*
X1494842D01*
X1494467Y1113208D01*
X1494217Y1112958D01*
X1494133Y1112667D01*
X1494217Y1112375D01*
X1494425Y1112167D01*
X1494758Y1112042D01*
X1495050Y1112000D01*
G01X1498150Y1114500D02*
X1497817Y1114417D01*
X1497567Y1114208D01*
X1497400Y1113958D01*
X1497275Y1113625D01*
X1497233Y1113250D01*
X1497275Y1112875D01*
X1497400Y1112542D01*
X1497567Y1112292D01*
X1497817Y1112083D01*
X1498150Y1112000D01*
X1498483Y1112083D01*
X1498733Y1112292D01*
X1498900Y1112542D01*
X1499025Y1112875D01*
X1499067Y1113250D01*
X1499025Y1113625D01*
X1498900Y1113958D01*
X1498733Y1114208D01*
X1498483Y1114417D01*
X1498150Y1114500D01*
G01X1483658Y1119943D02*
Y1115943D01*
X1491058D01*
G01X1496000Y1126350D02*
X1495958Y1126017D01*
X1495792Y1125725D01*
X1495542Y1125475D01*
X1495250Y1125308D01*
X1494917Y1125225D01*
X1494583D01*
X1494250Y1125308D01*
X1493958Y1125475D01*
X1493708Y1125725D01*
X1493542Y1126017D01*
X1493500Y1126350D01*
X1493542Y1126683D01*
X1493708Y1126975D01*
X1493958Y1127225D01*
X1494250Y1127392D01*
X1494583Y1127475D01*
X1494917D01*
X1495250Y1127392D01*
X1495542Y1127225D01*
X1495792Y1126975D01*
X1495958Y1126683D01*
X1496000Y1126350D01*
G01X1495333Y1126683D02*
X1496000Y1127183D01*
G01X1493917Y1128658D02*
X1493667Y1128908D01*
X1493542Y1129200D01*
X1493500Y1129533D01*
X1493583Y1129950D01*
X1493792Y1130242D01*
X1494042Y1130325D01*
X1494292Y1130283D01*
X1494500Y1130117D01*
X1494917Y1129283D01*
X1495208Y1128908D01*
X1495625Y1128658D01*
X1496000Y1128575D01*
Y1130325D01*
G01X1495708Y1131842D02*
X1495917Y1132133D01*
X1496000Y1132467D01*
X1495917Y1132800D01*
X1495667Y1133092D01*
X1495292Y1133300D01*
X1494917Y1133383D01*
X1494458D01*
X1494083Y1133300D01*
X1493750Y1133092D01*
X1493583Y1132842D01*
X1493500Y1132550D01*
X1493583Y1132217D01*
X1493750Y1131967D01*
X1494000Y1131800D01*
X1494333Y1131717D01*
X1494625Y1131800D01*
X1494917Y1132008D01*
X1495083Y1132258D01*
X1495125Y1132550D01*
X1495042Y1132883D01*
X1494833Y1133133D01*
X1494458Y1133383D01*
G01X1495625Y1134733D02*
X1495833Y1134983D01*
X1495958Y1135275D01*
X1496000Y1135650D01*
X1495917Y1136025D01*
X1495750Y1136317D01*
X1495458Y1136525D01*
X1495125Y1136567D01*
X1494792Y1136483D01*
X1494583Y1136275D01*
X1494417Y1135983D01*
X1494375Y1135692D01*
X1494417Y1135400D01*
X1494583Y1135025D01*
X1493500Y1135150D01*
Y1136275D01*
G01X1478721Y1137591D02*
Y1123591D01*
G01X1491721D02*
Y1137591D01*
G01X1478721Y1123591D02*
X1491721D01*
G01X1476533Y1096000D02*
Y1098500D01*
X1477367D01*
X1477700Y1098375D01*
X1477950Y1098208D01*
X1478158Y1097958D01*
X1478325Y1097667D01*
X1478367Y1097250D01*
X1478325Y1096833D01*
X1478158Y1096542D01*
X1477950Y1096292D01*
X1477700Y1096125D01*
X1477367Y1096000D01*
X1476533D01*
G01X1480467D02*
X1480550Y1096542D01*
X1480675Y1097000D01*
X1480842Y1097417D01*
X1481050Y1097875D01*
X1481383Y1098500D01*
X1479717D01*
G01X1501942Y1141373D02*
Y1143873D01*
X1502983D01*
X1503317Y1143748D01*
X1503525Y1143581D01*
X1503608Y1143248D01*
X1503525Y1142915D01*
X1503275Y1142706D01*
X1502983Y1142581D01*
X1501942D01*
G01X1502983D02*
X1503608Y1141373D01*
G01X1504958Y1141873D02*
X1505208Y1141581D01*
X1505542Y1141415D01*
X1505917Y1141373D01*
X1506250Y1141415D01*
X1506583Y1141623D01*
X1506792Y1141873D01*
X1506833Y1142123D01*
X1506750Y1142415D01*
X1506458Y1142623D01*
X1506167Y1142706D01*
X1505792D01*
G01X1506167D02*
X1506417Y1142831D01*
X1506625Y1143040D01*
X1506708Y1143290D01*
X1506625Y1143540D01*
X1506417Y1143748D01*
X1506042Y1143873D01*
X1505667Y1143831D01*
X1505292Y1143665D01*
G01X1508975Y1141373D02*
Y1143873D01*
X1508475Y1143373D01*
G01Y1141373D02*
X1509475D01*
G01X1512575D02*
Y1143873D01*
X1511033Y1142081D01*
X1513117D01*
G01X1497725Y1152373D02*
Y1148373D01*
X1505125D01*
G01X1483883Y1146062D02*
Y1142062D01*
X1491283D01*
G01X1491721Y1137591D02*
X1478721D01*
G01X1481350Y1165500D02*
X1481017Y1165542D01*
X1480725Y1165708D01*
X1480475Y1165958D01*
X1480308Y1166250D01*
X1480225Y1166583D01*
Y1166917D01*
X1480308Y1167250D01*
X1480475Y1167542D01*
X1480725Y1167792D01*
X1481017Y1167958D01*
X1481350Y1168000D01*
X1481683Y1167958D01*
X1481975Y1167792D01*
X1482225Y1167542D01*
X1482392Y1167250D01*
X1482475Y1166917D01*
Y1166583D01*
X1482392Y1166250D01*
X1482225Y1165958D01*
X1481975Y1165708D01*
X1481683Y1165542D01*
X1481350Y1165500D01*
G01X1481683Y1166167D02*
X1482183Y1165500D01*
G01X1483658Y1167583D02*
X1483908Y1167833D01*
X1484200Y1167958D01*
X1484533Y1168000D01*
X1484950Y1167917D01*
X1485242Y1167708D01*
X1485325Y1167458D01*
X1485283Y1167208D01*
X1485117Y1167000D01*
X1484283Y1166583D01*
X1483908Y1166292D01*
X1483658Y1165875D01*
X1483575Y1165500D01*
X1485325D01*
G01X1486633Y1165875D02*
X1486883Y1165667D01*
X1487175Y1165542D01*
X1487550Y1165500D01*
X1487925Y1165583D01*
X1488217Y1165750D01*
X1488425Y1166042D01*
X1488467Y1166375D01*
X1488383Y1166708D01*
X1488175Y1166917D01*
X1487883Y1167083D01*
X1487592Y1167125D01*
X1487300Y1167083D01*
X1486925Y1166917D01*
X1487050Y1168000D01*
X1488175D01*
G01X1489942Y1165792D02*
X1490233Y1165583D01*
X1490567Y1165500D01*
X1490900Y1165583D01*
X1491192Y1165833D01*
X1491400Y1166208D01*
X1491483Y1166583D01*
Y1167042D01*
X1491400Y1167417D01*
X1491192Y1167750D01*
X1490942Y1167917D01*
X1490650Y1168000D01*
X1490317Y1167917D01*
X1490067Y1167750D01*
X1489900Y1167500D01*
X1489817Y1167167D01*
X1489900Y1166875D01*
X1490108Y1166583D01*
X1490358Y1166417D01*
X1490650Y1166375D01*
X1490983Y1166458D01*
X1491233Y1166667D01*
X1491483Y1167042D01*
G01X1478968Y1164058D02*
Y1150058D01*
G01X1491968Y1164058D02*
X1478968D01*
G01X1491968Y1150058D02*
Y1164058D01*
G01X1478968Y1150058D02*
X1491968D01*
G01X1496000Y1171850D02*
X1498500D01*
G01X1496000Y1170892D02*
Y1172808D01*
G01X1498500Y1174117D02*
X1496000D01*
Y1175117D01*
X1496125Y1175450D01*
X1496417Y1175700D01*
X1496750Y1175783D01*
X1497083Y1175700D01*
X1497333Y1175492D01*
X1497458Y1175117D01*
Y1174117D01*
G01X1498500Y1178550D02*
X1496000D01*
X1497792Y1177008D01*
Y1179092D01*
G01X1496417Y1180358D02*
X1496167Y1180608D01*
X1496042Y1180900D01*
X1496000Y1181233D01*
X1496083Y1181650D01*
X1496292Y1181942D01*
X1496542Y1182025D01*
X1496792Y1181983D01*
X1497000Y1181817D01*
X1497417Y1180983D01*
X1497708Y1180608D01*
X1498125Y1180358D01*
X1498500Y1180275D01*
Y1182025D01*
G01X1477453Y1165544D02*
X1474953D01*
Y1166585D01*
X1475078Y1166919D01*
X1475245Y1167127D01*
X1475578Y1167210D01*
X1475911Y1167127D01*
X1476120Y1166877D01*
X1476245Y1166585D01*
Y1165544D01*
G01Y1166585D02*
X1477453Y1167210D01*
G01X1475370Y1168685D02*
X1475120Y1168935D01*
X1474995Y1169227D01*
X1474953Y1169560D01*
X1475036Y1169977D01*
X1475245Y1170269D01*
X1475495Y1170352D01*
X1475745Y1170310D01*
X1475953Y1170144D01*
X1476370Y1169310D01*
X1476661Y1168935D01*
X1477078Y1168685D01*
X1477453Y1168602D01*
Y1170352D01*
G01X1477161Y1171869D02*
X1477370Y1172160D01*
X1477453Y1172494D01*
X1477370Y1172827D01*
X1477120Y1173119D01*
X1476745Y1173327D01*
X1476370Y1173410D01*
X1475911D01*
X1475536Y1173327D01*
X1475203Y1173119D01*
X1475036Y1172869D01*
X1474953Y1172577D01*
X1475036Y1172244D01*
X1475203Y1171994D01*
X1475453Y1171827D01*
X1475786Y1171744D01*
X1476078Y1171827D01*
X1476370Y1172035D01*
X1476536Y1172285D01*
X1476578Y1172577D01*
X1476495Y1172910D01*
X1476286Y1173160D01*
X1475911Y1173410D01*
G01X1477453Y1175594D02*
X1476911Y1175677D01*
X1476453Y1175802D01*
X1476036Y1175969D01*
X1475578Y1176177D01*
X1474953Y1176510D01*
Y1174844D01*
G01X1504017Y1165000D02*
Y1167500D01*
X1505058D01*
X1505392Y1167375D01*
X1505600Y1167208D01*
X1505683Y1166875D01*
X1505600Y1166542D01*
X1505350Y1166333D01*
X1505058Y1166208D01*
X1504017D01*
G01X1505058D02*
X1505683Y1165000D01*
G01X1507033Y1165500D02*
X1507283Y1165208D01*
X1507617Y1165042D01*
X1507992Y1165000D01*
X1508325Y1165042D01*
X1508658Y1165250D01*
X1508867Y1165500D01*
X1508908Y1165750D01*
X1508825Y1166042D01*
X1508533Y1166250D01*
X1508242Y1166333D01*
X1507867D01*
G01X1508242D02*
X1508492Y1166458D01*
X1508700Y1166667D01*
X1508783Y1166917D01*
X1508700Y1167167D01*
X1508492Y1167375D01*
X1508117Y1167500D01*
X1507742Y1167458D01*
X1507367Y1167292D01*
G01X1511050Y1165000D02*
Y1167500D01*
X1510550Y1167000D01*
G01Y1165000D02*
X1511550D01*
G01X1514150D02*
X1514442Y1165042D01*
X1514775Y1165167D01*
X1514983Y1165375D01*
X1515067Y1165667D01*
X1514983Y1165958D01*
X1514733Y1166208D01*
X1514358Y1166333D01*
X1513942D01*
X1513692Y1166417D01*
X1513483Y1166625D01*
X1513400Y1166917D01*
X1513525Y1167208D01*
X1513817Y1167417D01*
X1514150Y1167500D01*
X1514483Y1167417D01*
X1514775Y1167208D01*
X1514900Y1166917D01*
X1514817Y1166625D01*
X1514608Y1166417D01*
X1514358Y1166333D01*
X1513942D01*
X1513567Y1166208D01*
X1513317Y1165958D01*
X1513233Y1165667D01*
X1513317Y1165375D01*
X1513525Y1165167D01*
X1513858Y1165042D01*
X1514150Y1165000D01*
G01X1503692Y1139465D02*
X1503442Y1139590D01*
X1503150Y1139673D01*
X1502817D01*
X1502442Y1139548D01*
X1502150Y1139340D01*
X1501942Y1139090D01*
X1501775Y1138673D01*
X1501733Y1138298D01*
X1501817Y1137923D01*
X1501942Y1137673D01*
X1502192Y1137423D01*
X1502483Y1137256D01*
X1502775Y1137173D01*
X1503067D01*
X1503358Y1137256D01*
X1503608Y1137381D01*
X1503817Y1137548D01*
G01X1505875Y1137173D02*
Y1139673D01*
X1505375Y1139173D01*
G01Y1137173D02*
X1506375D01*
G01X1509475D02*
Y1139673D01*
X1507933Y1137881D01*
X1510017D01*
G01X1511367Y1137465D02*
X1511658Y1137256D01*
X1511992Y1137173D01*
X1512325Y1137256D01*
X1512617Y1137506D01*
X1512825Y1137881D01*
X1512908Y1138256D01*
Y1138715D01*
X1512825Y1139090D01*
X1512617Y1139423D01*
X1512367Y1139590D01*
X1512075Y1139673D01*
X1511742Y1139590D01*
X1511492Y1139423D01*
X1511325Y1139173D01*
X1511242Y1138840D01*
X1511325Y1138548D01*
X1511533Y1138256D01*
X1511783Y1138090D01*
X1512075Y1138048D01*
X1512408Y1138131D01*
X1512658Y1138340D01*
X1512908Y1138715D01*
G01X1519325Y1233500D02*
Y1236000D01*
G01X1521075D02*
Y1233500D01*
G01Y1234750D02*
X1519325D01*
G01X1522383Y1233500D02*
Y1236000D01*
X1523217D01*
X1523550Y1235875D01*
X1523800Y1235708D01*
X1524008Y1235458D01*
X1524175Y1235167D01*
X1524217Y1234750D01*
X1524175Y1234333D01*
X1524008Y1234042D01*
X1523800Y1233792D01*
X1523550Y1233625D01*
X1523217Y1233500D01*
X1522383D01*
G01X1525483D02*
Y1236000D01*
X1526317D01*
X1526650Y1235875D01*
X1526900Y1235708D01*
X1527108Y1235458D01*
X1527275Y1235167D01*
X1527317Y1234750D01*
X1527275Y1234333D01*
X1527108Y1234042D01*
X1526900Y1233792D01*
X1526650Y1233625D01*
X1526317Y1233500D01*
X1525483D01*
G01X1528625Y1233833D02*
X1528958Y1233625D01*
X1529333Y1233500D01*
X1529667D01*
X1530000Y1233625D01*
X1530250Y1233833D01*
X1530375Y1234125D01*
X1530292Y1234417D01*
X1530083Y1234667D01*
X1529708Y1234833D01*
X1529208Y1234917D01*
X1528917Y1235083D01*
X1528792Y1235375D01*
X1528875Y1235667D01*
X1529083Y1235875D01*
X1529375Y1236000D01*
X1529667D01*
X1529958Y1235917D01*
X1530208Y1235708D01*
G01X1531558Y1233500D02*
X1532600Y1236000D01*
X1533642Y1233500D01*
G01X1533267Y1234375D02*
X1531933D01*
G01X1534825Y1233833D02*
X1535158Y1233625D01*
X1535533Y1233500D01*
X1535867D01*
X1536200Y1233625D01*
X1536450Y1233833D01*
X1536575Y1234125D01*
X1536492Y1234417D01*
X1536283Y1234667D01*
X1535908Y1234833D01*
X1535408Y1234917D01*
X1535117Y1235083D01*
X1534992Y1235375D01*
X1535075Y1235667D01*
X1535283Y1235875D01*
X1535575Y1236000D01*
X1535867D01*
X1536158Y1235917D01*
X1536408Y1235708D01*
G01X1538800Y1233500D02*
X1539092Y1233542D01*
X1539425Y1233667D01*
X1539633Y1233875D01*
X1539717Y1234167D01*
X1539633Y1234458D01*
X1539383Y1234708D01*
X1539008Y1234833D01*
X1538592D01*
X1538342Y1234917D01*
X1538133Y1235125D01*
X1538050Y1235417D01*
X1538175Y1235708D01*
X1538467Y1235917D01*
X1538800Y1236000D01*
X1539133Y1235917D01*
X1539425Y1235708D01*
X1539550Y1235417D01*
X1539467Y1235125D01*
X1539258Y1234917D01*
X1539008Y1234833D01*
X1538592D01*
X1538217Y1234708D01*
X1537967Y1234458D01*
X1537883Y1234167D01*
X1537967Y1233875D01*
X1538175Y1233667D01*
X1538508Y1233542D01*
X1538800Y1233500D01*
G01X1484773Y1271565D02*
Y1282765D01*
X1493573D01*
Y1271565D01*
X1484773D01*
G01X1480090Y1285665D02*
Y1288165D01*
X1481131D01*
X1481465Y1288040D01*
X1481673Y1287873D01*
X1481756Y1287540D01*
X1481673Y1287207D01*
X1481423Y1286998D01*
X1481131Y1286873D01*
X1480090D01*
G01X1481131D02*
X1481756Y1285665D01*
G01X1483190Y1288165D02*
Y1285665D01*
X1484856D01*
G01X1487956D02*
X1486290D01*
Y1288165D01*
X1487956D01*
G01X1487290Y1286957D02*
X1486290D01*
G01X1489306Y1285665D02*
Y1288165D01*
X1490140D01*
X1490473Y1288040D01*
X1490723Y1287873D01*
X1490931Y1287623D01*
X1491098Y1287332D01*
X1491140Y1286915D01*
X1491098Y1286498D01*
X1490931Y1286207D01*
X1490723Y1285957D01*
X1490473Y1285790D01*
X1490140Y1285665D01*
X1489306D01*
G01X1492406Y1286165D02*
X1492656Y1285873D01*
X1492990Y1285707D01*
X1493365Y1285665D01*
X1493698Y1285707D01*
X1494031Y1285915D01*
X1494240Y1286165D01*
X1494281Y1286415D01*
X1494198Y1286707D01*
X1493906Y1286915D01*
X1493615Y1286998D01*
X1493240D01*
G01X1493615D02*
X1493865Y1287123D01*
X1494073Y1287332D01*
X1494156Y1287582D01*
X1494073Y1287832D01*
X1493865Y1288040D01*
X1493490Y1288165D01*
X1493115Y1288123D01*
X1492740Y1287957D01*
G01X1495506Y1286165D02*
X1495756Y1285873D01*
X1496090Y1285707D01*
X1496465Y1285665D01*
X1496798Y1285707D01*
X1497131Y1285915D01*
X1497340Y1286165D01*
X1497381Y1286415D01*
X1497298Y1286707D01*
X1497006Y1286915D01*
X1496715Y1286998D01*
X1496340D01*
G01X1496715D02*
X1496965Y1287123D01*
X1497173Y1287332D01*
X1497256Y1287582D01*
X1497173Y1287832D01*
X1496965Y1288040D01*
X1496590Y1288165D01*
X1496215Y1288123D01*
X1495840Y1287957D01*
G01X1500060Y1656361D02*
X1500460Y1656761D01*
X1500927Y1656961D01*
X1501460Y1657028D01*
X1502127Y1656895D01*
X1502594Y1656561D01*
X1502727Y1656161D01*
X1502660Y1655761D01*
X1502394Y1655428D01*
X1501060Y1654761D01*
X1500460Y1654295D01*
X1500060Y1653628D01*
X1499927Y1653028D01*
X1502727D01*
G01X1562425Y148178D02*
X1559925D01*
Y149219D01*
X1560050Y149553D01*
X1560217Y149761D01*
X1560550Y149844D01*
X1560883Y149761D01*
X1561092Y149511D01*
X1561217Y149219D01*
Y148178D01*
G01Y149219D02*
X1562425Y149844D01*
G01Y152111D02*
X1562383Y152403D01*
X1562258Y152736D01*
X1562050Y152944D01*
X1561758Y153028D01*
X1561467Y152944D01*
X1561217Y152694D01*
X1561092Y152319D01*
Y151903D01*
X1561008Y151653D01*
X1560800Y151444D01*
X1560508Y151361D01*
X1560217Y151486D01*
X1560008Y151778D01*
X1559925Y152111D01*
X1560008Y152444D01*
X1560217Y152736D01*
X1560508Y152861D01*
X1560800Y152778D01*
X1561008Y152569D01*
X1561092Y152319D01*
Y151903D01*
X1561217Y151528D01*
X1561467Y151278D01*
X1561758Y151194D01*
X1562050Y151278D01*
X1562258Y151486D01*
X1562383Y151819D01*
X1562425Y152111D01*
G01Y155128D02*
X1561883Y155211D01*
X1561425Y155336D01*
X1561008Y155503D01*
X1560550Y155711D01*
X1559925Y156044D01*
Y154378D01*
G01X1562425Y158811D02*
X1559925D01*
X1561717Y157269D01*
Y159353D01*
G01X1558425Y163961D02*
X1562425D01*
Y171361D01*
G01X1571000Y149017D02*
X1568500D01*
Y150058D01*
X1568625Y150392D01*
X1568792Y150600D01*
X1569125Y150683D01*
X1569458Y150600D01*
X1569667Y150350D01*
X1569792Y150058D01*
Y149017D01*
G01Y150058D02*
X1571000Y150683D01*
G01Y152950D02*
X1570958Y153242D01*
X1570833Y153575D01*
X1570625Y153783D01*
X1570333Y153867D01*
X1570042Y153783D01*
X1569792Y153533D01*
X1569667Y153158D01*
Y152742D01*
X1569583Y152492D01*
X1569375Y152283D01*
X1569083Y152200D01*
X1568792Y152325D01*
X1568583Y152617D01*
X1568500Y152950D01*
X1568583Y153283D01*
X1568792Y153575D01*
X1569083Y153700D01*
X1569375Y153617D01*
X1569583Y153408D01*
X1569667Y153158D01*
Y152742D01*
X1569792Y152367D01*
X1570042Y152117D01*
X1570333Y152033D01*
X1570625Y152117D01*
X1570833Y152325D01*
X1570958Y152658D01*
X1571000Y152950D01*
G01Y155967D02*
X1570458Y156050D01*
X1570000Y156175D01*
X1569583Y156342D01*
X1569125Y156550D01*
X1568500Y156883D01*
Y155217D01*
G01X1569958Y158358D02*
X1569667Y158650D01*
X1569500Y158900D01*
X1569417Y159233D01*
X1569500Y159525D01*
X1569667Y159733D01*
X1569917Y159900D01*
X1570208Y159942D01*
X1570458Y159900D01*
X1570708Y159733D01*
X1570917Y159483D01*
X1571000Y159192D01*
X1570917Y158858D01*
X1570667Y158567D01*
X1570292Y158400D01*
X1569875Y158358D01*
X1569333Y158442D01*
X1569042Y158567D01*
X1568750Y158775D01*
X1568542Y159067D01*
X1568500Y159358D01*
X1568583Y159650D01*
X1568792Y159858D01*
G01X1568425Y163961D02*
X1572425D01*
Y171361D01*
G01X1557425Y148178D02*
X1554925D01*
Y149219D01*
X1555050Y149553D01*
X1555217Y149761D01*
X1555550Y149844D01*
X1555883Y149761D01*
X1556092Y149511D01*
X1556217Y149219D01*
Y148178D01*
G01Y149219D02*
X1557425Y149844D01*
G01Y152111D02*
X1557383Y152403D01*
X1557258Y152736D01*
X1557050Y152944D01*
X1556758Y153028D01*
X1556467Y152944D01*
X1556217Y152694D01*
X1556092Y152319D01*
Y151903D01*
X1556008Y151653D01*
X1555800Y151444D01*
X1555508Y151361D01*
X1555217Y151486D01*
X1555008Y151778D01*
X1554925Y152111D01*
X1555008Y152444D01*
X1555217Y152736D01*
X1555508Y152861D01*
X1555800Y152778D01*
X1556008Y152569D01*
X1556092Y152319D01*
Y151903D01*
X1556217Y151528D01*
X1556467Y151278D01*
X1556758Y151194D01*
X1557050Y151278D01*
X1557258Y151486D01*
X1557383Y151819D01*
X1557425Y152111D01*
G01Y155128D02*
X1556883Y155211D01*
X1556425Y155336D01*
X1556008Y155503D01*
X1555550Y155711D01*
X1554925Y156044D01*
Y154378D01*
G01X1557425Y158311D02*
X1557383Y158603D01*
X1557258Y158936D01*
X1557050Y159144D01*
X1556758Y159228D01*
X1556467Y159144D01*
X1556217Y158894D01*
X1556092Y158519D01*
Y158103D01*
X1556008Y157853D01*
X1555800Y157644D01*
X1555508Y157561D01*
X1555217Y157686D01*
X1555008Y157978D01*
X1554925Y158311D01*
X1555008Y158644D01*
X1555217Y158936D01*
X1555508Y159061D01*
X1555800Y158978D01*
X1556008Y158769D01*
X1556092Y158519D01*
Y158103D01*
X1556217Y157728D01*
X1556467Y157478D01*
X1556758Y157394D01*
X1557050Y157478D01*
X1557258Y157686D01*
X1557383Y158019D01*
X1557425Y158311D01*
G01X1557925Y171361D02*
X1553925D01*
Y163961D01*
G01X1562125Y189161D02*
Y193161D01*
X1554725D01*
G01X1568125Y176361D02*
X1572125D01*
Y183761D01*
G01X1547500Y173850D02*
X1547458Y173517D01*
X1547292Y173225D01*
X1547042Y172975D01*
X1546750Y172808D01*
X1546417Y172725D01*
X1546083D01*
X1545750Y172808D01*
X1545458Y172975D01*
X1545208Y173225D01*
X1545042Y173517D01*
X1545000Y173850D01*
X1545042Y174183D01*
X1545208Y174475D01*
X1545458Y174725D01*
X1545750Y174892D01*
X1546083Y174975D01*
X1546417D01*
X1546750Y174892D01*
X1547042Y174725D01*
X1547292Y174475D01*
X1547458Y174183D01*
X1547500Y173850D01*
G01X1546833Y174183D02*
X1547500Y174683D01*
G01Y176950D02*
X1545000D01*
X1545500Y176450D01*
G01X1547500D02*
Y177450D01*
G01X1547208Y179342D02*
X1547417Y179633D01*
X1547500Y179967D01*
X1547417Y180300D01*
X1547167Y180592D01*
X1546792Y180800D01*
X1546417Y180883D01*
X1545958D01*
X1545583Y180800D01*
X1545250Y180592D01*
X1545083Y180342D01*
X1545000Y180050D01*
X1545083Y179717D01*
X1545250Y179467D01*
X1545500Y179300D01*
X1545833Y179217D01*
X1546125Y179300D01*
X1546417Y179508D01*
X1546583Y179758D01*
X1546625Y180050D01*
X1546542Y180383D01*
X1546333Y180633D01*
X1545958Y180883D01*
G01X1547000Y182233D02*
X1547292Y182483D01*
X1547458Y182817D01*
X1547500Y183192D01*
X1547458Y183525D01*
X1547250Y183858D01*
X1547000Y184067D01*
X1546750Y184108D01*
X1546458Y184025D01*
X1546250Y183733D01*
X1546167Y183442D01*
Y183067D01*
G01Y183442D02*
X1546042Y183692D01*
X1545833Y183900D01*
X1545583Y183983D01*
X1545333Y183900D01*
X1545125Y183692D01*
X1545000Y183317D01*
X1545042Y182942D01*
X1545208Y182567D01*
G01X1549225Y183861D02*
Y172461D01*
G01X1562625Y183861D02*
X1549225D01*
G01X1562625Y172461D02*
Y183861D01*
G01X1549225Y172461D02*
X1562625D01*
G01X1584925Y184661D02*
X1568825D01*
G01Y191661D02*
X1584925D01*
G01X1568825Y184661D02*
Y191661D01*
G01X1561325Y218961D02*
Y199761D01*
X1572525D01*
Y218961D01*
X1561325D01*
Y218561D01*
G01X1548017Y232500D02*
Y235000D01*
X1549058D01*
X1549392Y234875D01*
X1549600Y234708D01*
X1549683Y234375D01*
X1549600Y234042D01*
X1549350Y233833D01*
X1549058Y233708D01*
X1548017D01*
G01X1549058D02*
X1549683Y232500D01*
G01X1551950D02*
X1552242Y232542D01*
X1552575Y232667D01*
X1552783Y232875D01*
X1552867Y233167D01*
X1552783Y233458D01*
X1552533Y233708D01*
X1552158Y233833D01*
X1551742D01*
X1551492Y233917D01*
X1551283Y234125D01*
X1551200Y234417D01*
X1551325Y234708D01*
X1551617Y234917D01*
X1551950Y235000D01*
X1552283Y234917D01*
X1552575Y234708D01*
X1552700Y234417D01*
X1552617Y234125D01*
X1552408Y233917D01*
X1552158Y233833D01*
X1551742D01*
X1551367Y233708D01*
X1551117Y233458D01*
X1551033Y233167D01*
X1551117Y232875D01*
X1551325Y232667D01*
X1551658Y232542D01*
X1551950Y232500D01*
G01X1554258Y233542D02*
X1554550Y233833D01*
X1554800Y234000D01*
X1555133Y234083D01*
X1555425Y234000D01*
X1555633Y233833D01*
X1555800Y233583D01*
X1555842Y233292D01*
X1555800Y233042D01*
X1555633Y232792D01*
X1555383Y232583D01*
X1555092Y232500D01*
X1554758Y232583D01*
X1554467Y232833D01*
X1554300Y233208D01*
X1554258Y233625D01*
X1554342Y234167D01*
X1554467Y234458D01*
X1554675Y234750D01*
X1554967Y234958D01*
X1555258Y235000D01*
X1555550Y234917D01*
X1555758Y234708D01*
G01X1557233Y232875D02*
X1557483Y232667D01*
X1557775Y232542D01*
X1558150Y232500D01*
X1558525Y232583D01*
X1558817Y232750D01*
X1559025Y233042D01*
X1559067Y233375D01*
X1558983Y233708D01*
X1558775Y233917D01*
X1558483Y234083D01*
X1558192Y234125D01*
X1557900Y234083D01*
X1557525Y233917D01*
X1557650Y235000D01*
X1558775D01*
G01X1562225Y244661D02*
Y236661D01*
X1544625D01*
Y244661D01*
X1562225D01*
G01X1549208Y247767D02*
X1549083Y247517D01*
X1549000Y247225D01*
Y246892D01*
X1549125Y246517D01*
X1549333Y246225D01*
X1549583Y246017D01*
X1550000Y245850D01*
X1550375Y245808D01*
X1550750Y245892D01*
X1551000Y246017D01*
X1551250Y246267D01*
X1551417Y246558D01*
X1551500Y246850D01*
Y247142D01*
X1551417Y247433D01*
X1551292Y247683D01*
X1551125Y247892D01*
G01X1551500Y250450D02*
X1549000D01*
X1550792Y248908D01*
Y250992D01*
G01X1551125Y252133D02*
X1551333Y252383D01*
X1551458Y252675D01*
X1551500Y253050D01*
X1551417Y253425D01*
X1551250Y253717D01*
X1550958Y253925D01*
X1550625Y253967D01*
X1550292Y253883D01*
X1550083Y253675D01*
X1549917Y253383D01*
X1549875Y253092D01*
X1549917Y252800D01*
X1550083Y252425D01*
X1549000Y252550D01*
Y253675D01*
G01X1551500Y256067D02*
X1550958Y256150D01*
X1550500Y256275D01*
X1550083Y256442D01*
X1549625Y256650D01*
X1549000Y256983D01*
Y255317D01*
G01X1552925Y250361D02*
Y255861D01*
G01X1560925Y250361D02*
X1552925D01*
G01X1560925Y255861D02*
Y250361D01*
G01X1563725Y246161D02*
X1565825Y244361D01*
X1563725Y242161D01*
G01X1563625Y238561D02*
X1582825D01*
Y249761D01*
X1563625D01*
Y238561D01*
X1564025D01*
G01X1553350Y221000D02*
X1553017Y221042D01*
X1552725Y221208D01*
X1552475Y221458D01*
X1552308Y221750D01*
X1552225Y222083D01*
Y222417D01*
X1552308Y222750D01*
X1552475Y223042D01*
X1552725Y223292D01*
X1553017Y223458D01*
X1553350Y223500D01*
X1553683Y223458D01*
X1553975Y223292D01*
X1554225Y223042D01*
X1554392Y222750D01*
X1554475Y222417D01*
Y222083D01*
X1554392Y221750D01*
X1554225Y221458D01*
X1553975Y221208D01*
X1553683Y221042D01*
X1553350Y221000D01*
G01X1553683Y221667D02*
X1554183Y221000D01*
G01X1556450D02*
Y223500D01*
X1555950Y223000D01*
G01Y221000D02*
X1556950D01*
G01X1558842Y221292D02*
X1559133Y221083D01*
X1559467Y221000D01*
X1559800Y221083D01*
X1560092Y221333D01*
X1560300Y221708D01*
X1560383Y222083D01*
Y222542D01*
X1560300Y222917D01*
X1560092Y223250D01*
X1559842Y223417D01*
X1559550Y223500D01*
X1559217Y223417D01*
X1558967Y223250D01*
X1558800Y223000D01*
X1558717Y222667D01*
X1558800Y222375D01*
X1559008Y222083D01*
X1559258Y221917D01*
X1559550Y221875D01*
X1559883Y221958D01*
X1560133Y222167D01*
X1560383Y222542D01*
G01X1562650Y221000D02*
Y223500D01*
X1562150Y223000D01*
G01Y221000D02*
X1563150D01*
G01X1568925Y218861D02*
X1567125Y216761D01*
X1564925Y218861D01*
G01X1564517Y265500D02*
Y268000D01*
X1565558D01*
X1565892Y267875D01*
X1566100Y267708D01*
X1566183Y267375D01*
X1566100Y267042D01*
X1565850Y266833D01*
X1565558Y266708D01*
X1564517D01*
G01X1565558D02*
X1566183Y265500D01*
G01X1568450D02*
X1568742Y265542D01*
X1569075Y265667D01*
X1569283Y265875D01*
X1569367Y266167D01*
X1569283Y266458D01*
X1569033Y266708D01*
X1568658Y266833D01*
X1568242D01*
X1567992Y266917D01*
X1567783Y267125D01*
X1567700Y267417D01*
X1567825Y267708D01*
X1568117Y267917D01*
X1568450Y268000D01*
X1568783Y267917D01*
X1569075Y267708D01*
X1569200Y267417D01*
X1569117Y267125D01*
X1568908Y266917D01*
X1568658Y266833D01*
X1568242D01*
X1567867Y266708D01*
X1567617Y266458D01*
X1567533Y266167D01*
X1567617Y265875D01*
X1567825Y265667D01*
X1568158Y265542D01*
X1568450Y265500D01*
G01X1570758Y266542D02*
X1571050Y266833D01*
X1571300Y267000D01*
X1571633Y267083D01*
X1571925Y267000D01*
X1572133Y266833D01*
X1572300Y266583D01*
X1572342Y266292D01*
X1572300Y266042D01*
X1572133Y265792D01*
X1571883Y265583D01*
X1571592Y265500D01*
X1571258Y265583D01*
X1570967Y265833D01*
X1570800Y266208D01*
X1570758Y266625D01*
X1570842Y267167D01*
X1570967Y267458D01*
X1571175Y267750D01*
X1571467Y267958D01*
X1571758Y268000D01*
X1572050Y267917D01*
X1572258Y267708D01*
G01X1574567Y265500D02*
X1574650Y266042D01*
X1574775Y266500D01*
X1574942Y266917D01*
X1575150Y267375D01*
X1575483Y268000D01*
X1573817D01*
G01X1570501Y277307D02*
Y269307D01*
X1552901D01*
Y277307D01*
X1570501D01*
G01X1570708Y288767D02*
X1570583Y288517D01*
X1570500Y288225D01*
Y287892D01*
X1570625Y287517D01*
X1570833Y287225D01*
X1571083Y287017D01*
X1571500Y286850D01*
X1571875Y286808D01*
X1572250Y286892D01*
X1572500Y287017D01*
X1572750Y287267D01*
X1572917Y287558D01*
X1573000Y287850D01*
Y288142D01*
X1572917Y288433D01*
X1572792Y288683D01*
X1572625Y288892D01*
G01X1573000Y291450D02*
X1570500D01*
X1572292Y289908D01*
Y291992D01*
G01X1571958Y293258D02*
X1571667Y293550D01*
X1571500Y293800D01*
X1571417Y294133D01*
X1571500Y294425D01*
X1571667Y294633D01*
X1571917Y294800D01*
X1572208Y294842D01*
X1572458Y294800D01*
X1572708Y294633D01*
X1572917Y294383D01*
X1573000Y294092D01*
X1572917Y293758D01*
X1572667Y293467D01*
X1572292Y293300D01*
X1571875Y293258D01*
X1571333Y293342D01*
X1571042Y293467D01*
X1570750Y293675D01*
X1570542Y293967D01*
X1570500Y294258D01*
X1570583Y294550D01*
X1570792Y294758D01*
G01X1573000Y297150D02*
X1570500D01*
X1571000Y296650D01*
G01X1573000D02*
Y297650D01*
G01X1560925Y267961D02*
Y262461D01*
G01X1552925Y267961D02*
X1560925D01*
G01X1552925Y262461D02*
Y267961D01*
G01X1566708Y288767D02*
X1566583Y288517D01*
X1566500Y288225D01*
Y287892D01*
X1566625Y287517D01*
X1566833Y287225D01*
X1567083Y287017D01*
X1567500Y286850D01*
X1567875Y286808D01*
X1568250Y286892D01*
X1568500Y287017D01*
X1568750Y287267D01*
X1568917Y287558D01*
X1569000Y287850D01*
Y288142D01*
X1568917Y288433D01*
X1568792Y288683D01*
X1568625Y288892D01*
G01X1569000Y291450D02*
X1566500D01*
X1568292Y289908D01*
Y291992D01*
G01X1567958Y293258D02*
X1567667Y293550D01*
X1567500Y293800D01*
X1567417Y294133D01*
X1567500Y294425D01*
X1567667Y294633D01*
X1567917Y294800D01*
X1568208Y294842D01*
X1568458Y294800D01*
X1568708Y294633D01*
X1568917Y294383D01*
X1569000Y294092D01*
X1568917Y293758D01*
X1568667Y293467D01*
X1568292Y293300D01*
X1567875Y293258D01*
X1567333Y293342D01*
X1567042Y293467D01*
X1566750Y293675D01*
X1566542Y293967D01*
X1566500Y294258D01*
X1566583Y294550D01*
X1566792Y294758D01*
G01X1568500Y296233D02*
X1568792Y296483D01*
X1568958Y296817D01*
X1569000Y297192D01*
X1568958Y297525D01*
X1568750Y297858D01*
X1568500Y298067D01*
X1568250Y298108D01*
X1567958Y298025D01*
X1567750Y297733D01*
X1567667Y297442D01*
Y297067D01*
G01Y297442D02*
X1567542Y297692D01*
X1567333Y297900D01*
X1567083Y297983D01*
X1566833Y297900D01*
X1566625Y297692D01*
X1566500Y297317D01*
X1566542Y296942D01*
X1566708Y296567D01*
G01X1545708Y271767D02*
X1545583Y271517D01*
X1545500Y271225D01*
Y270892D01*
X1545625Y270517D01*
X1545833Y270225D01*
X1546083Y270017D01*
X1546500Y269850D01*
X1546875Y269808D01*
X1547250Y269892D01*
X1547500Y270017D01*
X1547750Y270267D01*
X1547917Y270558D01*
X1548000Y270850D01*
Y271142D01*
X1547917Y271433D01*
X1547792Y271683D01*
X1547625Y271892D01*
G01X1548000Y274450D02*
X1545500D01*
X1547292Y272908D01*
Y274992D01*
G01X1547625Y276133D02*
X1547833Y276383D01*
X1547958Y276675D01*
X1548000Y277050D01*
X1547917Y277425D01*
X1547750Y277717D01*
X1547458Y277925D01*
X1547125Y277967D01*
X1546792Y277883D01*
X1546583Y277675D01*
X1546417Y277383D01*
X1546375Y277092D01*
X1546417Y276800D01*
X1546583Y276425D01*
X1545500Y276550D01*
Y277675D01*
G01X1546958Y279358D02*
X1546667Y279650D01*
X1546500Y279900D01*
X1546417Y280233D01*
X1546500Y280525D01*
X1546667Y280733D01*
X1546917Y280900D01*
X1547208Y280942D01*
X1547458Y280900D01*
X1547708Y280733D01*
X1547917Y280483D01*
X1548000Y280192D01*
X1547917Y279858D01*
X1547667Y279567D01*
X1547292Y279400D01*
X1546875Y279358D01*
X1546333Y279442D01*
X1546042Y279567D01*
X1545750Y279775D01*
X1545542Y280067D01*
X1545500Y280358D01*
X1545583Y280650D01*
X1545792Y280858D01*
G01X1524208Y499767D02*
X1524083Y499517D01*
X1524000Y499225D01*
Y498892D01*
X1524125Y498517D01*
X1524333Y498225D01*
X1524583Y498017D01*
X1525000Y497850D01*
X1525375Y497808D01*
X1525750Y497892D01*
X1526000Y498017D01*
X1526250Y498267D01*
X1526417Y498558D01*
X1526500Y498850D01*
Y499142D01*
X1526417Y499433D01*
X1526292Y499683D01*
X1526125Y499892D01*
G01Y501033D02*
X1526333Y501283D01*
X1526458Y501575D01*
X1526500Y501950D01*
X1526417Y502325D01*
X1526250Y502617D01*
X1525958Y502825D01*
X1525625Y502867D01*
X1525292Y502783D01*
X1525083Y502575D01*
X1524917Y502283D01*
X1524875Y501992D01*
X1524917Y501700D01*
X1525083Y501325D01*
X1524000Y501450D01*
Y502575D01*
G01X1525458Y504258D02*
X1525167Y504550D01*
X1525000Y504800D01*
X1524917Y505133D01*
X1525000Y505425D01*
X1525167Y505633D01*
X1525417Y505800D01*
X1525708Y505842D01*
X1525958Y505800D01*
X1526208Y505633D01*
X1526417Y505383D01*
X1526500Y505092D01*
X1526417Y504758D01*
X1526167Y504467D01*
X1525792Y504300D01*
X1525375Y504258D01*
X1524833Y504342D01*
X1524542Y504467D01*
X1524250Y504675D01*
X1524042Y504967D01*
X1524000Y505258D01*
X1524083Y505550D01*
X1524292Y505758D01*
G01X1526500Y508650D02*
X1524000D01*
X1525792Y507108D01*
Y509192D01*
G01X1528708Y500267D02*
X1528583Y500017D01*
X1528500Y499725D01*
Y499392D01*
X1528625Y499017D01*
X1528833Y498725D01*
X1529083Y498517D01*
X1529500Y498350D01*
X1529875Y498308D01*
X1530250Y498392D01*
X1530500Y498517D01*
X1530750Y498767D01*
X1530917Y499058D01*
X1531000Y499350D01*
Y499642D01*
X1530917Y499933D01*
X1530792Y500183D01*
X1530625Y500392D01*
G01Y501533D02*
X1530833Y501783D01*
X1530958Y502075D01*
X1531000Y502450D01*
X1530917Y502825D01*
X1530750Y503117D01*
X1530458Y503325D01*
X1530125Y503367D01*
X1529792Y503283D01*
X1529583Y503075D01*
X1529417Y502783D01*
X1529375Y502492D01*
X1529417Y502200D01*
X1529583Y501825D01*
X1528500Y501950D01*
Y503075D01*
G01X1530625Y504633D02*
X1530833Y504883D01*
X1530958Y505175D01*
X1531000Y505550D01*
X1530917Y505925D01*
X1530750Y506217D01*
X1530458Y506425D01*
X1530125Y506467D01*
X1529792Y506383D01*
X1529583Y506175D01*
X1529417Y505883D01*
X1529375Y505592D01*
X1529417Y505300D01*
X1529583Y504925D01*
X1528500Y505050D01*
Y506175D01*
G01X1529958Y507858D02*
X1529667Y508150D01*
X1529500Y508400D01*
X1529417Y508733D01*
X1529500Y509025D01*
X1529667Y509233D01*
X1529917Y509400D01*
X1530208Y509442D01*
X1530458Y509400D01*
X1530708Y509233D01*
X1530917Y508983D01*
X1531000Y508692D01*
X1530917Y508358D01*
X1530667Y508067D01*
X1530292Y507900D01*
X1529875Y507858D01*
X1529333Y507942D01*
X1529042Y508067D01*
X1528750Y508275D01*
X1528542Y508567D01*
X1528500Y508858D01*
X1528583Y509150D01*
X1528792Y509358D01*
G01X1525967Y514000D02*
Y516500D01*
X1527008D01*
X1527342Y516375D01*
X1527550Y516208D01*
X1527633Y515875D01*
X1527550Y515542D01*
X1527300Y515333D01*
X1527008Y515208D01*
X1525967D01*
G01X1527008D02*
X1527633Y514000D01*
G01X1529900D02*
Y516500D01*
X1529400Y516000D01*
G01Y514000D02*
X1530400D01*
G01X1533000Y516500D02*
X1532667Y516417D01*
X1532417Y516208D01*
X1532250Y515958D01*
X1532125Y515625D01*
X1532083Y515250D01*
X1532125Y514875D01*
X1532250Y514542D01*
X1532417Y514292D01*
X1532667Y514083D01*
X1533000Y514000D01*
X1533333Y514083D01*
X1533583Y514292D01*
X1533750Y514542D01*
X1533875Y514875D01*
X1533917Y515250D01*
X1533875Y515625D01*
X1533750Y515958D01*
X1533583Y516208D01*
X1533333Y516417D01*
X1533000Y516500D01*
G01X1535392Y514292D02*
X1535683Y514083D01*
X1536017Y514000D01*
X1536350Y514083D01*
X1536642Y514333D01*
X1536850Y514708D01*
X1536933Y515083D01*
Y515542D01*
X1536850Y515917D01*
X1536642Y516250D01*
X1536392Y516417D01*
X1536100Y516500D01*
X1535767Y516417D01*
X1535517Y516250D01*
X1535350Y516000D01*
X1535267Y515667D01*
X1535350Y515375D01*
X1535558Y515083D01*
X1535808Y514917D01*
X1536100Y514875D01*
X1536433Y514958D01*
X1536683Y515167D01*
X1536933Y515542D01*
G01X1539700Y514000D02*
Y516500D01*
X1538158Y514708D01*
X1540242D01*
G01X1545334Y526400D02*
X1545292Y526067D01*
X1545126Y525775D01*
X1544876Y525525D01*
X1544584Y525358D01*
X1544251Y525275D01*
X1543917D01*
X1543584Y525358D01*
X1543292Y525525D01*
X1543042Y525775D01*
X1542876Y526067D01*
X1542834Y526400D01*
X1542876Y526733D01*
X1543042Y527025D01*
X1543292Y527275D01*
X1543584Y527442D01*
X1543917Y527525D01*
X1544251D01*
X1544584Y527442D01*
X1544876Y527275D01*
X1545126Y527025D01*
X1545292Y526733D01*
X1545334Y526400D01*
G01X1544667Y526733D02*
X1545334Y527233D01*
G01Y529500D02*
X1542834D01*
X1543334Y529000D01*
G01X1545334D02*
Y530000D01*
G01X1542834Y532600D02*
X1542917Y532267D01*
X1543126Y532017D01*
X1543376Y531850D01*
X1543709Y531725D01*
X1544084Y531683D01*
X1544459Y531725D01*
X1544792Y531850D01*
X1545042Y532017D01*
X1545251Y532267D01*
X1545334Y532600D01*
X1545251Y532933D01*
X1545042Y533183D01*
X1544792Y533350D01*
X1544459Y533475D01*
X1544084Y533517D01*
X1543709Y533475D01*
X1543376Y533350D01*
X1543126Y533183D01*
X1542917Y532933D01*
X1542834Y532600D01*
G01X1527067Y527900D02*
Y530400D01*
X1528108D01*
X1528442Y530275D01*
X1528650Y530108D01*
X1528733Y529775D01*
X1528650Y529442D01*
X1528400Y529233D01*
X1528108Y529108D01*
X1527067D01*
G01X1528108D02*
X1528733Y527900D01*
G01X1531000D02*
Y530400D01*
X1530500Y529900D01*
G01Y527900D02*
X1531500D01*
G01X1534100Y530400D02*
X1533767Y530317D01*
X1533517Y530108D01*
X1533350Y529858D01*
X1533225Y529525D01*
X1533183Y529150D01*
X1533225Y528775D01*
X1533350Y528442D01*
X1533517Y528192D01*
X1533767Y527983D01*
X1534100Y527900D01*
X1534433Y527983D01*
X1534683Y528192D01*
X1534850Y528442D01*
X1534975Y528775D01*
X1535017Y529150D01*
X1534975Y529525D01*
X1534850Y529858D01*
X1534683Y530108D01*
X1534433Y530317D01*
X1534100Y530400D01*
G01X1537200Y527900D02*
X1537492Y527942D01*
X1537825Y528067D01*
X1538033Y528275D01*
X1538117Y528567D01*
X1538033Y528858D01*
X1537783Y529108D01*
X1537408Y529233D01*
X1536992D01*
X1536742Y529317D01*
X1536533Y529525D01*
X1536450Y529817D01*
X1536575Y530108D01*
X1536867Y530317D01*
X1537200Y530400D01*
X1537533Y530317D01*
X1537825Y530108D01*
X1537950Y529817D01*
X1537867Y529525D01*
X1537658Y529317D01*
X1537408Y529233D01*
X1536992D01*
X1536617Y529108D01*
X1536367Y528858D01*
X1536283Y528567D01*
X1536367Y528275D01*
X1536575Y528067D01*
X1536908Y527942D01*
X1537200Y527900D01*
G01X1540300Y530400D02*
X1539967Y530317D01*
X1539717Y530108D01*
X1539550Y529858D01*
X1539425Y529525D01*
X1539383Y529150D01*
X1539425Y528775D01*
X1539550Y528442D01*
X1539717Y528192D01*
X1539967Y527983D01*
X1540300Y527900D01*
X1540633Y527983D01*
X1540883Y528192D01*
X1541050Y528442D01*
X1541175Y528775D01*
X1541217Y529150D01*
X1541175Y529525D01*
X1541050Y529858D01*
X1540883Y530108D01*
X1540633Y530317D01*
X1540300Y530400D01*
G01X1549334Y519967D02*
X1546834D01*
Y521008D01*
X1546959Y521342D01*
X1547126Y521550D01*
X1547459Y521633D01*
X1547792Y521550D01*
X1548001Y521300D01*
X1548126Y521008D01*
Y519967D01*
G01Y521008D02*
X1549334Y521633D01*
G01Y523900D02*
X1546834D01*
X1547334Y523400D01*
G01X1549334D02*
Y524400D01*
G01X1547251Y526208D02*
X1547001Y526458D01*
X1546876Y526750D01*
X1546834Y527083D01*
X1546917Y527500D01*
X1547126Y527792D01*
X1547376Y527875D01*
X1547626Y527833D01*
X1547834Y527667D01*
X1548251Y526833D01*
X1548542Y526458D01*
X1548959Y526208D01*
X1549334Y526125D01*
Y527875D01*
G01X1549042Y529392D02*
X1549251Y529683D01*
X1549334Y530017D01*
X1549251Y530350D01*
X1549001Y530642D01*
X1548626Y530850D01*
X1548251Y530933D01*
X1547792D01*
X1547417Y530850D01*
X1547084Y530642D01*
X1546917Y530392D01*
X1546834Y530100D01*
X1546917Y529767D01*
X1547084Y529517D01*
X1547334Y529350D01*
X1547667Y529267D01*
X1547959Y529350D01*
X1548251Y529558D01*
X1548417Y529808D01*
X1548459Y530100D01*
X1548376Y530433D01*
X1548167Y530683D01*
X1547792Y530933D01*
G01X1548959Y532283D02*
X1549167Y532533D01*
X1549292Y532825D01*
X1549334Y533200D01*
X1549251Y533575D01*
X1549084Y533867D01*
X1548792Y534075D01*
X1548459Y534117D01*
X1548126Y534033D01*
X1547917Y533825D01*
X1547751Y533533D01*
X1547709Y533242D01*
X1547751Y532950D01*
X1547917Y532575D01*
X1546834Y532700D01*
Y533825D01*
G01X1544817Y537459D02*
X1544567Y537584D01*
X1544275Y537667D01*
X1543942D01*
X1543567Y537542D01*
X1543275Y537334D01*
X1543067Y537084D01*
X1542900Y536667D01*
X1542858Y536292D01*
X1542942Y535917D01*
X1543067Y535667D01*
X1543317Y535417D01*
X1543608Y535250D01*
X1543900Y535167D01*
X1544192D01*
X1544483Y535250D01*
X1544733Y535375D01*
X1544942Y535542D01*
G01X1546292Y535459D02*
X1546583Y535250D01*
X1546917Y535167D01*
X1547250Y535250D01*
X1547542Y535500D01*
X1547750Y535875D01*
X1547833Y536250D01*
Y536709D01*
X1547750Y537084D01*
X1547542Y537417D01*
X1547292Y537584D01*
X1547000Y537667D01*
X1546667Y537584D01*
X1546417Y537417D01*
X1546250Y537167D01*
X1546167Y536834D01*
X1546250Y536542D01*
X1546458Y536250D01*
X1546708Y536084D01*
X1547000Y536042D01*
X1547333Y536125D01*
X1547583Y536334D01*
X1547833Y536709D01*
G01X1549183Y535542D02*
X1549433Y535334D01*
X1549725Y535209D01*
X1550100Y535167D01*
X1550475Y535250D01*
X1550767Y535417D01*
X1550975Y535709D01*
X1551017Y536042D01*
X1550933Y536375D01*
X1550725Y536584D01*
X1550433Y536750D01*
X1550142Y536792D01*
X1549850Y536750D01*
X1549475Y536584D01*
X1549600Y537667D01*
X1550725D01*
G01X1524708Y534317D02*
X1524583Y534067D01*
X1524500Y533775D01*
Y533442D01*
X1524625Y533067D01*
X1524833Y532775D01*
X1525083Y532567D01*
X1525500Y532400D01*
X1525875Y532358D01*
X1526250Y532442D01*
X1526500Y532567D01*
X1526750Y532817D01*
X1526917Y533108D01*
X1527000Y533400D01*
Y533692D01*
X1526917Y533983D01*
X1526792Y534233D01*
X1526625Y534442D01*
G01X1524917Y535708D02*
X1524667Y535958D01*
X1524542Y536250D01*
X1524500Y536583D01*
X1524583Y537000D01*
X1524792Y537292D01*
X1525042Y537375D01*
X1525292Y537333D01*
X1525500Y537167D01*
X1525917Y536333D01*
X1526208Y535958D01*
X1526625Y535708D01*
X1527000Y535625D01*
Y537375D01*
G01Y540100D02*
X1524500D01*
X1526292Y538558D01*
Y540642D01*
G01X1557125Y643917D02*
Y647917D01*
X1549725D01*
G01X1561425Y602934D02*
X1558925D01*
Y603975D01*
X1559050Y604309D01*
X1559217Y604517D01*
X1559550Y604600D01*
X1559883Y604517D01*
X1560092Y604267D01*
X1560217Y603975D01*
Y602934D01*
G01Y603975D02*
X1561425Y604600D01*
G01X1561050Y605950D02*
X1561258Y606200D01*
X1561383Y606492D01*
X1561425Y606867D01*
X1561342Y607242D01*
X1561175Y607534D01*
X1560883Y607742D01*
X1560550Y607784D01*
X1560217Y607700D01*
X1560008Y607492D01*
X1559842Y607200D01*
X1559800Y606909D01*
X1559842Y606617D01*
X1560008Y606242D01*
X1558925Y606367D01*
Y607492D01*
G01X1561133Y609259D02*
X1561342Y609550D01*
X1561425Y609884D01*
X1561342Y610217D01*
X1561092Y610509D01*
X1560717Y610717D01*
X1560342Y610800D01*
X1559883D01*
X1559508Y610717D01*
X1559175Y610509D01*
X1559008Y610259D01*
X1558925Y609967D01*
X1559008Y609634D01*
X1559175Y609384D01*
X1559425Y609217D01*
X1559758Y609134D01*
X1560050Y609217D01*
X1560342Y609425D01*
X1560508Y609675D01*
X1560550Y609967D01*
X1560467Y610300D01*
X1560258Y610550D01*
X1559883Y610800D01*
G01X1561425Y613067D02*
X1561383Y613359D01*
X1561258Y613692D01*
X1561050Y613900D01*
X1560758Y613984D01*
X1560467Y613900D01*
X1560217Y613650D01*
X1560092Y613275D01*
Y612859D01*
X1560008Y612609D01*
X1559800Y612400D01*
X1559508Y612317D01*
X1559217Y612442D01*
X1559008Y612734D01*
X1558925Y613067D01*
X1559008Y613400D01*
X1559217Y613692D01*
X1559508Y613817D01*
X1559800Y613734D01*
X1560008Y613525D01*
X1560092Y613275D01*
Y612859D01*
X1560217Y612484D01*
X1560467Y612234D01*
X1560758Y612150D01*
X1561050Y612234D01*
X1561258Y612442D01*
X1561383Y612775D01*
X1561425Y613067D01*
G01X1558425Y616717D02*
X1562425D01*
Y624117D01*
G01X1571425Y602934D02*
X1568925D01*
Y603975D01*
X1569050Y604309D01*
X1569217Y604517D01*
X1569550Y604600D01*
X1569883Y604517D01*
X1570092Y604267D01*
X1570217Y603975D01*
Y602934D01*
G01Y603975D02*
X1571425Y604600D01*
G01X1570383Y606075D02*
X1570092Y606367D01*
X1569925Y606617D01*
X1569842Y606950D01*
X1569925Y607242D01*
X1570092Y607450D01*
X1570342Y607617D01*
X1570633Y607659D01*
X1570883Y607617D01*
X1571133Y607450D01*
X1571342Y607200D01*
X1571425Y606909D01*
X1571342Y606575D01*
X1571092Y606284D01*
X1570717Y606117D01*
X1570300Y606075D01*
X1569758Y606159D01*
X1569467Y606284D01*
X1569175Y606492D01*
X1568967Y606784D01*
X1568925Y607075D01*
X1569008Y607367D01*
X1569217Y607575D01*
G01X1568925Y609967D02*
X1569008Y609634D01*
X1569217Y609384D01*
X1569467Y609217D01*
X1569800Y609092D01*
X1570175Y609050D01*
X1570550Y609092D01*
X1570883Y609217D01*
X1571133Y609384D01*
X1571342Y609634D01*
X1571425Y609967D01*
X1571342Y610300D01*
X1571133Y610550D01*
X1570883Y610717D01*
X1570550Y610842D01*
X1570175Y610884D01*
X1569800Y610842D01*
X1569467Y610717D01*
X1569217Y610550D01*
X1569008Y610300D01*
X1568925Y609967D01*
G01Y613067D02*
X1569008Y612734D01*
X1569217Y612484D01*
X1569467Y612317D01*
X1569800Y612192D01*
X1570175Y612150D01*
X1570550Y612192D01*
X1570883Y612317D01*
X1571133Y612484D01*
X1571342Y612734D01*
X1571425Y613067D01*
X1571342Y613400D01*
X1571133Y613650D01*
X1570883Y613817D01*
X1570550Y613942D01*
X1570175Y613984D01*
X1569800Y613942D01*
X1569467Y613817D01*
X1569217Y613650D01*
X1569008Y613400D01*
X1568925Y613067D01*
G01X1568425Y616717D02*
X1572425D01*
Y624117D01*
G01X1556925Y602934D02*
X1554425D01*
Y603975D01*
X1554550Y604309D01*
X1554717Y604517D01*
X1555050Y604600D01*
X1555383Y604517D01*
X1555592Y604267D01*
X1555717Y603975D01*
Y602934D01*
G01Y603975D02*
X1556925Y604600D01*
G01X1555883Y606075D02*
X1555592Y606367D01*
X1555425Y606617D01*
X1555342Y606950D01*
X1555425Y607242D01*
X1555592Y607450D01*
X1555842Y607617D01*
X1556133Y607659D01*
X1556383Y607617D01*
X1556633Y607450D01*
X1556842Y607200D01*
X1556925Y606909D01*
X1556842Y606575D01*
X1556592Y606284D01*
X1556217Y606117D01*
X1555800Y606075D01*
X1555258Y606159D01*
X1554967Y606284D01*
X1554675Y606492D01*
X1554467Y606784D01*
X1554425Y607075D01*
X1554508Y607367D01*
X1554717Y607575D01*
G01X1554425Y609967D02*
X1554508Y609634D01*
X1554717Y609384D01*
X1554967Y609217D01*
X1555300Y609092D01*
X1555675Y609050D01*
X1556050Y609092D01*
X1556383Y609217D01*
X1556633Y609384D01*
X1556842Y609634D01*
X1556925Y609967D01*
X1556842Y610300D01*
X1556633Y610550D01*
X1556383Y610717D01*
X1556050Y610842D01*
X1555675Y610884D01*
X1555300Y610842D01*
X1554967Y610717D01*
X1554717Y610550D01*
X1554508Y610300D01*
X1554425Y609967D01*
G01X1554842Y612275D02*
X1554592Y612525D01*
X1554467Y612817D01*
X1554425Y613150D01*
X1554508Y613567D01*
X1554717Y613859D01*
X1554967Y613942D01*
X1555217Y613900D01*
X1555425Y613734D01*
X1555842Y612900D01*
X1556133Y612525D01*
X1556550Y612275D01*
X1556925Y612192D01*
Y613942D01*
G01X1557925Y624117D02*
X1553925D01*
Y616717D01*
G01X1570725Y651417D02*
Y647417D01*
X1578125D01*
G01X1568225Y629117D02*
X1572225D01*
Y636517D01*
G01X1547833Y626850D02*
X1547791Y626517D01*
X1547625Y626225D01*
X1547375Y625975D01*
X1547083Y625808D01*
X1546750Y625725D01*
X1546416D01*
X1546083Y625808D01*
X1545791Y625975D01*
X1545541Y626225D01*
X1545375Y626517D01*
X1545333Y626850D01*
X1545375Y627183D01*
X1545541Y627475D01*
X1545791Y627725D01*
X1546083Y627892D01*
X1546416Y627975D01*
X1546750D01*
X1547083Y627892D01*
X1547375Y627725D01*
X1547625Y627475D01*
X1547791Y627183D01*
X1547833Y626850D01*
G01X1547166Y627183D02*
X1547833Y627683D01*
G01Y629950D02*
X1545333D01*
X1545833Y629450D01*
G01X1547833D02*
Y630450D01*
G01X1545750Y632258D02*
X1545500Y632508D01*
X1545375Y632800D01*
X1545333Y633133D01*
X1545416Y633550D01*
X1545625Y633842D01*
X1545875Y633925D01*
X1546125Y633883D01*
X1546333Y633717D01*
X1546750Y632883D01*
X1547041Y632508D01*
X1547458Y632258D01*
X1547833Y632175D01*
Y633925D01*
G01Y636150D02*
X1545333D01*
X1545833Y635650D01*
G01X1547833D02*
Y636650D01*
G01X1549225Y636617D02*
Y625217D01*
G01X1562625Y636617D02*
X1549225D01*
G01X1562625Y625217D02*
Y636617D01*
G01X1549225Y625217D02*
X1562625D01*
G01X1579925Y639417D02*
X1563825D01*
G01Y646417D02*
X1579925D01*
G01X1563825Y639417D02*
Y646417D01*
G01X1547517Y684500D02*
Y687000D01*
X1548558D01*
X1548892Y686875D01*
X1549100Y686708D01*
X1549183Y686375D01*
X1549100Y686042D01*
X1548850Y685833D01*
X1548558Y685708D01*
X1547517D01*
G01X1548558D02*
X1549183Y684500D01*
G01X1550533Y684875D02*
X1550783Y684667D01*
X1551075Y684542D01*
X1551450Y684500D01*
X1551825Y684583D01*
X1552117Y684750D01*
X1552325Y685042D01*
X1552367Y685375D01*
X1552283Y685708D01*
X1552075Y685917D01*
X1551783Y686083D01*
X1551492Y686125D01*
X1551200Y686083D01*
X1550825Y685917D01*
X1550950Y687000D01*
X1552075D01*
G01X1554550Y684500D02*
X1554842Y684542D01*
X1555175Y684667D01*
X1555383Y684875D01*
X1555467Y685167D01*
X1555383Y685458D01*
X1555133Y685708D01*
X1554758Y685833D01*
X1554342D01*
X1554092Y685917D01*
X1553883Y686125D01*
X1553800Y686417D01*
X1553925Y686708D01*
X1554217Y686917D01*
X1554550Y687000D01*
X1554883Y686917D01*
X1555175Y686708D01*
X1555300Y686417D01*
X1555217Y686125D01*
X1555008Y685917D01*
X1554758Y685833D01*
X1554342D01*
X1553967Y685708D01*
X1553717Y685458D01*
X1553633Y685167D01*
X1553717Y684875D01*
X1553925Y684667D01*
X1554258Y684542D01*
X1554550Y684500D01*
G01X1556942Y684792D02*
X1557233Y684583D01*
X1557567Y684500D01*
X1557900Y684583D01*
X1558192Y684833D01*
X1558400Y685208D01*
X1558483Y685583D01*
Y686042D01*
X1558400Y686417D01*
X1558192Y686750D01*
X1557942Y686917D01*
X1557650Y687000D01*
X1557317Y686917D01*
X1557067Y686750D01*
X1556900Y686500D01*
X1556817Y686167D01*
X1556900Y685875D01*
X1557108Y685583D01*
X1557358Y685417D01*
X1557650Y685375D01*
X1557983Y685458D01*
X1558233Y685667D01*
X1558483Y686042D01*
G01X1562225Y697417D02*
Y689417D01*
X1544625D01*
Y697417D01*
X1562225D01*
G01X1563725Y698917D02*
X1565825Y697117D01*
X1563725Y694917D01*
G01X1563625Y691317D02*
X1582825D01*
Y702517D01*
X1563625D01*
Y691317D01*
X1564025D01*
G01X1548350Y675500D02*
X1548017Y675542D01*
X1547725Y675708D01*
X1547475Y675958D01*
X1547308Y676250D01*
X1547225Y676583D01*
Y676917D01*
X1547308Y677250D01*
X1547475Y677542D01*
X1547725Y677792D01*
X1548017Y677958D01*
X1548350Y678000D01*
X1548683Y677958D01*
X1548975Y677792D01*
X1549225Y677542D01*
X1549392Y677250D01*
X1549475Y676917D01*
Y676583D01*
X1549392Y676250D01*
X1549225Y675958D01*
X1548975Y675708D01*
X1548683Y675542D01*
X1548350Y675500D01*
G01X1548683Y676167D02*
X1549183Y675500D01*
G01X1551450D02*
Y678000D01*
X1550950Y677500D01*
G01Y675500D02*
X1551950D01*
G01X1554550D02*
Y678000D01*
X1554050Y677500D01*
G01Y675500D02*
X1555050D01*
G01X1556942Y675792D02*
X1557233Y675583D01*
X1557567Y675500D01*
X1557900Y675583D01*
X1558192Y675833D01*
X1558400Y676208D01*
X1558483Y676583D01*
Y677042D01*
X1558400Y677417D01*
X1558192Y677750D01*
X1557942Y677917D01*
X1557650Y678000D01*
X1557317Y677917D01*
X1557067Y677750D01*
X1556900Y677500D01*
X1556817Y677167D01*
X1556900Y676875D01*
X1557108Y676583D01*
X1557358Y676417D01*
X1557650Y676375D01*
X1557983Y676458D01*
X1558233Y676667D01*
X1558483Y677042D01*
G01X1563925Y673617D02*
X1562125Y671517D01*
X1559925Y673617D01*
G01X1556325Y673717D02*
Y654517D01*
X1567525D01*
Y673717D01*
X1556325D01*
Y673317D01*
G01X1562517Y731000D02*
Y733500D01*
X1563558D01*
X1563892Y733375D01*
X1564100Y733208D01*
X1564183Y732875D01*
X1564100Y732542D01*
X1563850Y732333D01*
X1563558Y732208D01*
X1562517D01*
G01X1563558D02*
X1564183Y731000D01*
G01X1565533Y731375D02*
X1565783Y731167D01*
X1566075Y731042D01*
X1566450Y731000D01*
X1566825Y731083D01*
X1567117Y731250D01*
X1567325Y731542D01*
X1567367Y731875D01*
X1567283Y732208D01*
X1567075Y732417D01*
X1566783Y732583D01*
X1566492Y732625D01*
X1566200Y732583D01*
X1565825Y732417D01*
X1565950Y733500D01*
X1567075D01*
G01X1568842Y731292D02*
X1569133Y731083D01*
X1569467Y731000D01*
X1569800Y731083D01*
X1570092Y731333D01*
X1570300Y731708D01*
X1570383Y732083D01*
Y732542D01*
X1570300Y732917D01*
X1570092Y733250D01*
X1569842Y733417D01*
X1569550Y733500D01*
X1569217Y733417D01*
X1568967Y733250D01*
X1568800Y733000D01*
X1568717Y732667D01*
X1568800Y732375D01*
X1569008Y732083D01*
X1569258Y731917D01*
X1569550Y731875D01*
X1569883Y731958D01*
X1570133Y732167D01*
X1570383Y732542D01*
G01X1572650Y731000D02*
Y733500D01*
X1572150Y733000D01*
G01Y731000D02*
X1573150D01*
G01X1570501Y730182D02*
Y722182D01*
X1552901D01*
Y730182D01*
X1570501D01*
G01X1570208Y741267D02*
X1570083Y741017D01*
X1570000Y740725D01*
Y740392D01*
X1570125Y740017D01*
X1570333Y739725D01*
X1570583Y739517D01*
X1571000Y739350D01*
X1571375Y739308D01*
X1571750Y739392D01*
X1572000Y739517D01*
X1572250Y739767D01*
X1572417Y740058D01*
X1572500Y740350D01*
Y740642D01*
X1572417Y740933D01*
X1572292Y741183D01*
X1572125Y741392D01*
G01X1572000Y742533D02*
X1572292Y742783D01*
X1572458Y743117D01*
X1572500Y743492D01*
X1572458Y743825D01*
X1572250Y744158D01*
X1572000Y744367D01*
X1571750Y744408D01*
X1571458Y744325D01*
X1571250Y744033D01*
X1571167Y743742D01*
Y743367D01*
G01Y743742D02*
X1571042Y743992D01*
X1570833Y744200D01*
X1570583Y744283D01*
X1570333Y744200D01*
X1570125Y743992D01*
X1570000Y743617D01*
X1570042Y743242D01*
X1570208Y742867D01*
G01X1570000Y746550D02*
X1570083Y746217D01*
X1570292Y745967D01*
X1570542Y745800D01*
X1570875Y745675D01*
X1571250Y745633D01*
X1571625Y745675D01*
X1571958Y745800D01*
X1572208Y745967D01*
X1572417Y746217D01*
X1572500Y746550D01*
X1572417Y746883D01*
X1572208Y747133D01*
X1571958Y747300D01*
X1571625Y747425D01*
X1571250Y747467D01*
X1570875Y747425D01*
X1570542Y747300D01*
X1570292Y747133D01*
X1570083Y746883D01*
X1570000Y746550D01*
G01X1572125Y748733D02*
X1572333Y748983D01*
X1572458Y749275D01*
X1572500Y749650D01*
X1572417Y750025D01*
X1572250Y750317D01*
X1571958Y750525D01*
X1571625Y750567D01*
X1571292Y750483D01*
X1571083Y750275D01*
X1570917Y749983D01*
X1570875Y749692D01*
X1570917Y749400D01*
X1571083Y749025D01*
X1570000Y749150D01*
Y750275D01*
G01X1549208Y701267D02*
X1549083Y701017D01*
X1549000Y700725D01*
Y700392D01*
X1549125Y700017D01*
X1549333Y699725D01*
X1549583Y699517D01*
X1550000Y699350D01*
X1550375Y699308D01*
X1550750Y699392D01*
X1551000Y699517D01*
X1551250Y699767D01*
X1551417Y700058D01*
X1551500Y700350D01*
Y700642D01*
X1551417Y700933D01*
X1551292Y701183D01*
X1551125Y701392D01*
G01X1551000Y702533D02*
X1551292Y702783D01*
X1551458Y703117D01*
X1551500Y703492D01*
X1551458Y703825D01*
X1551250Y704158D01*
X1551000Y704367D01*
X1550750Y704408D01*
X1550458Y704325D01*
X1550250Y704033D01*
X1550167Y703742D01*
Y703367D01*
G01Y703742D02*
X1550042Y703992D01*
X1549833Y704200D01*
X1549583Y704283D01*
X1549333Y704200D01*
X1549125Y703992D01*
X1549000Y703617D01*
X1549042Y703242D01*
X1549208Y702867D01*
G01X1549000Y706550D02*
X1549083Y706217D01*
X1549292Y705967D01*
X1549542Y705800D01*
X1549875Y705675D01*
X1550250Y705633D01*
X1550625Y705675D01*
X1550958Y705800D01*
X1551208Y705967D01*
X1551417Y706217D01*
X1551500Y706550D01*
X1551417Y706883D01*
X1551208Y707133D01*
X1550958Y707300D01*
X1550625Y707425D01*
X1550250Y707467D01*
X1549875Y707425D01*
X1549542Y707300D01*
X1549292Y707133D01*
X1549083Y706883D01*
X1549000Y706550D01*
G01X1551500Y709650D02*
X1549000D01*
X1549500Y709150D01*
G01X1551500D02*
Y710150D01*
G01X1552925Y703117D02*
Y708617D01*
G01X1560925Y703117D02*
X1552925D01*
G01X1560925Y708617D02*
Y703117D01*
G01Y720717D02*
Y715217D01*
G01X1552925Y720717D02*
X1560925D01*
G01X1552925Y715217D02*
Y720717D01*
G01X1566208Y741267D02*
X1566083Y741017D01*
X1566000Y740725D01*
Y740392D01*
X1566125Y740017D01*
X1566333Y739725D01*
X1566583Y739517D01*
X1567000Y739350D01*
X1567375Y739308D01*
X1567750Y739392D01*
X1568000Y739517D01*
X1568250Y739767D01*
X1568417Y740058D01*
X1568500Y740350D01*
Y740642D01*
X1568417Y740933D01*
X1568292Y741183D01*
X1568125Y741392D01*
G01X1568000Y742533D02*
X1568292Y742783D01*
X1568458Y743117D01*
X1568500Y743492D01*
X1568458Y743825D01*
X1568250Y744158D01*
X1568000Y744367D01*
X1567750Y744408D01*
X1567458Y744325D01*
X1567250Y744033D01*
X1567167Y743742D01*
Y743367D01*
G01Y743742D02*
X1567042Y743992D01*
X1566833Y744200D01*
X1566583Y744283D01*
X1566333Y744200D01*
X1566125Y743992D01*
X1566000Y743617D01*
X1566042Y743242D01*
X1566208Y742867D01*
G01X1566000Y746550D02*
X1566083Y746217D01*
X1566292Y745967D01*
X1566542Y745800D01*
X1566875Y745675D01*
X1567250Y745633D01*
X1567625Y745675D01*
X1567958Y745800D01*
X1568208Y745967D01*
X1568417Y746217D01*
X1568500Y746550D01*
X1568417Y746883D01*
X1568208Y747133D01*
X1567958Y747300D01*
X1567625Y747425D01*
X1567250Y747467D01*
X1566875Y747425D01*
X1566542Y747300D01*
X1566292Y747133D01*
X1566083Y746883D01*
X1566000Y746550D01*
G01X1568500Y749567D02*
X1567958Y749650D01*
X1567500Y749775D01*
X1567083Y749942D01*
X1566625Y750150D01*
X1566000Y750483D01*
Y748817D01*
G01X1546208Y724767D02*
X1546083Y724517D01*
X1546000Y724225D01*
Y723892D01*
X1546125Y723517D01*
X1546333Y723225D01*
X1546583Y723017D01*
X1547000Y722850D01*
X1547375Y722808D01*
X1547750Y722892D01*
X1548000Y723017D01*
X1548250Y723267D01*
X1548417Y723558D01*
X1548500Y723850D01*
Y724142D01*
X1548417Y724433D01*
X1548292Y724683D01*
X1548125Y724892D01*
G01X1548000Y726033D02*
X1548292Y726283D01*
X1548458Y726617D01*
X1548500Y726992D01*
X1548458Y727325D01*
X1548250Y727658D01*
X1548000Y727867D01*
X1547750Y727908D01*
X1547458Y727825D01*
X1547250Y727533D01*
X1547167Y727242D01*
Y726867D01*
G01Y727242D02*
X1547042Y727492D01*
X1546833Y727700D01*
X1546583Y727783D01*
X1546333Y727700D01*
X1546125Y727492D01*
X1546000Y727117D01*
X1546042Y726742D01*
X1546208Y726367D01*
G01X1546000Y730050D02*
X1546083Y729717D01*
X1546292Y729467D01*
X1546542Y729300D01*
X1546875Y729175D01*
X1547250Y729133D01*
X1547625Y729175D01*
X1547958Y729300D01*
X1548208Y729467D01*
X1548417Y729717D01*
X1548500Y730050D01*
X1548417Y730383D01*
X1548208Y730633D01*
X1547958Y730800D01*
X1547625Y730925D01*
X1547250Y730967D01*
X1546875Y730925D01*
X1546542Y730800D01*
X1546292Y730633D01*
X1546083Y730383D01*
X1546000Y730050D01*
G01Y733150D02*
X1546083Y732817D01*
X1546292Y732567D01*
X1546542Y732400D01*
X1546875Y732275D01*
X1547250Y732233D01*
X1547625Y732275D01*
X1547958Y732400D01*
X1548208Y732567D01*
X1548417Y732817D01*
X1548500Y733150D01*
X1548417Y733483D01*
X1548208Y733733D01*
X1547958Y733900D01*
X1547625Y734025D01*
X1547250Y734067D01*
X1546875Y734025D01*
X1546542Y733900D01*
X1546292Y733733D01*
X1546083Y733483D01*
X1546000Y733150D01*
G01X1561425Y1054690D02*
X1558925D01*
Y1055731D01*
X1559050Y1056065D01*
X1559217Y1056273D01*
X1559550Y1056356D01*
X1559883Y1056273D01*
X1560092Y1056023D01*
X1560217Y1055731D01*
Y1054690D01*
G01Y1055731D02*
X1561425Y1056356D01*
G01X1560925Y1057706D02*
X1561217Y1057956D01*
X1561383Y1058290D01*
X1561425Y1058665D01*
X1561383Y1058998D01*
X1561175Y1059331D01*
X1560925Y1059540D01*
X1560675Y1059581D01*
X1560383Y1059498D01*
X1560175Y1059206D01*
X1560092Y1058915D01*
Y1058540D01*
G01Y1058915D02*
X1559967Y1059165D01*
X1559758Y1059373D01*
X1559508Y1059456D01*
X1559258Y1059373D01*
X1559050Y1059165D01*
X1558925Y1058790D01*
X1558967Y1058415D01*
X1559133Y1058040D01*
G01X1559342Y1060931D02*
X1559092Y1061181D01*
X1558967Y1061473D01*
X1558925Y1061806D01*
X1559008Y1062223D01*
X1559217Y1062515D01*
X1559467Y1062598D01*
X1559717Y1062556D01*
X1559925Y1062390D01*
X1560342Y1061556D01*
X1560633Y1061181D01*
X1561050Y1060931D01*
X1561425Y1060848D01*
Y1062598D01*
G01X1559342Y1064031D02*
X1559092Y1064281D01*
X1558967Y1064573D01*
X1558925Y1064906D01*
X1559008Y1065323D01*
X1559217Y1065615D01*
X1559467Y1065698D01*
X1559717Y1065656D01*
X1559925Y1065490D01*
X1560342Y1064656D01*
X1560633Y1064281D01*
X1561050Y1064031D01*
X1561425Y1063948D01*
Y1065698D01*
G01X1558425Y1069473D02*
X1562425D01*
Y1076873D01*
G01X1567834Y1055517D02*
X1565334D01*
Y1056558D01*
X1565459Y1056892D01*
X1565626Y1057100D01*
X1565959Y1057183D01*
X1566292Y1057100D01*
X1566501Y1056850D01*
X1566626Y1056558D01*
Y1055517D01*
G01Y1056558D02*
X1567834Y1057183D01*
G01X1567334Y1058533D02*
X1567626Y1058783D01*
X1567792Y1059117D01*
X1567834Y1059492D01*
X1567792Y1059825D01*
X1567584Y1060158D01*
X1567334Y1060367D01*
X1567084Y1060408D01*
X1566792Y1060325D01*
X1566584Y1060033D01*
X1566501Y1059742D01*
Y1059367D01*
G01Y1059742D02*
X1566376Y1059992D01*
X1566167Y1060200D01*
X1565917Y1060283D01*
X1565667Y1060200D01*
X1565459Y1059992D01*
X1565334Y1059617D01*
X1565376Y1059242D01*
X1565542Y1058867D01*
G01X1565751Y1061758D02*
X1565501Y1062008D01*
X1565376Y1062300D01*
X1565334Y1062633D01*
X1565417Y1063050D01*
X1565626Y1063342D01*
X1565876Y1063425D01*
X1566126Y1063383D01*
X1566334Y1063217D01*
X1566751Y1062383D01*
X1567042Y1062008D01*
X1567459Y1061758D01*
X1567834Y1061675D01*
Y1063425D01*
G01X1567459Y1064733D02*
X1567667Y1064983D01*
X1567792Y1065275D01*
X1567834Y1065650D01*
X1567751Y1066025D01*
X1567584Y1066317D01*
X1567292Y1066525D01*
X1566959Y1066567D01*
X1566626Y1066483D01*
X1566417Y1066275D01*
X1566251Y1065983D01*
X1566209Y1065692D01*
X1566251Y1065400D01*
X1566417Y1065025D01*
X1565334Y1065150D01*
Y1066275D01*
G01X1568425Y1069473D02*
X1572425D01*
Y1076873D01*
G01X1556925Y1054690D02*
X1554425D01*
Y1055731D01*
X1554550Y1056065D01*
X1554717Y1056273D01*
X1555050Y1056356D01*
X1555383Y1056273D01*
X1555592Y1056023D01*
X1555717Y1055731D01*
Y1054690D01*
G01Y1055731D02*
X1556925Y1056356D01*
G01X1556425Y1057706D02*
X1556717Y1057956D01*
X1556883Y1058290D01*
X1556925Y1058665D01*
X1556883Y1058998D01*
X1556675Y1059331D01*
X1556425Y1059540D01*
X1556175Y1059581D01*
X1555883Y1059498D01*
X1555675Y1059206D01*
X1555592Y1058915D01*
Y1058540D01*
G01Y1058915D02*
X1555467Y1059165D01*
X1555258Y1059373D01*
X1555008Y1059456D01*
X1554758Y1059373D01*
X1554550Y1059165D01*
X1554425Y1058790D01*
X1554467Y1058415D01*
X1554633Y1058040D01*
G01X1554842Y1060931D02*
X1554592Y1061181D01*
X1554467Y1061473D01*
X1554425Y1061806D01*
X1554508Y1062223D01*
X1554717Y1062515D01*
X1554967Y1062598D01*
X1555217Y1062556D01*
X1555425Y1062390D01*
X1555842Y1061556D01*
X1556133Y1061181D01*
X1556550Y1060931D01*
X1556925Y1060848D01*
Y1062598D01*
G01Y1064740D02*
X1556383Y1064823D01*
X1555925Y1064948D01*
X1555508Y1065115D01*
X1555050Y1065323D01*
X1554425Y1065656D01*
Y1063990D01*
G01X1557925Y1076873D02*
X1553925D01*
Y1069473D01*
G01X1568425Y1081973D02*
X1572425D01*
Y1089373D01*
G01X1549225D02*
Y1077973D01*
G01X1562625D02*
Y1089373D01*
G01X1549225Y1077973D02*
X1562625D01*
G01X1558342Y1131273D02*
Y1133773D01*
X1559383D01*
X1559717Y1133648D01*
X1559925Y1133481D01*
X1560008Y1133148D01*
X1559925Y1132815D01*
X1559675Y1132606D01*
X1559383Y1132481D01*
X1558342D01*
G01X1559383D02*
X1560008Y1131273D01*
G01X1561358Y1131773D02*
X1561608Y1131481D01*
X1561942Y1131315D01*
X1562317Y1131273D01*
X1562650Y1131315D01*
X1562983Y1131523D01*
X1563192Y1131773D01*
X1563233Y1132023D01*
X1563150Y1132315D01*
X1562858Y1132523D01*
X1562567Y1132606D01*
X1562192D01*
G01X1562567D02*
X1562817Y1132731D01*
X1563025Y1132940D01*
X1563108Y1133190D01*
X1563025Y1133440D01*
X1562817Y1133648D01*
X1562442Y1133773D01*
X1562067Y1133731D01*
X1561692Y1133565D01*
G01X1564583Y1133356D02*
X1564833Y1133606D01*
X1565125Y1133731D01*
X1565458Y1133773D01*
X1565875Y1133690D01*
X1566167Y1133481D01*
X1566250Y1133231D01*
X1566208Y1132981D01*
X1566042Y1132773D01*
X1565208Y1132356D01*
X1564833Y1132065D01*
X1564583Y1131648D01*
X1564500Y1131273D01*
X1566250D01*
G01X1568475D02*
Y1133773D01*
X1567975Y1133273D01*
G01Y1131273D02*
X1568975D01*
G01X1554525Y1130273D02*
Y1134273D01*
X1547125D01*
G01X1555900Y1090500D02*
X1555567Y1090542D01*
X1555275Y1090708D01*
X1555025Y1090958D01*
X1554858Y1091250D01*
X1554775Y1091583D01*
Y1091917D01*
X1554858Y1092250D01*
X1555025Y1092542D01*
X1555275Y1092792D01*
X1555567Y1092958D01*
X1555900Y1093000D01*
X1556233Y1092958D01*
X1556525Y1092792D01*
X1556775Y1092542D01*
X1556942Y1092250D01*
X1557025Y1091917D01*
Y1091583D01*
X1556942Y1091250D01*
X1556775Y1090958D01*
X1556525Y1090708D01*
X1556233Y1090542D01*
X1555900Y1090500D01*
G01X1556233Y1091167D02*
X1556733Y1090500D01*
G01X1559500D02*
Y1093000D01*
X1557958Y1091208D01*
X1560042D01*
G01X1561392Y1090792D02*
X1561683Y1090583D01*
X1562017Y1090500D01*
X1562350Y1090583D01*
X1562642Y1090833D01*
X1562850Y1091208D01*
X1562933Y1091583D01*
Y1092042D01*
X1562850Y1092417D01*
X1562642Y1092750D01*
X1562392Y1092917D01*
X1562100Y1093000D01*
X1561767Y1092917D01*
X1561517Y1092750D01*
X1561350Y1092500D01*
X1561267Y1092167D01*
X1561350Y1091875D01*
X1561558Y1091583D01*
X1561808Y1091417D01*
X1562100Y1091375D01*
X1562433Y1091458D01*
X1562683Y1091667D01*
X1562933Y1092042D01*
G01X1562625Y1089373D02*
X1549225D01*
G01X1568400Y1092200D02*
X1568067Y1092242D01*
X1567775Y1092408D01*
X1567525Y1092658D01*
X1567358Y1092950D01*
X1567275Y1093283D01*
Y1093617D01*
X1567358Y1093950D01*
X1567525Y1094242D01*
X1567775Y1094492D01*
X1568067Y1094658D01*
X1568400Y1094700D01*
X1568733Y1094658D01*
X1569025Y1094492D01*
X1569275Y1094242D01*
X1569442Y1093950D01*
X1569525Y1093617D01*
Y1093283D01*
X1569442Y1092950D01*
X1569275Y1092658D01*
X1569025Y1092408D01*
X1568733Y1092242D01*
X1568400Y1092200D01*
G01X1568733Y1092867D02*
X1569233Y1092200D01*
G01X1570583Y1092575D02*
X1570833Y1092367D01*
X1571125Y1092242D01*
X1571500Y1092200D01*
X1571875Y1092283D01*
X1572167Y1092450D01*
X1572375Y1092742D01*
X1572417Y1093075D01*
X1572333Y1093408D01*
X1572125Y1093617D01*
X1571833Y1093783D01*
X1571542Y1093825D01*
X1571250Y1093783D01*
X1570875Y1093617D01*
X1571000Y1094700D01*
X1572125D01*
G01X1574600D02*
X1574267Y1094617D01*
X1574017Y1094408D01*
X1573850Y1094158D01*
X1573725Y1093825D01*
X1573683Y1093450D01*
X1573725Y1093075D01*
X1573850Y1092742D01*
X1574017Y1092492D01*
X1574267Y1092283D01*
X1574600Y1092200D01*
X1574933Y1092283D01*
X1575183Y1092492D01*
X1575350Y1092742D01*
X1575475Y1093075D01*
X1575517Y1093450D01*
X1575475Y1093825D01*
X1575350Y1094158D01*
X1575183Y1094408D01*
X1574933Y1094617D01*
X1574600Y1094700D01*
G01X1555400Y1094667D02*
X1555067Y1094709D01*
X1554775Y1094875D01*
X1554525Y1095125D01*
X1554358Y1095417D01*
X1554275Y1095750D01*
Y1096084D01*
X1554358Y1096417D01*
X1554525Y1096709D01*
X1554775Y1096959D01*
X1555067Y1097125D01*
X1555400Y1097167D01*
X1555733Y1097125D01*
X1556025Y1096959D01*
X1556275Y1096709D01*
X1556442Y1096417D01*
X1556525Y1096084D01*
Y1095750D01*
X1556442Y1095417D01*
X1556275Y1095125D01*
X1556025Y1094875D01*
X1555733Y1094709D01*
X1555400Y1094667D01*
G01X1555733Y1095334D02*
X1556233Y1094667D01*
G01X1559000D02*
Y1097167D01*
X1557458Y1095375D01*
X1559542D01*
G01X1561600Y1094667D02*
X1561892Y1094709D01*
X1562225Y1094834D01*
X1562433Y1095042D01*
X1562517Y1095334D01*
X1562433Y1095625D01*
X1562183Y1095875D01*
X1561808Y1096000D01*
X1561392D01*
X1561142Y1096084D01*
X1560933Y1096292D01*
X1560850Y1096584D01*
X1560975Y1096875D01*
X1561267Y1097084D01*
X1561600Y1097167D01*
X1561933Y1097084D01*
X1562225Y1096875D01*
X1562350Y1096584D01*
X1562267Y1096292D01*
X1562058Y1096084D01*
X1561808Y1096000D01*
X1561392D01*
X1561017Y1095875D01*
X1560767Y1095625D01*
X1560683Y1095334D01*
X1560767Y1095042D01*
X1560975Y1094834D01*
X1561308Y1094709D01*
X1561600Y1094667D01*
G01X1567273Y1113175D02*
X1565173Y1114975D01*
X1567273Y1117175D01*
G01X1567373Y1120775D02*
X1548173D01*
Y1109575D01*
X1567373D01*
Y1120775D01*
X1566973D01*
G01X1545517Y1151500D02*
Y1154000D01*
X1546558D01*
X1546892Y1153875D01*
X1547100Y1153708D01*
X1547183Y1153375D01*
X1547100Y1153042D01*
X1546850Y1152833D01*
X1546558Y1152708D01*
X1545517D01*
G01X1546558D02*
X1547183Y1151500D01*
G01X1548533Y1152000D02*
X1548783Y1151708D01*
X1549117Y1151542D01*
X1549492Y1151500D01*
X1549825Y1151542D01*
X1550158Y1151750D01*
X1550367Y1152000D01*
X1550408Y1152250D01*
X1550325Y1152542D01*
X1550033Y1152750D01*
X1549742Y1152833D01*
X1549367D01*
G01X1549742D02*
X1549992Y1152958D01*
X1550200Y1153167D01*
X1550283Y1153417D01*
X1550200Y1153667D01*
X1549992Y1153875D01*
X1549617Y1154000D01*
X1549242Y1153958D01*
X1548867Y1153792D01*
G01X1552550Y1151500D02*
Y1154000D01*
X1552050Y1153500D01*
G01Y1151500D02*
X1553050D01*
G01X1554733Y1152000D02*
X1554983Y1151708D01*
X1555317Y1151542D01*
X1555692Y1151500D01*
X1556025Y1151542D01*
X1556358Y1151750D01*
X1556567Y1152000D01*
X1556608Y1152250D01*
X1556525Y1152542D01*
X1556233Y1152750D01*
X1555942Y1152833D01*
X1555567D01*
G01X1555942D02*
X1556192Y1152958D01*
X1556400Y1153167D01*
X1556483Y1153417D01*
X1556400Y1153667D01*
X1556192Y1153875D01*
X1555817Y1154000D01*
X1555442Y1153958D01*
X1555067Y1153792D01*
G01X1562225Y1150173D02*
Y1142173D01*
X1544625D01*
Y1150173D01*
X1562225D01*
G01X1570559Y1183291D02*
Y1175291D01*
X1552959D01*
Y1183291D01*
X1570559D01*
G01X1568208Y1163767D02*
X1568083Y1163517D01*
X1568000Y1163225D01*
Y1162892D01*
X1568125Y1162517D01*
X1568333Y1162225D01*
X1568583Y1162017D01*
X1569000Y1161850D01*
X1569375Y1161808D01*
X1569750Y1161892D01*
X1570000Y1162017D01*
X1570250Y1162267D01*
X1570417Y1162558D01*
X1570500Y1162850D01*
Y1163142D01*
X1570417Y1163433D01*
X1570292Y1163683D01*
X1570125Y1163892D01*
G01X1570500Y1165950D02*
X1568000D01*
X1568500Y1165450D01*
G01X1570500D02*
Y1166450D01*
G01Y1169550D02*
X1568000D01*
X1569792Y1168008D01*
Y1170092D01*
G01X1570125Y1171233D02*
X1570333Y1171483D01*
X1570458Y1171775D01*
X1570500Y1172150D01*
X1570417Y1172525D01*
X1570250Y1172817D01*
X1569958Y1173025D01*
X1569625Y1173067D01*
X1569292Y1172983D01*
X1569083Y1172775D01*
X1568917Y1172483D01*
X1568875Y1172192D01*
X1568917Y1171900D01*
X1569083Y1171525D01*
X1568000Y1171650D01*
Y1172775D01*
G01X1552925Y1155873D02*
Y1161373D01*
G01X1560925Y1155873D02*
X1552925D01*
G01X1560925Y1161373D02*
Y1155873D01*
G01Y1173473D02*
Y1167973D01*
G01X1552925Y1173473D02*
X1560925D01*
G01X1552925Y1167973D02*
Y1173473D01*
G01X1564208Y1163767D02*
X1564083Y1163517D01*
X1564000Y1163225D01*
Y1162892D01*
X1564125Y1162517D01*
X1564333Y1162225D01*
X1564583Y1162017D01*
X1565000Y1161850D01*
X1565375Y1161808D01*
X1565750Y1161892D01*
X1566000Y1162017D01*
X1566250Y1162267D01*
X1566417Y1162558D01*
X1566500Y1162850D01*
Y1163142D01*
X1566417Y1163433D01*
X1566292Y1163683D01*
X1566125Y1163892D01*
G01X1566500Y1165950D02*
X1564000D01*
X1564500Y1165450D01*
G01X1566500D02*
Y1166450D01*
G01Y1169550D02*
X1564000D01*
X1565792Y1168008D01*
Y1170092D01*
G01X1566500Y1172650D02*
X1564000D01*
X1565792Y1171108D01*
Y1173192D01*
G01X1560092Y1137665D02*
X1559842Y1137790D01*
X1559550Y1137873D01*
X1559217D01*
X1558842Y1137748D01*
X1558550Y1137540D01*
X1558342Y1137290D01*
X1558175Y1136873D01*
X1558133Y1136498D01*
X1558217Y1136123D01*
X1558342Y1135873D01*
X1558592Y1135623D01*
X1558883Y1135456D01*
X1559175Y1135373D01*
X1559467D01*
X1559758Y1135456D01*
X1560008Y1135581D01*
X1560217Y1135748D01*
G01X1562275Y1135373D02*
Y1137873D01*
X1561775Y1137373D01*
G01Y1135373D02*
X1562775D01*
G01X1564458Y1135748D02*
X1564708Y1135540D01*
X1565000Y1135415D01*
X1565375Y1135373D01*
X1565750Y1135456D01*
X1566042Y1135623D01*
X1566250Y1135915D01*
X1566292Y1136248D01*
X1566208Y1136581D01*
X1566000Y1136790D01*
X1565708Y1136956D01*
X1565417Y1136998D01*
X1565125Y1136956D01*
X1564750Y1136790D01*
X1564875Y1137873D01*
X1566000D01*
G01X1567683Y1137456D02*
X1567933Y1137706D01*
X1568225Y1137831D01*
X1568558Y1137873D01*
X1568975Y1137790D01*
X1569267Y1137581D01*
X1569350Y1137331D01*
X1569308Y1137081D01*
X1569142Y1136873D01*
X1568308Y1136456D01*
X1567933Y1136165D01*
X1567683Y1135748D01*
X1567600Y1135373D01*
X1569350D01*
G01X1570133Y1194940D02*
X1570008Y1194690D01*
X1569925Y1194398D01*
Y1194065D01*
X1570050Y1193690D01*
X1570258Y1193398D01*
X1570508Y1193190D01*
X1570925Y1193023D01*
X1571300Y1192981D01*
X1571675Y1193065D01*
X1571925Y1193190D01*
X1572175Y1193440D01*
X1572342Y1193731D01*
X1572425Y1194023D01*
Y1194315D01*
X1572342Y1194606D01*
X1572217Y1194856D01*
X1572050Y1195065D01*
G01X1572425Y1197123D02*
X1569925D01*
X1570425Y1196623D01*
G01X1572425D02*
Y1197623D01*
G01X1572050Y1199306D02*
X1572258Y1199556D01*
X1572383Y1199848D01*
X1572425Y1200223D01*
X1572342Y1200598D01*
X1572175Y1200890D01*
X1571883Y1201098D01*
X1571550Y1201140D01*
X1571217Y1201056D01*
X1571008Y1200848D01*
X1570842Y1200556D01*
X1570800Y1200265D01*
X1570842Y1199973D01*
X1571008Y1199598D01*
X1569925Y1199723D01*
Y1200848D01*
G01Y1203323D02*
X1570008Y1202990D01*
X1570217Y1202740D01*
X1570467Y1202573D01*
X1570800Y1202448D01*
X1571175Y1202406D01*
X1571550Y1202448D01*
X1571883Y1202573D01*
X1572133Y1202740D01*
X1572342Y1202990D01*
X1572425Y1203323D01*
X1572342Y1203656D01*
X1572133Y1203906D01*
X1571883Y1204073D01*
X1571550Y1204198D01*
X1571175Y1204240D01*
X1570800Y1204198D01*
X1570467Y1204073D01*
X1570217Y1203906D01*
X1570008Y1203656D01*
X1569925Y1203323D01*
G01X1566133Y1194940D02*
X1566008Y1194690D01*
X1565925Y1194398D01*
Y1194065D01*
X1566050Y1193690D01*
X1566258Y1193398D01*
X1566508Y1193190D01*
X1566925Y1193023D01*
X1567300Y1192981D01*
X1567675Y1193065D01*
X1567925Y1193190D01*
X1568175Y1193440D01*
X1568342Y1193731D01*
X1568425Y1194023D01*
Y1194315D01*
X1568342Y1194606D01*
X1568217Y1194856D01*
X1568050Y1195065D01*
G01X1568425Y1197123D02*
X1565925D01*
X1566425Y1196623D01*
G01X1568425D02*
Y1197623D01*
G01X1568050Y1199306D02*
X1568258Y1199556D01*
X1568383Y1199848D01*
X1568425Y1200223D01*
X1568342Y1200598D01*
X1568175Y1200890D01*
X1567883Y1201098D01*
X1567550Y1201140D01*
X1567217Y1201056D01*
X1567008Y1200848D01*
X1566842Y1200556D01*
X1566800Y1200265D01*
X1566842Y1199973D01*
X1567008Y1199598D01*
X1565925Y1199723D01*
Y1200848D01*
G01X1568425Y1203323D02*
X1565925D01*
X1566425Y1202823D01*
G01X1568425D02*
Y1203823D01*
G01X1565117Y1653028D02*
Y1657028D01*
X1562650Y1654161D01*
X1565984D01*
G01X1531355Y1653828D02*
X1531755Y1653361D01*
X1532289Y1653095D01*
X1532889Y1653028D01*
X1533422Y1653095D01*
X1533955Y1653428D01*
X1534289Y1653828D01*
X1534355Y1654228D01*
X1534222Y1654695D01*
X1533755Y1655028D01*
X1533289Y1655161D01*
X1532689D01*
G01X1533289D02*
X1533689Y1655361D01*
X1534022Y1655695D01*
X1534155Y1656095D01*
X1534022Y1656495D01*
X1533689Y1656828D01*
X1533089Y1657028D01*
X1532489Y1656961D01*
X1531889Y1656695D01*
G01X1606200Y73900D02*
Y46100D01*
X1634000D01*
Y73900D01*
X1606200D01*
G01X1581356Y124660D02*
X1578856D01*
Y125701D01*
X1578981Y126035D01*
X1579148Y126243D01*
X1579481Y126326D01*
X1579814Y126243D01*
X1580023Y125993D01*
X1580148Y125701D01*
Y124660D01*
G01Y125701D02*
X1581356Y126326D01*
G01Y128593D02*
X1578856D01*
X1579356Y128093D01*
G01X1581356D02*
Y129093D01*
G01X1579273Y130901D02*
X1579023Y131151D01*
X1578898Y131443D01*
X1578856Y131776D01*
X1578939Y132193D01*
X1579148Y132485D01*
X1579398Y132568D01*
X1579648Y132526D01*
X1579856Y132360D01*
X1580273Y131526D01*
X1580564Y131151D01*
X1580981Y130901D01*
X1581356Y130818D01*
Y132568D01*
G01X1587757Y131704D02*
X1583757D01*
Y124304D01*
G01X1587942Y189661D02*
Y192161D01*
X1588983D01*
X1589317Y192036D01*
X1589525Y191869D01*
X1589608Y191536D01*
X1589525Y191203D01*
X1589275Y190994D01*
X1588983Y190869D01*
X1587942D01*
G01X1588983D02*
X1589608Y189661D01*
G01X1591875D02*
X1592167Y189703D01*
X1592500Y189828D01*
X1592708Y190036D01*
X1592792Y190328D01*
X1592708Y190619D01*
X1592458Y190869D01*
X1592083Y190994D01*
X1591667D01*
X1591417Y191078D01*
X1591208Y191286D01*
X1591125Y191578D01*
X1591250Y191869D01*
X1591542Y192078D01*
X1591875Y192161D01*
X1592208Y192078D01*
X1592500Y191869D01*
X1592625Y191578D01*
X1592542Y191286D01*
X1592333Y191078D01*
X1592083Y190994D01*
X1591667D01*
X1591292Y190869D01*
X1591042Y190619D01*
X1590958Y190328D01*
X1591042Y190036D01*
X1591250Y189828D01*
X1591583Y189703D01*
X1591875Y189661D01*
G01X1594892D02*
X1594975Y190203D01*
X1595100Y190661D01*
X1595267Y191078D01*
X1595475Y191536D01*
X1595808Y192161D01*
X1594142D01*
G01X1597158Y190161D02*
X1597408Y189869D01*
X1597742Y189703D01*
X1598117Y189661D01*
X1598450Y189703D01*
X1598783Y189911D01*
X1598992Y190161D01*
X1599033Y190411D01*
X1598950Y190703D01*
X1598658Y190911D01*
X1598367Y190994D01*
X1597992D01*
G01X1598367D02*
X1598617Y191119D01*
X1598825Y191328D01*
X1598908Y191578D01*
X1598825Y191828D01*
X1598617Y192036D01*
X1598242Y192161D01*
X1597867Y192119D01*
X1597492Y191953D01*
G01X1584925Y171578D02*
X1582425D01*
Y172619D01*
X1582550Y172953D01*
X1582717Y173161D01*
X1583050Y173244D01*
X1583383Y173161D01*
X1583592Y172911D01*
X1583717Y172619D01*
Y171578D01*
G01Y172619D02*
X1584925Y173244D01*
G01Y175511D02*
X1584883Y175803D01*
X1584758Y176136D01*
X1584550Y176344D01*
X1584258Y176428D01*
X1583967Y176344D01*
X1583717Y176094D01*
X1583592Y175719D01*
Y175303D01*
X1583508Y175053D01*
X1583300Y174844D01*
X1583008Y174761D01*
X1582717Y174886D01*
X1582508Y175178D01*
X1582425Y175511D01*
X1582508Y175844D01*
X1582717Y176136D01*
X1583008Y176261D01*
X1583300Y176178D01*
X1583508Y175969D01*
X1583592Y175719D01*
Y175303D01*
X1583717Y174928D01*
X1583967Y174678D01*
X1584258Y174594D01*
X1584550Y174678D01*
X1584758Y174886D01*
X1584883Y175219D01*
X1584925Y175511D01*
G01Y178528D02*
X1584383Y178611D01*
X1583925Y178736D01*
X1583508Y178903D01*
X1583050Y179111D01*
X1582425Y179444D01*
Y177778D01*
G01X1584633Y181003D02*
X1584842Y181294D01*
X1584925Y181628D01*
X1584842Y181961D01*
X1584592Y182253D01*
X1584217Y182461D01*
X1583842Y182544D01*
X1583383D01*
X1583008Y182461D01*
X1582675Y182253D01*
X1582508Y182003D01*
X1582425Y181711D01*
X1582508Y181378D01*
X1582675Y181128D01*
X1582925Y180961D01*
X1583258Y180878D01*
X1583550Y180961D01*
X1583842Y181169D01*
X1584008Y181419D01*
X1584050Y181711D01*
X1583967Y182044D01*
X1583758Y182294D01*
X1583383Y182544D01*
G01X1572925Y176361D02*
X1576925D01*
Y183761D01*
G01X1601517Y193500D02*
Y196000D01*
X1602558D01*
X1602892Y195875D01*
X1603100Y195708D01*
X1603183Y195375D01*
X1603100Y195042D01*
X1602850Y194833D01*
X1602558Y194708D01*
X1601517D01*
G01X1602558D02*
X1603183Y193500D01*
G01X1605450D02*
X1605742Y193542D01*
X1606075Y193667D01*
X1606283Y193875D01*
X1606367Y194167D01*
X1606283Y194458D01*
X1606033Y194708D01*
X1605658Y194833D01*
X1605242D01*
X1604992Y194917D01*
X1604783Y195125D01*
X1604700Y195417D01*
X1604825Y195708D01*
X1605117Y195917D01*
X1605450Y196000D01*
X1605783Y195917D01*
X1606075Y195708D01*
X1606200Y195417D01*
X1606117Y195125D01*
X1605908Y194917D01*
X1605658Y194833D01*
X1605242D01*
X1604867Y194708D01*
X1604617Y194458D01*
X1604533Y194167D01*
X1604617Y193875D01*
X1604825Y193667D01*
X1605158Y193542D01*
X1605450Y193500D01*
G01X1608550D02*
X1608842Y193542D01*
X1609175Y193667D01*
X1609383Y193875D01*
X1609467Y194167D01*
X1609383Y194458D01*
X1609133Y194708D01*
X1608758Y194833D01*
X1608342D01*
X1608092Y194917D01*
X1607883Y195125D01*
X1607800Y195417D01*
X1607925Y195708D01*
X1608217Y195917D01*
X1608550Y196000D01*
X1608883Y195917D01*
X1609175Y195708D01*
X1609300Y195417D01*
X1609217Y195125D01*
X1609008Y194917D01*
X1608758Y194833D01*
X1608342D01*
X1607967Y194708D01*
X1607717Y194458D01*
X1607633Y194167D01*
X1607717Y193875D01*
X1607925Y193667D01*
X1608258Y193542D01*
X1608550Y193500D01*
G01X1610858Y195583D02*
X1611108Y195833D01*
X1611400Y195958D01*
X1611733Y196000D01*
X1612150Y195917D01*
X1612442Y195708D01*
X1612525Y195458D01*
X1612483Y195208D01*
X1612317Y195000D01*
X1611483Y194583D01*
X1611108Y194292D01*
X1610858Y193875D01*
X1610775Y193500D01*
X1612525D01*
G01X1575725Y196661D02*
Y192661D01*
X1583125D01*
G01X1580975Y171508D02*
X1578475D01*
Y172549D01*
X1578600Y172883D01*
X1578767Y173091D01*
X1579100Y173174D01*
X1579433Y173091D01*
X1579642Y172841D01*
X1579767Y172549D01*
Y171508D01*
G01Y172549D02*
X1580975Y173174D01*
G01Y175441D02*
X1580933Y175733D01*
X1580808Y176066D01*
X1580600Y176274D01*
X1580308Y176358D01*
X1580017Y176274D01*
X1579767Y176024D01*
X1579642Y175649D01*
Y175233D01*
X1579558Y174983D01*
X1579350Y174774D01*
X1579058Y174691D01*
X1578767Y174816D01*
X1578558Y175108D01*
X1578475Y175441D01*
X1578558Y175774D01*
X1578767Y176066D01*
X1579058Y176191D01*
X1579350Y176108D01*
X1579558Y175899D01*
X1579642Y175649D01*
Y175233D01*
X1579767Y174858D01*
X1580017Y174608D01*
X1580308Y174524D01*
X1580600Y174608D01*
X1580808Y174816D01*
X1580933Y175149D01*
X1580975Y175441D01*
G01Y178541D02*
X1580933Y178833D01*
X1580808Y179166D01*
X1580600Y179374D01*
X1580308Y179458D01*
X1580017Y179374D01*
X1579767Y179124D01*
X1579642Y178749D01*
Y178333D01*
X1579558Y178083D01*
X1579350Y177874D01*
X1579058Y177791D01*
X1578767Y177916D01*
X1578558Y178208D01*
X1578475Y178541D01*
X1578558Y178874D01*
X1578767Y179166D01*
X1579058Y179291D01*
X1579350Y179208D01*
X1579558Y178999D01*
X1579642Y178749D01*
Y178333D01*
X1579767Y177958D01*
X1580017Y177708D01*
X1580308Y177624D01*
X1580600Y177708D01*
X1580808Y177916D01*
X1580933Y178249D01*
X1580975Y178541D01*
G01X1580475Y180724D02*
X1580767Y180974D01*
X1580933Y181308D01*
X1580975Y181683D01*
X1580933Y182016D01*
X1580725Y182349D01*
X1580475Y182558D01*
X1580225Y182599D01*
X1579933Y182516D01*
X1579725Y182224D01*
X1579642Y181933D01*
Y181558D01*
G01Y181933D02*
X1579517Y182183D01*
X1579308Y182391D01*
X1579058Y182474D01*
X1578808Y182391D01*
X1578600Y182183D01*
X1578475Y181808D01*
X1578517Y181433D01*
X1578683Y181058D01*
G01X1601408Y189661D02*
Y192161D01*
X1602242D01*
X1602575Y192036D01*
X1602825Y191869D01*
X1603033Y191619D01*
X1603200Y191328D01*
X1603242Y190911D01*
X1603200Y190494D01*
X1603033Y190203D01*
X1602825Y189953D01*
X1602575Y189786D01*
X1602242Y189661D01*
X1601408D01*
G01X1604508Y190161D02*
X1604758Y189869D01*
X1605092Y189703D01*
X1605467Y189661D01*
X1605800Y189703D01*
X1606133Y189911D01*
X1606342Y190161D01*
X1606383Y190411D01*
X1606300Y190703D01*
X1606008Y190911D01*
X1605717Y190994D01*
X1605342D01*
G01X1605717D02*
X1605967Y191119D01*
X1606175Y191328D01*
X1606258Y191578D01*
X1606175Y191828D01*
X1605967Y192036D01*
X1605592Y192161D01*
X1605217Y192119D01*
X1604842Y191953D01*
G01X1607733Y191744D02*
X1607983Y191994D01*
X1608275Y192119D01*
X1608608Y192161D01*
X1609025Y192078D01*
X1609317Y191869D01*
X1609400Y191619D01*
X1609358Y191369D01*
X1609192Y191161D01*
X1608358Y190744D01*
X1607983Y190453D01*
X1607733Y190036D01*
X1607650Y189661D01*
X1609400D01*
G01X1584925Y191661D02*
Y184661D01*
G01X1619683Y172684D02*
X1619433Y172809D01*
X1619141Y172892D01*
X1618808D01*
X1618433Y172767D01*
X1618141Y172559D01*
X1617933Y172309D01*
X1617766Y171892D01*
X1617724Y171517D01*
X1617808Y171142D01*
X1617933Y170892D01*
X1618183Y170642D01*
X1618474Y170475D01*
X1618766Y170392D01*
X1619058D01*
X1619349Y170475D01*
X1619599Y170600D01*
X1619808Y170767D01*
G01X1622366Y170392D02*
Y172892D01*
X1620824Y171100D01*
X1622908D01*
G01X1624174Y171434D02*
X1624466Y171725D01*
X1624716Y171892D01*
X1625049Y171975D01*
X1625341Y171892D01*
X1625549Y171725D01*
X1625716Y171475D01*
X1625758Y171184D01*
X1625716Y170934D01*
X1625549Y170684D01*
X1625299Y170475D01*
X1625008Y170392D01*
X1624674Y170475D01*
X1624383Y170725D01*
X1624216Y171100D01*
X1624174Y171517D01*
X1624258Y172059D01*
X1624383Y172350D01*
X1624591Y172642D01*
X1624883Y172850D01*
X1625174Y172892D01*
X1625466Y172809D01*
X1625674Y172600D01*
G01X1628066Y170392D02*
X1628358Y170434D01*
X1628691Y170559D01*
X1628899Y170767D01*
X1628983Y171059D01*
X1628899Y171350D01*
X1628649Y171600D01*
X1628274Y171725D01*
X1627858D01*
X1627608Y171809D01*
X1627399Y172017D01*
X1627316Y172309D01*
X1627441Y172600D01*
X1627733Y172809D01*
X1628066Y172892D01*
X1628399Y172809D01*
X1628691Y172600D01*
X1628816Y172309D01*
X1628733Y172017D01*
X1628524Y171809D01*
X1628274Y171725D01*
X1627858D01*
X1627483Y171600D01*
X1627233Y171350D01*
X1627149Y171059D01*
X1627233Y170767D01*
X1627441Y170559D01*
X1627774Y170434D01*
X1628066Y170392D01*
G01X1619767Y176292D02*
X1619517Y176417D01*
X1619225Y176500D01*
X1618892D01*
X1618517Y176375D01*
X1618225Y176167D01*
X1618017Y175917D01*
X1617850Y175500D01*
X1617808Y175125D01*
X1617892Y174750D01*
X1618017Y174500D01*
X1618267Y174250D01*
X1618558Y174083D01*
X1618850Y174000D01*
X1619142D01*
X1619433Y174083D01*
X1619683Y174208D01*
X1619892Y174375D01*
G01X1622450Y174000D02*
Y176500D01*
X1620908Y174708D01*
X1622992D01*
G01X1624258Y175042D02*
X1624550Y175333D01*
X1624800Y175500D01*
X1625133Y175583D01*
X1625425Y175500D01*
X1625633Y175333D01*
X1625800Y175083D01*
X1625842Y174792D01*
X1625800Y174542D01*
X1625633Y174292D01*
X1625383Y174083D01*
X1625092Y174000D01*
X1624758Y174083D01*
X1624467Y174333D01*
X1624300Y174708D01*
X1624258Y175125D01*
X1624342Y175667D01*
X1624467Y175958D01*
X1624675Y176250D01*
X1624967Y176458D01*
X1625258Y176500D01*
X1625550Y176417D01*
X1625758Y176208D01*
G01X1628067Y174000D02*
X1628150Y174542D01*
X1628275Y175000D01*
X1628442Y175417D01*
X1628650Y175875D01*
X1628983Y176500D01*
X1627317D01*
G01X1589692Y196053D02*
X1589442Y196178D01*
X1589150Y196261D01*
X1588817D01*
X1588442Y196136D01*
X1588150Y195928D01*
X1587942Y195678D01*
X1587775Y195261D01*
X1587733Y194886D01*
X1587817Y194511D01*
X1587942Y194261D01*
X1588192Y194011D01*
X1588483Y193844D01*
X1588775Y193761D01*
X1589067D01*
X1589358Y193844D01*
X1589608Y193969D01*
X1589817Y194136D01*
G01X1592375Y193761D02*
Y196261D01*
X1590833Y194469D01*
X1592917D01*
G01X1594183Y194803D02*
X1594475Y195094D01*
X1594725Y195261D01*
X1595058Y195344D01*
X1595350Y195261D01*
X1595558Y195094D01*
X1595725Y194844D01*
X1595767Y194553D01*
X1595725Y194303D01*
X1595558Y194053D01*
X1595308Y193844D01*
X1595017Y193761D01*
X1594683Y193844D01*
X1594392Y194094D01*
X1594225Y194469D01*
X1594183Y194886D01*
X1594267Y195428D01*
X1594392Y195719D01*
X1594600Y196011D01*
X1594892Y196219D01*
X1595183Y196261D01*
X1595475Y196178D01*
X1595683Y195969D01*
G01X1598575Y193761D02*
Y196261D01*
X1597033Y194469D01*
X1599117D01*
G01X1586942Y222161D02*
Y224661D01*
X1587983D01*
X1588317Y224536D01*
X1588525Y224369D01*
X1588608Y224036D01*
X1588525Y223703D01*
X1588275Y223494D01*
X1587983Y223369D01*
X1586942D01*
G01X1587983D02*
X1588608Y222161D01*
G01X1590875D02*
X1591167Y222203D01*
X1591500Y222328D01*
X1591708Y222536D01*
X1591792Y222828D01*
X1591708Y223119D01*
X1591458Y223369D01*
X1591083Y223494D01*
X1590667D01*
X1590417Y223578D01*
X1590208Y223786D01*
X1590125Y224078D01*
X1590250Y224369D01*
X1590542Y224578D01*
X1590875Y224661D01*
X1591208Y224578D01*
X1591500Y224369D01*
X1591625Y224078D01*
X1591542Y223786D01*
X1591333Y223578D01*
X1591083Y223494D01*
X1590667D01*
X1590292Y223369D01*
X1590042Y223119D01*
X1589958Y222828D01*
X1590042Y222536D01*
X1590250Y222328D01*
X1590583Y222203D01*
X1590875Y222161D01*
G01X1593975D02*
X1594267Y222203D01*
X1594600Y222328D01*
X1594808Y222536D01*
X1594892Y222828D01*
X1594808Y223119D01*
X1594558Y223369D01*
X1594183Y223494D01*
X1593767D01*
X1593517Y223578D01*
X1593308Y223786D01*
X1593225Y224078D01*
X1593350Y224369D01*
X1593642Y224578D01*
X1593975Y224661D01*
X1594308Y224578D01*
X1594600Y224369D01*
X1594725Y224078D01*
X1594642Y223786D01*
X1594433Y223578D01*
X1594183Y223494D01*
X1593767D01*
X1593392Y223369D01*
X1593142Y223119D01*
X1593058Y222828D01*
X1593142Y222536D01*
X1593350Y222328D01*
X1593683Y222203D01*
X1593975Y222161D01*
G01X1597075Y224661D02*
X1596742Y224578D01*
X1596492Y224369D01*
X1596325Y224119D01*
X1596200Y223786D01*
X1596158Y223411D01*
X1596200Y223036D01*
X1596325Y222703D01*
X1596492Y222453D01*
X1596742Y222244D01*
X1597075Y222161D01*
X1597408Y222244D01*
X1597658Y222453D01*
X1597825Y222703D01*
X1597950Y223036D01*
X1597992Y223411D01*
X1597950Y223786D01*
X1597825Y224119D01*
X1597658Y224369D01*
X1597408Y224578D01*
X1597075Y224661D01*
G01X1585625Y221661D02*
Y225661D01*
X1578225D01*
G01X1608255Y243661D02*
Y246161D01*
X1609296D01*
X1609630Y246036D01*
X1609838Y245869D01*
X1609921Y245536D01*
X1609838Y245203D01*
X1609588Y244994D01*
X1609296Y244869D01*
X1608255D01*
G01X1609296D02*
X1609921Y243661D01*
G01X1612188D02*
X1612480Y243703D01*
X1612813Y243828D01*
X1613021Y244036D01*
X1613105Y244328D01*
X1613021Y244619D01*
X1612771Y244869D01*
X1612396Y244994D01*
X1611980D01*
X1611730Y245078D01*
X1611521Y245286D01*
X1611438Y245578D01*
X1611563Y245869D01*
X1611855Y246078D01*
X1612188Y246161D01*
X1612521Y246078D01*
X1612813Y245869D01*
X1612938Y245578D01*
X1612855Y245286D01*
X1612646Y245078D01*
X1612396Y244994D01*
X1611980D01*
X1611605Y244869D01*
X1611355Y244619D01*
X1611271Y244328D01*
X1611355Y244036D01*
X1611563Y243828D01*
X1611896Y243703D01*
X1612188Y243661D01*
G01X1615288D02*
X1615580Y243703D01*
X1615913Y243828D01*
X1616121Y244036D01*
X1616205Y244328D01*
X1616121Y244619D01*
X1615871Y244869D01*
X1615496Y244994D01*
X1615080D01*
X1614830Y245078D01*
X1614621Y245286D01*
X1614538Y245578D01*
X1614663Y245869D01*
X1614955Y246078D01*
X1615288Y246161D01*
X1615621Y246078D01*
X1615913Y245869D01*
X1616038Y245578D01*
X1615955Y245286D01*
X1615746Y245078D01*
X1615496Y244994D01*
X1615080D01*
X1614705Y244869D01*
X1614455Y244619D01*
X1614371Y244328D01*
X1614455Y244036D01*
X1614663Y243828D01*
X1614996Y243703D01*
X1615288Y243661D01*
G01X1617680Y243953D02*
X1617971Y243744D01*
X1618305Y243661D01*
X1618638Y243744D01*
X1618930Y243994D01*
X1619138Y244369D01*
X1619221Y244744D01*
Y245203D01*
X1619138Y245578D01*
X1618930Y245911D01*
X1618680Y246078D01*
X1618388Y246161D01*
X1618055Y246078D01*
X1617805Y245911D01*
X1617638Y245661D01*
X1617555Y245328D01*
X1617638Y245036D01*
X1617846Y244744D01*
X1618096Y244578D01*
X1618388Y244536D01*
X1618721Y244619D01*
X1618971Y244828D01*
X1619221Y245203D01*
G01X1576850Y260000D02*
X1576517Y260042D01*
X1576225Y260208D01*
X1575975Y260458D01*
X1575808Y260750D01*
X1575725Y261083D01*
Y261417D01*
X1575808Y261750D01*
X1575975Y262042D01*
X1576225Y262292D01*
X1576517Y262458D01*
X1576850Y262500D01*
X1577183Y262458D01*
X1577475Y262292D01*
X1577725Y262042D01*
X1577892Y261750D01*
X1577975Y261417D01*
Y261083D01*
X1577892Y260750D01*
X1577725Y260458D01*
X1577475Y260208D01*
X1577183Y260042D01*
X1576850Y260000D01*
G01X1577183Y260667D02*
X1577683Y260000D01*
G01X1579950D02*
Y262500D01*
X1579450Y262000D01*
G01Y260000D02*
X1580450D01*
G01X1582342Y260292D02*
X1582633Y260083D01*
X1582967Y260000D01*
X1583300Y260083D01*
X1583592Y260333D01*
X1583800Y260708D01*
X1583883Y261083D01*
Y261542D01*
X1583800Y261917D01*
X1583592Y262250D01*
X1583342Y262417D01*
X1583050Y262500D01*
X1582717Y262417D01*
X1582467Y262250D01*
X1582300Y262000D01*
X1582217Y261667D01*
X1582300Y261375D01*
X1582508Y261083D01*
X1582758Y260917D01*
X1583050Y260875D01*
X1583383Y260958D01*
X1583633Y261167D01*
X1583883Y261542D01*
G01X1586650Y260000D02*
Y262500D01*
X1585108Y260708D01*
X1587192D01*
G01X1608017Y255000D02*
Y257500D01*
X1609058D01*
X1609392Y257375D01*
X1609600Y257208D01*
X1609683Y256875D01*
X1609600Y256542D01*
X1609350Y256333D01*
X1609058Y256208D01*
X1608017D01*
G01X1609058D02*
X1609683Y255000D01*
G01X1611950D02*
X1612242Y255042D01*
X1612575Y255167D01*
X1612783Y255375D01*
X1612867Y255667D01*
X1612783Y255958D01*
X1612533Y256208D01*
X1612158Y256333D01*
X1611742D01*
X1611492Y256417D01*
X1611283Y256625D01*
X1611200Y256917D01*
X1611325Y257208D01*
X1611617Y257417D01*
X1611950Y257500D01*
X1612283Y257417D01*
X1612575Y257208D01*
X1612700Y256917D01*
X1612617Y256625D01*
X1612408Y256417D01*
X1612158Y256333D01*
X1611742D01*
X1611367Y256208D01*
X1611117Y255958D01*
X1611033Y255667D01*
X1611117Y255375D01*
X1611325Y255167D01*
X1611658Y255042D01*
X1611950Y255000D01*
G01X1614342Y255292D02*
X1614633Y255083D01*
X1614967Y255000D01*
X1615300Y255083D01*
X1615592Y255333D01*
X1615800Y255708D01*
X1615883Y256083D01*
Y256542D01*
X1615800Y256917D01*
X1615592Y257250D01*
X1615342Y257417D01*
X1615050Y257500D01*
X1614717Y257417D01*
X1614467Y257250D01*
X1614300Y257000D01*
X1614217Y256667D01*
X1614300Y256375D01*
X1614508Y256083D01*
X1614758Y255917D01*
X1615050Y255875D01*
X1615383Y255958D01*
X1615633Y256167D01*
X1615883Y256542D01*
G01X1617233Y255500D02*
X1617483Y255208D01*
X1617817Y255042D01*
X1618192Y255000D01*
X1618525Y255042D01*
X1618858Y255250D01*
X1619067Y255500D01*
X1619108Y255750D01*
X1619025Y256042D01*
X1618733Y256250D01*
X1618442Y256333D01*
X1618067D01*
G01X1618442D02*
X1618692Y256458D01*
X1618900Y256667D01*
X1618983Y256917D01*
X1618900Y257167D01*
X1618692Y257375D01*
X1618317Y257500D01*
X1617942Y257458D01*
X1617567Y257292D01*
G01X1610005Y241853D02*
X1609755Y241978D01*
X1609463Y242061D01*
X1609130D01*
X1608755Y241936D01*
X1608463Y241728D01*
X1608255Y241478D01*
X1608088Y241061D01*
X1608046Y240686D01*
X1608130Y240311D01*
X1608255Y240061D01*
X1608505Y239811D01*
X1608796Y239644D01*
X1609088Y239561D01*
X1609380D01*
X1609671Y239644D01*
X1609921Y239769D01*
X1610130Y239936D01*
G01X1612688Y239561D02*
Y242061D01*
X1611146Y240269D01*
X1613230D01*
G01X1615205Y239561D02*
X1615288Y240103D01*
X1615413Y240561D01*
X1615580Y240978D01*
X1615788Y241436D01*
X1616121Y242061D01*
X1614455D01*
G01X1618888Y239561D02*
Y242061D01*
X1617346Y240269D01*
X1619430D01*
G01X1588692Y228553D02*
X1588442Y228678D01*
X1588150Y228761D01*
X1587817D01*
X1587442Y228636D01*
X1587150Y228428D01*
X1586942Y228178D01*
X1586775Y227761D01*
X1586733Y227386D01*
X1586817Y227011D01*
X1586942Y226761D01*
X1587192Y226511D01*
X1587483Y226344D01*
X1587775Y226261D01*
X1588067D01*
X1588358Y226344D01*
X1588608Y226469D01*
X1588817Y226636D01*
G01X1591375Y226261D02*
Y228761D01*
X1589833Y226969D01*
X1591917D01*
G01X1593183Y227303D02*
X1593475Y227594D01*
X1593725Y227761D01*
X1594058Y227844D01*
X1594350Y227761D01*
X1594558Y227594D01*
X1594725Y227344D01*
X1594767Y227053D01*
X1594725Y226803D01*
X1594558Y226553D01*
X1594308Y226344D01*
X1594017Y226261D01*
X1593683Y226344D01*
X1593392Y226594D01*
X1593225Y226969D01*
X1593183Y227386D01*
X1593267Y227928D01*
X1593392Y228219D01*
X1593600Y228511D01*
X1593892Y228719D01*
X1594183Y228761D01*
X1594475Y228678D01*
X1594683Y228469D01*
G01X1596158Y226636D02*
X1596408Y226428D01*
X1596700Y226303D01*
X1597075Y226261D01*
X1597450Y226344D01*
X1597742Y226511D01*
X1597950Y226803D01*
X1597992Y227136D01*
X1597908Y227469D01*
X1597700Y227678D01*
X1597408Y227844D01*
X1597117Y227886D01*
X1596825Y227844D01*
X1596450Y227678D01*
X1596575Y228761D01*
X1597700D01*
G01X1574542Y288767D02*
X1574417Y288517D01*
X1574334Y288225D01*
Y287892D01*
X1574459Y287517D01*
X1574667Y287225D01*
X1574917Y287017D01*
X1575334Y286850D01*
X1575709Y286808D01*
X1576084Y286892D01*
X1576334Y287017D01*
X1576584Y287267D01*
X1576751Y287558D01*
X1576834Y287850D01*
Y288142D01*
X1576751Y288433D01*
X1576626Y288683D01*
X1576459Y288892D01*
G01X1576834Y291450D02*
X1574334D01*
X1576126Y289908D01*
Y291992D01*
G01X1575792Y293258D02*
X1575501Y293550D01*
X1575334Y293800D01*
X1575251Y294133D01*
X1575334Y294425D01*
X1575501Y294633D01*
X1575751Y294800D01*
X1576042Y294842D01*
X1576292Y294800D01*
X1576542Y294633D01*
X1576751Y294383D01*
X1576834Y294092D01*
X1576751Y293758D01*
X1576501Y293467D01*
X1576126Y293300D01*
X1575709Y293258D01*
X1575167Y293342D01*
X1574876Y293467D01*
X1574584Y293675D01*
X1574376Y293967D01*
X1574334Y294258D01*
X1574417Y294550D01*
X1574626Y294758D01*
G01X1574751Y296358D02*
X1574501Y296608D01*
X1574376Y296900D01*
X1574334Y297233D01*
X1574417Y297650D01*
X1574626Y297942D01*
X1574876Y298025D01*
X1575126Y297983D01*
X1575334Y297817D01*
X1575751Y296983D01*
X1576042Y296608D01*
X1576459Y296358D01*
X1576834Y296275D01*
Y298025D01*
G01X1610300Y272166D02*
Y269666D01*
G01X1609342Y272166D02*
X1611258D01*
G01X1612567Y269666D02*
Y272166D01*
X1613567D01*
X1613900Y272041D01*
X1614150Y271749D01*
X1614233Y271416D01*
X1614150Y271083D01*
X1613942Y270833D01*
X1613567Y270708D01*
X1612567D01*
G01X1616500Y269666D02*
Y272166D01*
X1616000Y271666D01*
G01Y269666D02*
X1617000D01*
G01X1618808Y270708D02*
X1619100Y270999D01*
X1619350Y271166D01*
X1619683Y271249D01*
X1619975Y271166D01*
X1620183Y270999D01*
X1620350Y270749D01*
X1620392Y270458D01*
X1620350Y270208D01*
X1620183Y269958D01*
X1619933Y269749D01*
X1619642Y269666D01*
X1619308Y269749D01*
X1619017Y269999D01*
X1618850Y270374D01*
X1618808Y270791D01*
X1618892Y271333D01*
X1619017Y271624D01*
X1619225Y271916D01*
X1619517Y272124D01*
X1619808Y272166D01*
X1620100Y272083D01*
X1620308Y271874D01*
G01X1622617Y269666D02*
X1622700Y270208D01*
X1622825Y270666D01*
X1622992Y271083D01*
X1623200Y271541D01*
X1623533Y272166D01*
X1621867D01*
G01X1605344Y382654D02*
Y385154D01*
X1606928D01*
G01X1606344Y383946D02*
X1605344D01*
G01X1608403Y385154D02*
Y382654D01*
X1610069D01*
G01X1613169D02*
X1611503D01*
Y385154D01*
X1613169D01*
G01X1612503Y383946D02*
X1611503D01*
G01X1614519Y382654D02*
Y385154D01*
X1615353D01*
X1615686Y385029D01*
X1615936Y384862D01*
X1616144Y384612D01*
X1616311Y384321D01*
X1616353Y383904D01*
X1616311Y383487D01*
X1616144Y383196D01*
X1615936Y382946D01*
X1615686Y382779D01*
X1615353Y382654D01*
X1614519D01*
G01X1617744Y384737D02*
X1617994Y384987D01*
X1618286Y385112D01*
X1618619Y385154D01*
X1619036Y385071D01*
X1619328Y384862D01*
X1619411Y384612D01*
X1619369Y384362D01*
X1619203Y384154D01*
X1618369Y383737D01*
X1617994Y383446D01*
X1617744Y383029D01*
X1617661Y382654D01*
X1619411D01*
G01X1620844Y384737D02*
X1621094Y384987D01*
X1621386Y385112D01*
X1621719Y385154D01*
X1622136Y385071D01*
X1622428Y384862D01*
X1622511Y384612D01*
X1622469Y384362D01*
X1622303Y384154D01*
X1621469Y383737D01*
X1621094Y383446D01*
X1620844Y383029D01*
X1620761Y382654D01*
X1622511D01*
G01X1608986Y366054D02*
Y377254D01*
X1617786D01*
Y366054D01*
X1608986D01*
G01X1581842Y491106D02*
X1581509Y491148D01*
X1581217Y491314D01*
X1580967Y491564D01*
X1580800Y491856D01*
X1580717Y492189D01*
Y492523D01*
X1580800Y492856D01*
X1580967Y493148D01*
X1581217Y493398D01*
X1581509Y493564D01*
X1581842Y493606D01*
X1582175Y493564D01*
X1582467Y493398D01*
X1582717Y493148D01*
X1582884Y492856D01*
X1582967Y492523D01*
Y492189D01*
X1582884Y491856D01*
X1582717Y491564D01*
X1582467Y491314D01*
X1582175Y491148D01*
X1581842Y491106D01*
G01X1582175Y491773D02*
X1582675Y491106D01*
G01X1584150Y493189D02*
X1584400Y493439D01*
X1584692Y493564D01*
X1585025Y493606D01*
X1585442Y493523D01*
X1585734Y493314D01*
X1585817Y493064D01*
X1585775Y492814D01*
X1585609Y492606D01*
X1584775Y492189D01*
X1584400Y491898D01*
X1584150Y491481D01*
X1584067Y491106D01*
X1585817D01*
G01X1588042D02*
X1588334Y491148D01*
X1588667Y491273D01*
X1588875Y491481D01*
X1588959Y491773D01*
X1588875Y492064D01*
X1588625Y492314D01*
X1588250Y492439D01*
X1587834D01*
X1587584Y492523D01*
X1587375Y492731D01*
X1587292Y493023D01*
X1587417Y493314D01*
X1587709Y493523D01*
X1588042Y493606D01*
X1588375Y493523D01*
X1588667Y493314D01*
X1588792Y493023D01*
X1588709Y492731D01*
X1588500Y492523D01*
X1588250Y492439D01*
X1587834D01*
X1587459Y492314D01*
X1587209Y492064D01*
X1587125Y491773D01*
X1587209Y491481D01*
X1587417Y491273D01*
X1587750Y491148D01*
X1588042Y491106D01*
G01X1591642D02*
Y493606D01*
X1590100Y491814D01*
X1592184D01*
G01X1593492Y496106D02*
Y510106D01*
G01X1580492Y496106D02*
X1593492D01*
G01X1580492Y510106D02*
Y496106D01*
G01X1595951Y491105D02*
X1595618Y491147D01*
X1595326Y491313D01*
X1595076Y491563D01*
X1594909Y491855D01*
X1594826Y492188D01*
Y492522D01*
X1594909Y492855D01*
X1595076Y493147D01*
X1595326Y493397D01*
X1595618Y493563D01*
X1595951Y493605D01*
X1596284Y493563D01*
X1596576Y493397D01*
X1596826Y493147D01*
X1596993Y492855D01*
X1597076Y492522D01*
Y492188D01*
X1596993Y491855D01*
X1596826Y491563D01*
X1596576Y491313D01*
X1596284Y491147D01*
X1595951Y491105D01*
G01X1596284Y491772D02*
X1596784Y491105D01*
G01X1598259Y493188D02*
X1598509Y493438D01*
X1598801Y493563D01*
X1599134Y493605D01*
X1599551Y493522D01*
X1599843Y493313D01*
X1599926Y493063D01*
X1599884Y492813D01*
X1599718Y492605D01*
X1598884Y492188D01*
X1598509Y491897D01*
X1598259Y491480D01*
X1598176Y491105D01*
X1599926D01*
G01X1602651D02*
Y493605D01*
X1601109Y491813D01*
X1603193D01*
G01X1605251Y491105D02*
X1605543Y491147D01*
X1605876Y491272D01*
X1606084Y491480D01*
X1606168Y491772D01*
X1606084Y492063D01*
X1605834Y492313D01*
X1605459Y492438D01*
X1605043D01*
X1604793Y492522D01*
X1604584Y492730D01*
X1604501Y493022D01*
X1604626Y493313D01*
X1604918Y493522D01*
X1605251Y493605D01*
X1605584Y493522D01*
X1605876Y493313D01*
X1606001Y493022D01*
X1605918Y492730D01*
X1605709Y492522D01*
X1605459Y492438D01*
X1605043D01*
X1604668Y492313D01*
X1604418Y492063D01*
X1604334Y491772D01*
X1604418Y491480D01*
X1604626Y491272D01*
X1604959Y491147D01*
X1605251Y491105D01*
G01X1607601Y496105D02*
Y510105D01*
G01X1594601Y496105D02*
X1607601D01*
G01X1594601Y510105D02*
Y496105D01*
G01X1621807Y495017D02*
X1619307D01*
Y496058D01*
X1619432Y496392D01*
X1619599Y496600D01*
X1619932Y496683D01*
X1620265Y496600D01*
X1620474Y496350D01*
X1620599Y496058D01*
Y495017D01*
G01Y496058D02*
X1621807Y496683D01*
G01X1621307Y498033D02*
X1621599Y498283D01*
X1621765Y498617D01*
X1621807Y498992D01*
X1621765Y499325D01*
X1621557Y499658D01*
X1621307Y499867D01*
X1621057Y499908D01*
X1620765Y499825D01*
X1620557Y499533D01*
X1620474Y499242D01*
Y498867D01*
G01Y499242D02*
X1620349Y499492D01*
X1620140Y499700D01*
X1619890Y499783D01*
X1619640Y499700D01*
X1619432Y499492D01*
X1619307Y499117D01*
X1619349Y498742D01*
X1619515Y498367D01*
G01X1621307Y501133D02*
X1621599Y501383D01*
X1621765Y501717D01*
X1621807Y502092D01*
X1621765Y502425D01*
X1621557Y502758D01*
X1621307Y502967D01*
X1621057Y503008D01*
X1620765Y502925D01*
X1620557Y502633D01*
X1620474Y502342D01*
Y501967D01*
G01Y502342D02*
X1620349Y502592D01*
X1620140Y502800D01*
X1619890Y502883D01*
X1619640Y502800D01*
X1619432Y502592D01*
X1619307Y502217D01*
X1619349Y501842D01*
X1619515Y501467D01*
G01X1621432Y504233D02*
X1621640Y504483D01*
X1621765Y504775D01*
X1621807Y505150D01*
X1621724Y505525D01*
X1621557Y505817D01*
X1621265Y506025D01*
X1620932Y506067D01*
X1620599Y505983D01*
X1620390Y505775D01*
X1620224Y505483D01*
X1620182Y505192D01*
X1620224Y504900D01*
X1620390Y504525D01*
X1619307Y504650D01*
Y505775D01*
G01X1594012Y520918D02*
Y523418D01*
X1595053D01*
X1595387Y523293D01*
X1595595Y523126D01*
X1595678Y522793D01*
X1595595Y522460D01*
X1595345Y522251D01*
X1595053Y522126D01*
X1594012D01*
G01X1595053D02*
X1595678Y520918D01*
G01X1597028Y521293D02*
X1597278Y521085D01*
X1597570Y520960D01*
X1597945Y520918D01*
X1598320Y521001D01*
X1598612Y521168D01*
X1598820Y521460D01*
X1598862Y521793D01*
X1598778Y522126D01*
X1598570Y522335D01*
X1598278Y522501D01*
X1597987Y522543D01*
X1597695Y522501D01*
X1597320Y522335D01*
X1597445Y523418D01*
X1598570D01*
G01X1601545Y520918D02*
Y523418D01*
X1600003Y521626D01*
X1602087D01*
G01X1604145Y520918D02*
Y523418D01*
X1603645Y522918D01*
G01Y520918D02*
X1604645D01*
G01X1602695Y511418D02*
Y515418D01*
X1595295D01*
G01X1579875Y520887D02*
Y523387D01*
X1580916D01*
X1581250Y523262D01*
X1581458Y523095D01*
X1581541Y522762D01*
X1581458Y522429D01*
X1581208Y522220D01*
X1580916Y522095D01*
X1579875D01*
G01X1580916D02*
X1581541Y520887D01*
G01X1582891Y521262D02*
X1583141Y521054D01*
X1583433Y520929D01*
X1583808Y520887D01*
X1584183Y520970D01*
X1584475Y521137D01*
X1584683Y521429D01*
X1584725Y521762D01*
X1584641Y522095D01*
X1584433Y522304D01*
X1584141Y522470D01*
X1583850Y522512D01*
X1583558Y522470D01*
X1583183Y522304D01*
X1583308Y523387D01*
X1584433D01*
G01X1587408Y520887D02*
Y523387D01*
X1585866Y521595D01*
X1587950D01*
G01X1590008Y523387D02*
X1589675Y523304D01*
X1589425Y523095D01*
X1589258Y522845D01*
X1589133Y522512D01*
X1589091Y522137D01*
X1589133Y521762D01*
X1589258Y521429D01*
X1589425Y521179D01*
X1589675Y520970D01*
X1590008Y520887D01*
X1590341Y520970D01*
X1590591Y521179D01*
X1590758Y521429D01*
X1590883Y521762D01*
X1590925Y522137D01*
X1590883Y522512D01*
X1590758Y522845D01*
X1590591Y523095D01*
X1590341Y523304D01*
X1590008Y523387D01*
G01X1588558Y511387D02*
Y515387D01*
X1581158D01*
G01X1593492Y510106D02*
X1580492D01*
G01X1607601Y510105D02*
X1594601D01*
G01X1577590Y620288D02*
Y622788D01*
X1578631D01*
X1578965Y622663D01*
X1579173Y622496D01*
X1579256Y622163D01*
X1579173Y621830D01*
X1578923Y621621D01*
X1578631Y621496D01*
X1577590D01*
G01X1578631D02*
X1579256Y620288D01*
G01X1580606Y620663D02*
X1580856Y620455D01*
X1581148Y620330D01*
X1581523Y620288D01*
X1581898Y620371D01*
X1582190Y620538D01*
X1582398Y620830D01*
X1582440Y621163D01*
X1582356Y621496D01*
X1582148Y621705D01*
X1581856Y621871D01*
X1581565Y621913D01*
X1581273Y621871D01*
X1580898Y621705D01*
X1581023Y622788D01*
X1582148D01*
G01X1583915Y620580D02*
X1584206Y620371D01*
X1584540Y620288D01*
X1584873Y620371D01*
X1585165Y620621D01*
X1585373Y620996D01*
X1585456Y621371D01*
Y621830D01*
X1585373Y622205D01*
X1585165Y622538D01*
X1584915Y622705D01*
X1584623Y622788D01*
X1584290Y622705D01*
X1584040Y622538D01*
X1583873Y622288D01*
X1583790Y621955D01*
X1583873Y621663D01*
X1584081Y621371D01*
X1584331Y621205D01*
X1584623Y621163D01*
X1584956Y621246D01*
X1585206Y621455D01*
X1585456Y621830D01*
G01X1587640Y620288D02*
X1587723Y620830D01*
X1587848Y621288D01*
X1588015Y621705D01*
X1588223Y622163D01*
X1588556Y622788D01*
X1586890D01*
G01X1598894Y607080D02*
X1596394D01*
Y608121D01*
X1596519Y608455D01*
X1596686Y608663D01*
X1597019Y608746D01*
X1597352Y608663D01*
X1597561Y608413D01*
X1597686Y608121D01*
Y607080D01*
G01Y608121D02*
X1598894Y608746D01*
G01X1597852Y610221D02*
X1597561Y610513D01*
X1597394Y610763D01*
X1597311Y611096D01*
X1597394Y611388D01*
X1597561Y611596D01*
X1597811Y611763D01*
X1598102Y611805D01*
X1598352Y611763D01*
X1598602Y611596D01*
X1598811Y611346D01*
X1598894Y611055D01*
X1598811Y610721D01*
X1598561Y610430D01*
X1598186Y610263D01*
X1597769Y610221D01*
X1597227Y610305D01*
X1596936Y610430D01*
X1596644Y610638D01*
X1596436Y610930D01*
X1596394Y611221D01*
X1596477Y611513D01*
X1596686Y611721D01*
G01X1596394Y614113D02*
X1596477Y613780D01*
X1596686Y613530D01*
X1596936Y613363D01*
X1597269Y613238D01*
X1597644Y613196D01*
X1598019Y613238D01*
X1598352Y613363D01*
X1598602Y613530D01*
X1598811Y613780D01*
X1598894Y614113D01*
X1598811Y614446D01*
X1598602Y614696D01*
X1598352Y614863D01*
X1598019Y614988D01*
X1597644Y615030D01*
X1597269Y614988D01*
X1596936Y614863D01*
X1596686Y614696D01*
X1596477Y614446D01*
X1596394Y614113D01*
G01X1598894Y617713D02*
X1596394D01*
X1598186Y616171D01*
Y618255D01*
G01X1572925Y629117D02*
X1576925D01*
Y636517D01*
G01X1591165Y623871D02*
Y626371D01*
X1592206D01*
X1592540Y626246D01*
X1592748Y626079D01*
X1592831Y625746D01*
X1592748Y625413D01*
X1592498Y625204D01*
X1592206Y625079D01*
X1591165D01*
G01X1592206D02*
X1592831Y623871D01*
G01X1594306Y624913D02*
X1594598Y625204D01*
X1594848Y625371D01*
X1595181Y625454D01*
X1595473Y625371D01*
X1595681Y625204D01*
X1595848Y624954D01*
X1595890Y624663D01*
X1595848Y624413D01*
X1595681Y624163D01*
X1595431Y623954D01*
X1595140Y623871D01*
X1594806Y623954D01*
X1594515Y624204D01*
X1594348Y624579D01*
X1594306Y624996D01*
X1594390Y625538D01*
X1594515Y625829D01*
X1594723Y626121D01*
X1595015Y626329D01*
X1595306Y626371D01*
X1595598Y626288D01*
X1595806Y626079D01*
G01X1598198Y626371D02*
X1597865Y626288D01*
X1597615Y626079D01*
X1597448Y625829D01*
X1597323Y625496D01*
X1597281Y625121D01*
X1597323Y624746D01*
X1597448Y624413D01*
X1597615Y624163D01*
X1597865Y623954D01*
X1598198Y623871D01*
X1598531Y623954D01*
X1598781Y624163D01*
X1598948Y624413D01*
X1599073Y624746D01*
X1599115Y625121D01*
X1599073Y625496D01*
X1598948Y625829D01*
X1598781Y626079D01*
X1598531Y626288D01*
X1598198Y626371D01*
G01X1600506Y624913D02*
X1600798Y625204D01*
X1601048Y625371D01*
X1601381Y625454D01*
X1601673Y625371D01*
X1601881Y625204D01*
X1602048Y624954D01*
X1602090Y624663D01*
X1602048Y624413D01*
X1601881Y624163D01*
X1601631Y623954D01*
X1601340Y623871D01*
X1601006Y623954D01*
X1600715Y624204D01*
X1600548Y624579D01*
X1600506Y624996D01*
X1600590Y625538D01*
X1600715Y625829D01*
X1600923Y626121D01*
X1601215Y626329D01*
X1601506Y626371D01*
X1601798Y626288D01*
X1602006Y626079D01*
G01X1594194Y607080D02*
X1591694D01*
Y608121D01*
X1591819Y608455D01*
X1591986Y608663D01*
X1592319Y608746D01*
X1592652Y608663D01*
X1592861Y608413D01*
X1592986Y608121D01*
Y607080D01*
G01Y608121D02*
X1594194Y608746D01*
G01X1593152Y610221D02*
X1592861Y610513D01*
X1592694Y610763D01*
X1592611Y611096D01*
X1592694Y611388D01*
X1592861Y611596D01*
X1593111Y611763D01*
X1593402Y611805D01*
X1593652Y611763D01*
X1593902Y611596D01*
X1594111Y611346D01*
X1594194Y611055D01*
X1594111Y610721D01*
X1593861Y610430D01*
X1593486Y610263D01*
X1593069Y610221D01*
X1592527Y610305D01*
X1592236Y610430D01*
X1591944Y610638D01*
X1591736Y610930D01*
X1591694Y611221D01*
X1591777Y611513D01*
X1591986Y611721D01*
G01X1591694Y614113D02*
X1591777Y613780D01*
X1591986Y613530D01*
X1592236Y613363D01*
X1592569Y613238D01*
X1592944Y613196D01*
X1593319Y613238D01*
X1593652Y613363D01*
X1593902Y613530D01*
X1594111Y613780D01*
X1594194Y614113D01*
X1594111Y614446D01*
X1593902Y614696D01*
X1593652Y614863D01*
X1593319Y614988D01*
X1592944Y615030D01*
X1592569Y614988D01*
X1592236Y614863D01*
X1591986Y614696D01*
X1591777Y614446D01*
X1591694Y614113D01*
G01X1594194Y617130D02*
X1593652Y617213D01*
X1593194Y617338D01*
X1592777Y617505D01*
X1592319Y617713D01*
X1591694Y618046D01*
Y616380D01*
G01X1591056Y620288D02*
Y622788D01*
X1591890D01*
X1592223Y622663D01*
X1592473Y622496D01*
X1592681Y622246D01*
X1592848Y621955D01*
X1592890Y621538D01*
X1592848Y621121D01*
X1592681Y620830D01*
X1592473Y620580D01*
X1592223Y620413D01*
X1591890Y620288D01*
X1591056D01*
G01X1594281Y622371D02*
X1594531Y622621D01*
X1594823Y622746D01*
X1595156Y622788D01*
X1595573Y622705D01*
X1595865Y622496D01*
X1595948Y622246D01*
X1595906Y621996D01*
X1595740Y621788D01*
X1594906Y621371D01*
X1594531Y621080D01*
X1594281Y620663D01*
X1594198Y620288D01*
X1595948D01*
G01X1598173Y622788D02*
X1597840Y622705D01*
X1597590Y622496D01*
X1597423Y622246D01*
X1597298Y621913D01*
X1597256Y621538D01*
X1597298Y621163D01*
X1597423Y620830D01*
X1597590Y620580D01*
X1597840Y620371D01*
X1598173Y620288D01*
X1598506Y620371D01*
X1598756Y620580D01*
X1598923Y620830D01*
X1599048Y621163D01*
X1599090Y621538D01*
X1599048Y621913D01*
X1598923Y622246D01*
X1598756Y622496D01*
X1598506Y622705D01*
X1598173Y622788D01*
G01X1579925Y646417D02*
Y639417D01*
G01X1619267Y625292D02*
X1619017Y625417D01*
X1618725Y625500D01*
X1618392D01*
X1618017Y625375D01*
X1617725Y625167D01*
X1617517Y624917D01*
X1617350Y624500D01*
X1617308Y624125D01*
X1617392Y623750D01*
X1617517Y623500D01*
X1617767Y623250D01*
X1618058Y623083D01*
X1618350Y623000D01*
X1618642D01*
X1618933Y623083D01*
X1619183Y623208D01*
X1619392Y623375D01*
G01X1620533Y623500D02*
X1620783Y623208D01*
X1621117Y623042D01*
X1621492Y623000D01*
X1621825Y623042D01*
X1622158Y623250D01*
X1622367Y623500D01*
X1622408Y623750D01*
X1622325Y624042D01*
X1622033Y624250D01*
X1621742Y624333D01*
X1621367D01*
G01X1621742D02*
X1621992Y624458D01*
X1622200Y624667D01*
X1622283Y624917D01*
X1622200Y625167D01*
X1621992Y625375D01*
X1621617Y625500D01*
X1621242Y625458D01*
X1620867Y625292D01*
G01X1624550Y623000D02*
Y625500D01*
X1624050Y625000D01*
G01Y623000D02*
X1625050D01*
G01X1626858Y625083D02*
X1627108Y625333D01*
X1627400Y625458D01*
X1627733Y625500D01*
X1628150Y625417D01*
X1628442Y625208D01*
X1628525Y624958D01*
X1628483Y624708D01*
X1628317Y624500D01*
X1627483Y624083D01*
X1627108Y623792D01*
X1626858Y623375D01*
X1626775Y623000D01*
X1628525D01*
G01X1619267Y629292D02*
X1619017Y629417D01*
X1618725Y629500D01*
X1618392D01*
X1618017Y629375D01*
X1617725Y629167D01*
X1617517Y628917D01*
X1617350Y628500D01*
X1617308Y628125D01*
X1617392Y627750D01*
X1617517Y627500D01*
X1617767Y627250D01*
X1618058Y627083D01*
X1618350Y627000D01*
X1618642D01*
X1618933Y627083D01*
X1619183Y627208D01*
X1619392Y627375D01*
G01X1620533Y627500D02*
X1620783Y627208D01*
X1621117Y627042D01*
X1621492Y627000D01*
X1621825Y627042D01*
X1622158Y627250D01*
X1622367Y627500D01*
X1622408Y627750D01*
X1622325Y628042D01*
X1622033Y628250D01*
X1621742Y628333D01*
X1621367D01*
G01X1621742D02*
X1621992Y628458D01*
X1622200Y628667D01*
X1622283Y628917D01*
X1622200Y629167D01*
X1621992Y629375D01*
X1621617Y629500D01*
X1621242Y629458D01*
X1620867Y629292D01*
G01X1624550Y627000D02*
Y629500D01*
X1624050Y629000D01*
G01Y627000D02*
X1625050D01*
G01X1627650D02*
Y629500D01*
X1627150Y629000D01*
G01Y627000D02*
X1628150D01*
G01X1579340Y626680D02*
X1579090Y626805D01*
X1578798Y626888D01*
X1578465D01*
X1578090Y626763D01*
X1577798Y626555D01*
X1577590Y626305D01*
X1577423Y625888D01*
X1577381Y625513D01*
X1577465Y625138D01*
X1577590Y624888D01*
X1577840Y624638D01*
X1578131Y624471D01*
X1578423Y624388D01*
X1578715D01*
X1579006Y624471D01*
X1579256Y624596D01*
X1579465Y624763D01*
G01X1580606Y624888D02*
X1580856Y624596D01*
X1581190Y624430D01*
X1581565Y624388D01*
X1581898Y624430D01*
X1582231Y624638D01*
X1582440Y624888D01*
X1582481Y625138D01*
X1582398Y625430D01*
X1582106Y625638D01*
X1581815Y625721D01*
X1581440D01*
G01X1581815D02*
X1582065Y625846D01*
X1582273Y626055D01*
X1582356Y626305D01*
X1582273Y626555D01*
X1582065Y626763D01*
X1581690Y626888D01*
X1581315Y626846D01*
X1580940Y626680D01*
G01X1584623Y626888D02*
X1584290Y626805D01*
X1584040Y626596D01*
X1583873Y626346D01*
X1583748Y626013D01*
X1583706Y625638D01*
X1583748Y625263D01*
X1583873Y624930D01*
X1584040Y624680D01*
X1584290Y624471D01*
X1584623Y624388D01*
X1584956Y624471D01*
X1585206Y624680D01*
X1585373Y624930D01*
X1585498Y625263D01*
X1585540Y625638D01*
X1585498Y626013D01*
X1585373Y626346D01*
X1585206Y626596D01*
X1584956Y626805D01*
X1584623Y626888D01*
G01X1587723Y624388D02*
X1588015Y624430D01*
X1588348Y624555D01*
X1588556Y624763D01*
X1588640Y625055D01*
X1588556Y625346D01*
X1588306Y625596D01*
X1587931Y625721D01*
X1587515D01*
X1587265Y625805D01*
X1587056Y626013D01*
X1586973Y626305D01*
X1587098Y626596D01*
X1587390Y626805D01*
X1587723Y626888D01*
X1588056Y626805D01*
X1588348Y626596D01*
X1588473Y626305D01*
X1588390Y626013D01*
X1588181Y625805D01*
X1587931Y625721D01*
X1587515D01*
X1587140Y625596D01*
X1586890Y625346D01*
X1586806Y625055D01*
X1586890Y624763D01*
X1587098Y624555D01*
X1587431Y624430D01*
X1587723Y624388D01*
G01X1587442Y674917D02*
Y677417D01*
X1588483D01*
X1588817Y677292D01*
X1589025Y677125D01*
X1589108Y676792D01*
X1589025Y676459D01*
X1588775Y676250D01*
X1588483Y676125D01*
X1587442D01*
G01X1588483D02*
X1589108Y674917D01*
G01X1590583Y675959D02*
X1590875Y676250D01*
X1591125Y676417D01*
X1591458Y676500D01*
X1591750Y676417D01*
X1591958Y676250D01*
X1592125Y676000D01*
X1592167Y675709D01*
X1592125Y675459D01*
X1591958Y675209D01*
X1591708Y675000D01*
X1591417Y674917D01*
X1591083Y675000D01*
X1590792Y675250D01*
X1590625Y675625D01*
X1590583Y676042D01*
X1590667Y676584D01*
X1590792Y676875D01*
X1591000Y677167D01*
X1591292Y677375D01*
X1591583Y677417D01*
X1591875Y677334D01*
X1592083Y677125D01*
G01X1594475Y677417D02*
X1594142Y677334D01*
X1593892Y677125D01*
X1593725Y676875D01*
X1593600Y676542D01*
X1593558Y676167D01*
X1593600Y675792D01*
X1593725Y675459D01*
X1593892Y675209D01*
X1594142Y675000D01*
X1594475Y674917D01*
X1594808Y675000D01*
X1595058Y675209D01*
X1595225Y675459D01*
X1595350Y675792D01*
X1595392Y676167D01*
X1595350Y676542D01*
X1595225Y676875D01*
X1595058Y677125D01*
X1594808Y677334D01*
X1594475Y677417D01*
G01X1596658Y675292D02*
X1596908Y675084D01*
X1597200Y674959D01*
X1597575Y674917D01*
X1597950Y675000D01*
X1598242Y675167D01*
X1598450Y675459D01*
X1598492Y675792D01*
X1598408Y676125D01*
X1598200Y676334D01*
X1597908Y676500D01*
X1597617Y676542D01*
X1597325Y676500D01*
X1596950Y676334D01*
X1597075Y677417D01*
X1598200D01*
G01X1585625Y674417D02*
Y678417D01*
X1578225D01*
G01X1608905Y695209D02*
X1608655Y695334D01*
X1608363Y695417D01*
X1608030D01*
X1607655Y695292D01*
X1607363Y695084D01*
X1607155Y694834D01*
X1606988Y694417D01*
X1606946Y694042D01*
X1607030Y693667D01*
X1607155Y693417D01*
X1607405Y693167D01*
X1607696Y693000D01*
X1607988Y692917D01*
X1608280D01*
X1608571Y693000D01*
X1608821Y693125D01*
X1609030Y693292D01*
G01X1610171Y693417D02*
X1610421Y693125D01*
X1610755Y692959D01*
X1611130Y692917D01*
X1611463Y692959D01*
X1611796Y693167D01*
X1612005Y693417D01*
X1612046Y693667D01*
X1611963Y693959D01*
X1611671Y694167D01*
X1611380Y694250D01*
X1611005D01*
G01X1611380D02*
X1611630Y694375D01*
X1611838Y694584D01*
X1611921Y694834D01*
X1611838Y695084D01*
X1611630Y695292D01*
X1611255Y695417D01*
X1610880Y695375D01*
X1610505Y695209D01*
G01X1614188Y692917D02*
Y695417D01*
X1613688Y694917D01*
G01Y692917D02*
X1614688D01*
G01X1616371Y693292D02*
X1616621Y693084D01*
X1616913Y692959D01*
X1617288Y692917D01*
X1617663Y693000D01*
X1617955Y693167D01*
X1618163Y693459D01*
X1618205Y693792D01*
X1618121Y694125D01*
X1617913Y694334D01*
X1617621Y694500D01*
X1617330Y694542D01*
X1617038Y694500D01*
X1616663Y694334D01*
X1616788Y695417D01*
X1617913D01*
G01X1589192Y681309D02*
X1588942Y681434D01*
X1588650Y681517D01*
X1588317D01*
X1587942Y681392D01*
X1587650Y681184D01*
X1587442Y680934D01*
X1587275Y680517D01*
X1587233Y680142D01*
X1587317Y679767D01*
X1587442Y679517D01*
X1587692Y679267D01*
X1587983Y679100D01*
X1588275Y679017D01*
X1588567D01*
X1588858Y679100D01*
X1589108Y679225D01*
X1589317Y679392D01*
G01X1590458Y679517D02*
X1590708Y679225D01*
X1591042Y679059D01*
X1591417Y679017D01*
X1591750Y679059D01*
X1592083Y679267D01*
X1592292Y679517D01*
X1592333Y679767D01*
X1592250Y680059D01*
X1591958Y680267D01*
X1591667Y680350D01*
X1591292D01*
G01X1591667D02*
X1591917Y680475D01*
X1592125Y680684D01*
X1592208Y680934D01*
X1592125Y681184D01*
X1591917Y681392D01*
X1591542Y681517D01*
X1591167Y681475D01*
X1590792Y681309D01*
G01X1594475Y681517D02*
X1594142Y681434D01*
X1593892Y681225D01*
X1593725Y680975D01*
X1593600Y680642D01*
X1593558Y680267D01*
X1593600Y679892D01*
X1593725Y679559D01*
X1593892Y679309D01*
X1594142Y679100D01*
X1594475Y679017D01*
X1594808Y679100D01*
X1595058Y679309D01*
X1595225Y679559D01*
X1595350Y679892D01*
X1595392Y680267D01*
X1595350Y680642D01*
X1595225Y680975D01*
X1595058Y681225D01*
X1594808Y681434D01*
X1594475Y681517D01*
G01X1596867Y679309D02*
X1597158Y679100D01*
X1597492Y679017D01*
X1597825Y679100D01*
X1598117Y679350D01*
X1598325Y679725D01*
X1598408Y680100D01*
Y680559D01*
X1598325Y680934D01*
X1598117Y681267D01*
X1597867Y681434D01*
X1597575Y681517D01*
X1597242Y681434D01*
X1596992Y681267D01*
X1596825Y681017D01*
X1596742Y680684D01*
X1596825Y680392D01*
X1597033Y680100D01*
X1597283Y679934D01*
X1597575Y679892D01*
X1597908Y679975D01*
X1598158Y680184D01*
X1598408Y680559D01*
G01X1607155Y697017D02*
Y699517D01*
X1608196D01*
X1608530Y699392D01*
X1608738Y699225D01*
X1608821Y698892D01*
X1608738Y698559D01*
X1608488Y698350D01*
X1608196Y698225D01*
X1607155D01*
G01X1608196D02*
X1608821Y697017D01*
G01X1610296Y698059D02*
X1610588Y698350D01*
X1610838Y698517D01*
X1611171Y698600D01*
X1611463Y698517D01*
X1611671Y698350D01*
X1611838Y698100D01*
X1611880Y697809D01*
X1611838Y697559D01*
X1611671Y697309D01*
X1611421Y697100D01*
X1611130Y697017D01*
X1610796Y697100D01*
X1610505Y697350D01*
X1610338Y697725D01*
X1610296Y698142D01*
X1610380Y698684D01*
X1610505Y698975D01*
X1610713Y699267D01*
X1611005Y699475D01*
X1611296Y699517D01*
X1611588Y699434D01*
X1611796Y699225D01*
G01X1614188Y697017D02*
Y699517D01*
X1613688Y699017D01*
G01Y697017D02*
X1614688D01*
G01X1616371Y697517D02*
X1616621Y697225D01*
X1616955Y697059D01*
X1617330Y697017D01*
X1617663Y697059D01*
X1617996Y697267D01*
X1618205Y697517D01*
X1618246Y697767D01*
X1618163Y698059D01*
X1617871Y698267D01*
X1617580Y698350D01*
X1617205D01*
G01X1617580D02*
X1617830Y698475D01*
X1618038Y698684D01*
X1618121Y698934D01*
X1618038Y699184D01*
X1617830Y699392D01*
X1617455Y699517D01*
X1617080Y699475D01*
X1616705Y699309D01*
G01X1574208Y741267D02*
X1574083Y741017D01*
X1574000Y740725D01*
Y740392D01*
X1574125Y740017D01*
X1574333Y739725D01*
X1574583Y739517D01*
X1575000Y739350D01*
X1575375Y739308D01*
X1575750Y739392D01*
X1576000Y739517D01*
X1576250Y739767D01*
X1576417Y740058D01*
X1576500Y740350D01*
Y740642D01*
X1576417Y740933D01*
X1576292Y741183D01*
X1576125Y741392D01*
G01X1576000Y742533D02*
X1576292Y742783D01*
X1576458Y743117D01*
X1576500Y743492D01*
X1576458Y743825D01*
X1576250Y744158D01*
X1576000Y744367D01*
X1575750Y744408D01*
X1575458Y744325D01*
X1575250Y744033D01*
X1575167Y743742D01*
Y743367D01*
G01Y743742D02*
X1575042Y743992D01*
X1574833Y744200D01*
X1574583Y744283D01*
X1574333Y744200D01*
X1574125Y743992D01*
X1574000Y743617D01*
X1574042Y743242D01*
X1574208Y742867D01*
G01X1574000Y746550D02*
X1574083Y746217D01*
X1574292Y745967D01*
X1574542Y745800D01*
X1574875Y745675D01*
X1575250Y745633D01*
X1575625Y745675D01*
X1575958Y745800D01*
X1576208Y745967D01*
X1576417Y746217D01*
X1576500Y746550D01*
X1576417Y746883D01*
X1576208Y747133D01*
X1575958Y747300D01*
X1575625Y747425D01*
X1575250Y747467D01*
X1574875Y747425D01*
X1574542Y747300D01*
X1574292Y747133D01*
X1574083Y746883D01*
X1574000Y746550D01*
G01X1575458Y748858D02*
X1575167Y749150D01*
X1575000Y749400D01*
X1574917Y749733D01*
X1575000Y750025D01*
X1575167Y750233D01*
X1575417Y750400D01*
X1575708Y750442D01*
X1575958Y750400D01*
X1576208Y750233D01*
X1576417Y749983D01*
X1576500Y749692D01*
X1576417Y749358D01*
X1576167Y749067D01*
X1575792Y748900D01*
X1575375Y748858D01*
X1574833Y748942D01*
X1574542Y749067D01*
X1574250Y749275D01*
X1574042Y749567D01*
X1574000Y749858D01*
X1574083Y750150D01*
X1574292Y750358D01*
G01X1575350Y712500D02*
X1575017Y712542D01*
X1574725Y712708D01*
X1574475Y712958D01*
X1574308Y713250D01*
X1574225Y713583D01*
Y713917D01*
X1574308Y714250D01*
X1574475Y714542D01*
X1574725Y714792D01*
X1575017Y714958D01*
X1575350Y715000D01*
X1575683Y714958D01*
X1575975Y714792D01*
X1576225Y714542D01*
X1576392Y714250D01*
X1576475Y713917D01*
Y713583D01*
X1576392Y713250D01*
X1576225Y712958D01*
X1575975Y712708D01*
X1575683Y712542D01*
X1575350Y712500D01*
G01X1575683Y713167D02*
X1576183Y712500D01*
G01X1578450D02*
Y715000D01*
X1577950Y714500D01*
G01Y712500D02*
X1578950D01*
G01X1580758Y714583D02*
X1581008Y714833D01*
X1581300Y714958D01*
X1581633Y715000D01*
X1582050Y714917D01*
X1582342Y714708D01*
X1582425Y714458D01*
X1582383Y714208D01*
X1582217Y714000D01*
X1581383Y713583D01*
X1581008Y713292D01*
X1580758Y712875D01*
X1580675Y712500D01*
X1582425D01*
G01X1583858Y714583D02*
X1584108Y714833D01*
X1584400Y714958D01*
X1584733Y715000D01*
X1585150Y714917D01*
X1585442Y714708D01*
X1585525Y714458D01*
X1585483Y714208D01*
X1585317Y714000D01*
X1584483Y713583D01*
X1584108Y713292D01*
X1583858Y712875D01*
X1583775Y712500D01*
X1585525D01*
G01X1608800Y724166D02*
Y721666D01*
G01X1607842Y724166D02*
X1609758D01*
G01X1611067Y721666D02*
Y724166D01*
X1612067D01*
X1612400Y724041D01*
X1612650Y723749D01*
X1612733Y723416D01*
X1612650Y723083D01*
X1612442Y722833D01*
X1612067Y722708D01*
X1611067D01*
G01X1615000Y721666D02*
Y724166D01*
X1614500Y723666D01*
G01Y721666D02*
X1615500D01*
G01X1618100Y724166D02*
X1617767Y724083D01*
X1617517Y723874D01*
X1617350Y723624D01*
X1617225Y723291D01*
X1617183Y722916D01*
X1617225Y722541D01*
X1617350Y722208D01*
X1617517Y721958D01*
X1617767Y721749D01*
X1618100Y721666D01*
X1618433Y721749D01*
X1618683Y721958D01*
X1618850Y722208D01*
X1618975Y722541D01*
X1619017Y722916D01*
X1618975Y723291D01*
X1618850Y723624D01*
X1618683Y723874D01*
X1618433Y724083D01*
X1618100Y724166D01*
G01X1621117Y721666D02*
X1621200Y722208D01*
X1621325Y722666D01*
X1621492Y723083D01*
X1621700Y723541D01*
X1622033Y724166D01*
X1620367D01*
G01X1605655Y708417D02*
Y710917D01*
X1606696D01*
X1607030Y710792D01*
X1607238Y710625D01*
X1607321Y710292D01*
X1607238Y709959D01*
X1606988Y709750D01*
X1606696Y709625D01*
X1605655D01*
G01X1606696D02*
X1607321Y708417D01*
G01X1608796Y709459D02*
X1609088Y709750D01*
X1609338Y709917D01*
X1609671Y710000D01*
X1609963Y709917D01*
X1610171Y709750D01*
X1610338Y709500D01*
X1610380Y709209D01*
X1610338Y708959D01*
X1610171Y708709D01*
X1609921Y708500D01*
X1609630Y708417D01*
X1609296Y708500D01*
X1609005Y708750D01*
X1608838Y709125D01*
X1608796Y709542D01*
X1608880Y710084D01*
X1609005Y710375D01*
X1609213Y710667D01*
X1609505Y710875D01*
X1609796Y710917D01*
X1610088Y710834D01*
X1610296Y710625D01*
G01X1612688Y708417D02*
Y710917D01*
X1612188Y710417D01*
G01Y708417D02*
X1613188D01*
G01X1615705D02*
X1615788Y708959D01*
X1615913Y709417D01*
X1616080Y709834D01*
X1616288Y710292D01*
X1616621Y710917D01*
X1614955D01*
G01X1614567Y777813D02*
Y780313D01*
G01X1616317D02*
Y777813D01*
G01Y779063D02*
X1614567D01*
G01X1617625Y777813D02*
Y780313D01*
X1618459D01*
X1618792Y780188D01*
X1619042Y780021D01*
X1619250Y779771D01*
X1619417Y779480D01*
X1619459Y779063D01*
X1619417Y778646D01*
X1619250Y778355D01*
X1619042Y778105D01*
X1618792Y777938D01*
X1618459Y777813D01*
X1617625D01*
G01X1620725D02*
Y780313D01*
X1621559D01*
X1621892Y780188D01*
X1622142Y780021D01*
X1622350Y779771D01*
X1622517Y779480D01*
X1622559Y779063D01*
X1622517Y778646D01*
X1622350Y778355D01*
X1622142Y778105D01*
X1621892Y777938D01*
X1621559Y777813D01*
X1620725D01*
G01X1623867Y778146D02*
X1624200Y777938D01*
X1624575Y777813D01*
X1624909D01*
X1625242Y777938D01*
X1625492Y778146D01*
X1625617Y778438D01*
X1625534Y778730D01*
X1625325Y778980D01*
X1624950Y779146D01*
X1624450Y779230D01*
X1624159Y779396D01*
X1624034Y779688D01*
X1624117Y779980D01*
X1624325Y780188D01*
X1624617Y780313D01*
X1624909D01*
X1625200Y780230D01*
X1625450Y780021D01*
G01X1626800Y777813D02*
X1627842Y780313D01*
X1628884Y777813D01*
G01X1628509Y778688D02*
X1627175D01*
G01X1630067Y778146D02*
X1630400Y777938D01*
X1630775Y777813D01*
X1631109D01*
X1631442Y777938D01*
X1631692Y778146D01*
X1631817Y778438D01*
X1631734Y778730D01*
X1631525Y778980D01*
X1631150Y779146D01*
X1630650Y779230D01*
X1630359Y779396D01*
X1630234Y779688D01*
X1630317Y779980D01*
X1630525Y780188D01*
X1630817Y780313D01*
X1631109D01*
X1631400Y780230D01*
X1631650Y780021D01*
G01X1633250Y779896D02*
X1633500Y780146D01*
X1633792Y780271D01*
X1634125Y780313D01*
X1634542Y780230D01*
X1634834Y780021D01*
X1634917Y779771D01*
X1634875Y779521D01*
X1634709Y779313D01*
X1633875Y778896D01*
X1633500Y778605D01*
X1633250Y778188D01*
X1633167Y777813D01*
X1634917D01*
G01X1637142D02*
Y780313D01*
X1636642Y779813D01*
G01Y777813D02*
X1637642D01*
G01X1598505Y837618D02*
Y840118D01*
X1600089D01*
G01X1599505Y838910D02*
X1598505D01*
G01X1601564Y840118D02*
Y837618D01*
X1603230D01*
G01X1606330D02*
X1604664D01*
Y840118D01*
X1606330D01*
G01X1605664Y838910D02*
X1604664D01*
G01X1607680Y837618D02*
Y840118D01*
X1608514D01*
X1608847Y839993D01*
X1609097Y839826D01*
X1609305Y839576D01*
X1609472Y839285D01*
X1609514Y838868D01*
X1609472Y838451D01*
X1609305Y838160D01*
X1609097Y837910D01*
X1608847Y837743D01*
X1608514Y837618D01*
X1607680D01*
G01X1611697D02*
Y840118D01*
X1611197Y839618D01*
G01Y837618D02*
X1612197D01*
G01X1614797Y840118D02*
X1614464Y840035D01*
X1614214Y839826D01*
X1614047Y839576D01*
X1613922Y839243D01*
X1613880Y838868D01*
X1613922Y838493D01*
X1614047Y838160D01*
X1614214Y837910D01*
X1614464Y837701D01*
X1614797Y837618D01*
X1615130Y837701D01*
X1615380Y837910D01*
X1615547Y838160D01*
X1615672Y838493D01*
X1615714Y838868D01*
X1615672Y839243D01*
X1615547Y839576D01*
X1615380Y839826D01*
X1615130Y840035D01*
X1614797Y840118D01*
G01X1608986Y818809D02*
Y830009D01*
X1617786D01*
Y818809D01*
X1608986D01*
G01X1594088Y972889D02*
Y975389D01*
X1595129D01*
X1595463Y975264D01*
X1595671Y975097D01*
X1595754Y974764D01*
X1595671Y974431D01*
X1595421Y974222D01*
X1595129Y974097D01*
X1594088D01*
G01X1595129D02*
X1595754Y972889D01*
G01X1598521D02*
Y975389D01*
X1596979Y973597D01*
X1599063D01*
G01X1600413Y973181D02*
X1600704Y972972D01*
X1601038Y972889D01*
X1601371Y972972D01*
X1601663Y973222D01*
X1601871Y973597D01*
X1601954Y973972D01*
Y974431D01*
X1601871Y974806D01*
X1601663Y975139D01*
X1601413Y975306D01*
X1601121Y975389D01*
X1600788Y975306D01*
X1600538Y975139D01*
X1600371Y974889D01*
X1600288Y974556D01*
X1600371Y974264D01*
X1600579Y973972D01*
X1600829Y973806D01*
X1601121Y973764D01*
X1601454Y973847D01*
X1601704Y974056D01*
X1601954Y974431D01*
G01X1603304Y973389D02*
X1603554Y973097D01*
X1603888Y972931D01*
X1604263Y972889D01*
X1604596Y972931D01*
X1604929Y973139D01*
X1605138Y973389D01*
X1605179Y973639D01*
X1605096Y973931D01*
X1604804Y974139D01*
X1604513Y974222D01*
X1604138D01*
G01X1604513D02*
X1604763Y974347D01*
X1604971Y974556D01*
X1605054Y974806D01*
X1604971Y975056D01*
X1604763Y975264D01*
X1604388Y975389D01*
X1604013Y975347D01*
X1603638Y975181D01*
G01X1602771Y963889D02*
Y967889D01*
X1595371D01*
G01X1579947Y972809D02*
Y975309D01*
X1580988D01*
X1581322Y975184D01*
X1581530Y975017D01*
X1581613Y974684D01*
X1581530Y974351D01*
X1581280Y974142D01*
X1580988Y974017D01*
X1579947D01*
G01X1580988D02*
X1581613Y972809D01*
G01X1584380D02*
Y975309D01*
X1582838Y973517D01*
X1584922D01*
G01X1586980Y972809D02*
X1587272Y972851D01*
X1587605Y972976D01*
X1587813Y973184D01*
X1587897Y973476D01*
X1587813Y973767D01*
X1587563Y974017D01*
X1587188Y974142D01*
X1586772D01*
X1586522Y974226D01*
X1586313Y974434D01*
X1586230Y974726D01*
X1586355Y975017D01*
X1586647Y975226D01*
X1586980Y975309D01*
X1587313Y975226D01*
X1587605Y975017D01*
X1587730Y974726D01*
X1587647Y974434D01*
X1587438Y974226D01*
X1587188Y974142D01*
X1586772D01*
X1586397Y974017D01*
X1586147Y973767D01*
X1586063Y973476D01*
X1586147Y973184D01*
X1586355Y972976D01*
X1586688Y972851D01*
X1586980Y972809D01*
G01X1590080D02*
X1590372Y972851D01*
X1590705Y972976D01*
X1590913Y973184D01*
X1590997Y973476D01*
X1590913Y973767D01*
X1590663Y974017D01*
X1590288Y974142D01*
X1589872D01*
X1589622Y974226D01*
X1589413Y974434D01*
X1589330Y974726D01*
X1589455Y975017D01*
X1589747Y975226D01*
X1590080Y975309D01*
X1590413Y975226D01*
X1590705Y975017D01*
X1590830Y974726D01*
X1590747Y974434D01*
X1590538Y974226D01*
X1590288Y974142D01*
X1589872D01*
X1589497Y974017D01*
X1589247Y973767D01*
X1589163Y973476D01*
X1589247Y973184D01*
X1589455Y972976D01*
X1589788Y972851D01*
X1590080Y972809D01*
G01X1588630Y963809D02*
Y967809D01*
X1581230D01*
G01X1582386Y944987D02*
X1582053Y945029D01*
X1581761Y945195D01*
X1581511Y945445D01*
X1581344Y945737D01*
X1581261Y946070D01*
Y946404D01*
X1581344Y946737D01*
X1581511Y947029D01*
X1581761Y947279D01*
X1582053Y947445D01*
X1582386Y947487D01*
X1582719Y947445D01*
X1583011Y947279D01*
X1583261Y947029D01*
X1583428Y946737D01*
X1583511Y946404D01*
Y946070D01*
X1583428Y945737D01*
X1583261Y945445D01*
X1583011Y945195D01*
X1582719Y945029D01*
X1582386Y944987D01*
G01X1582719Y945654D02*
X1583219Y944987D01*
G01X1584694Y947070D02*
X1584944Y947320D01*
X1585236Y947445D01*
X1585569Y947487D01*
X1585986Y947404D01*
X1586278Y947195D01*
X1586361Y946945D01*
X1586319Y946695D01*
X1586153Y946487D01*
X1585319Y946070D01*
X1584944Y945779D01*
X1584694Y945362D01*
X1584611Y944987D01*
X1586361D01*
G01X1588503D02*
X1588586Y945529D01*
X1588711Y945987D01*
X1588878Y946404D01*
X1589086Y946862D01*
X1589419Y947487D01*
X1587753D01*
G01X1590894Y947070D02*
X1591144Y947320D01*
X1591436Y947445D01*
X1591769Y947487D01*
X1592186Y947404D01*
X1592478Y947195D01*
X1592561Y946945D01*
X1592519Y946695D01*
X1592353Y946487D01*
X1591519Y946070D01*
X1591144Y945779D01*
X1590894Y945362D01*
X1590811Y944987D01*
X1592561D01*
G01X1593536Y948987D02*
Y962987D01*
G01X1580536Y948987D02*
X1593536D01*
G01X1580536Y962987D02*
Y948987D01*
G01X1593536Y962987D02*
X1580536D01*
G01X1596578Y945028D02*
X1596245Y945070D01*
X1595953Y945236D01*
X1595703Y945486D01*
X1595536Y945778D01*
X1595453Y946111D01*
Y946445D01*
X1595536Y946778D01*
X1595703Y947070D01*
X1595953Y947320D01*
X1596245Y947486D01*
X1596578Y947528D01*
X1596911Y947486D01*
X1597203Y947320D01*
X1597453Y947070D01*
X1597620Y946778D01*
X1597703Y946445D01*
Y946111D01*
X1597620Y945778D01*
X1597453Y945486D01*
X1597203Y945236D01*
X1596911Y945070D01*
X1596578Y945028D01*
G01X1596911Y945695D02*
X1597411Y945028D01*
G01X1598886Y947111D02*
X1599136Y947361D01*
X1599428Y947486D01*
X1599761Y947528D01*
X1600178Y947445D01*
X1600470Y947236D01*
X1600553Y946986D01*
X1600511Y946736D01*
X1600345Y946528D01*
X1599511Y946111D01*
X1599136Y945820D01*
X1598886Y945403D01*
X1598803Y945028D01*
X1600553D01*
G01X1601861Y945528D02*
X1602111Y945236D01*
X1602445Y945070D01*
X1602820Y945028D01*
X1603153Y945070D01*
X1603486Y945278D01*
X1603695Y945528D01*
X1603736Y945778D01*
X1603653Y946070D01*
X1603361Y946278D01*
X1603070Y946361D01*
X1602695D01*
G01X1603070D02*
X1603320Y946486D01*
X1603528Y946695D01*
X1603611Y946945D01*
X1603528Y947195D01*
X1603320Y947403D01*
X1602945Y947528D01*
X1602570Y947486D01*
X1602195Y947320D01*
G01X1605086Y946070D02*
X1605378Y946361D01*
X1605628Y946528D01*
X1605961Y946611D01*
X1606253Y946528D01*
X1606461Y946361D01*
X1606628Y946111D01*
X1606670Y945820D01*
X1606628Y945570D01*
X1606461Y945320D01*
X1606211Y945111D01*
X1605920Y945028D01*
X1605586Y945111D01*
X1605295Y945361D01*
X1605128Y945736D01*
X1605086Y946153D01*
X1605170Y946695D01*
X1605295Y946986D01*
X1605503Y947278D01*
X1605795Y947486D01*
X1606086Y947528D01*
X1606378Y947445D01*
X1606586Y947236D01*
G01X1607728Y949028D02*
Y963028D01*
G01X1594728Y949028D02*
X1607728D01*
G01X1594728Y963028D02*
Y949028D01*
G01X1607728Y963028D02*
X1594728D01*
G01X1584425Y1071190D02*
X1581925D01*
Y1072231D01*
X1582050Y1072565D01*
X1582217Y1072773D01*
X1582550Y1072856D01*
X1582883Y1072773D01*
X1583092Y1072523D01*
X1583217Y1072231D01*
Y1071190D01*
G01Y1072231D02*
X1584425Y1072856D01*
G01X1583925Y1074206D02*
X1584217Y1074456D01*
X1584383Y1074790D01*
X1584425Y1075165D01*
X1584383Y1075498D01*
X1584175Y1075831D01*
X1583925Y1076040D01*
X1583675Y1076081D01*
X1583383Y1075998D01*
X1583175Y1075706D01*
X1583092Y1075415D01*
Y1075040D01*
G01Y1075415D02*
X1582967Y1075665D01*
X1582758Y1075873D01*
X1582508Y1075956D01*
X1582258Y1075873D01*
X1582050Y1075665D01*
X1581925Y1075290D01*
X1581967Y1074915D01*
X1582133Y1074540D01*
G01X1582342Y1077431D02*
X1582092Y1077681D01*
X1581967Y1077973D01*
X1581925Y1078306D01*
X1582008Y1078723D01*
X1582217Y1079015D01*
X1582467Y1079098D01*
X1582717Y1079056D01*
X1582925Y1078890D01*
X1583342Y1078056D01*
X1583633Y1077681D01*
X1584050Y1077431D01*
X1584425Y1077348D01*
Y1079098D01*
G01Y1081323D02*
X1584383Y1081615D01*
X1584258Y1081948D01*
X1584050Y1082156D01*
X1583758Y1082240D01*
X1583467Y1082156D01*
X1583217Y1081906D01*
X1583092Y1081531D01*
Y1081115D01*
X1583008Y1080865D01*
X1582800Y1080656D01*
X1582508Y1080573D01*
X1582217Y1080698D01*
X1582008Y1080990D01*
X1581925Y1081323D01*
X1582008Y1081656D01*
X1582217Y1081948D01*
X1582508Y1082073D01*
X1582800Y1081990D01*
X1583008Y1081781D01*
X1583092Y1081531D01*
Y1081115D01*
X1583217Y1080740D01*
X1583467Y1080490D01*
X1583758Y1080406D01*
X1584050Y1080490D01*
X1584258Y1080698D01*
X1584383Y1081031D01*
X1584425Y1081323D01*
G01X1572925Y1081973D02*
X1576925D01*
Y1089373D01*
G01X1579925Y1071190D02*
X1577425D01*
Y1072231D01*
X1577550Y1072565D01*
X1577717Y1072773D01*
X1578050Y1072856D01*
X1578383Y1072773D01*
X1578592Y1072523D01*
X1578717Y1072231D01*
Y1071190D01*
G01Y1072231D02*
X1579925Y1072856D01*
G01X1579425Y1074206D02*
X1579717Y1074456D01*
X1579883Y1074790D01*
X1579925Y1075165D01*
X1579883Y1075498D01*
X1579675Y1075831D01*
X1579425Y1076040D01*
X1579175Y1076081D01*
X1578883Y1075998D01*
X1578675Y1075706D01*
X1578592Y1075415D01*
Y1075040D01*
G01Y1075415D02*
X1578467Y1075665D01*
X1578258Y1075873D01*
X1578008Y1075956D01*
X1577758Y1075873D01*
X1577550Y1075665D01*
X1577425Y1075290D01*
X1577467Y1074915D01*
X1577633Y1074540D01*
G01X1579425Y1077306D02*
X1579717Y1077556D01*
X1579883Y1077890D01*
X1579925Y1078265D01*
X1579883Y1078598D01*
X1579675Y1078931D01*
X1579425Y1079140D01*
X1579175Y1079181D01*
X1578883Y1079098D01*
X1578675Y1078806D01*
X1578592Y1078515D01*
Y1078140D01*
G01Y1078515D02*
X1578467Y1078765D01*
X1578258Y1078973D01*
X1578008Y1079056D01*
X1577758Y1078973D01*
X1577550Y1078765D01*
X1577425Y1078390D01*
X1577467Y1078015D01*
X1577633Y1077640D01*
G01X1579925Y1081323D02*
X1577425D01*
X1577925Y1080823D01*
G01X1579925D02*
Y1081823D01*
G01X1587033Y1079500D02*
Y1082000D01*
X1587867D01*
X1588200Y1081875D01*
X1588450Y1081708D01*
X1588658Y1081458D01*
X1588825Y1081167D01*
X1588867Y1080750D01*
X1588825Y1080333D01*
X1588658Y1080042D01*
X1588450Y1079792D01*
X1588200Y1079625D01*
X1587867Y1079500D01*
X1587033D01*
G01X1591050D02*
X1591342Y1079542D01*
X1591675Y1079667D01*
X1591883Y1079875D01*
X1591967Y1080167D01*
X1591883Y1080458D01*
X1591633Y1080708D01*
X1591258Y1080833D01*
X1590842D01*
X1590592Y1080917D01*
X1590383Y1081125D01*
X1590300Y1081417D01*
X1590425Y1081708D01*
X1590717Y1081917D01*
X1591050Y1082000D01*
X1591383Y1081917D01*
X1591675Y1081708D01*
X1591800Y1081417D01*
X1591717Y1081125D01*
X1591508Y1080917D01*
X1591258Y1080833D01*
X1590842D01*
X1590467Y1080708D01*
X1590217Y1080458D01*
X1590133Y1080167D01*
X1590217Y1079875D01*
X1590425Y1079667D01*
X1590758Y1079542D01*
X1591050Y1079500D01*
G01X1620767Y1078292D02*
X1620517Y1078417D01*
X1620225Y1078500D01*
X1619892D01*
X1619517Y1078375D01*
X1619225Y1078167D01*
X1619017Y1077917D01*
X1618850Y1077500D01*
X1618808Y1077125D01*
X1618892Y1076750D01*
X1619017Y1076500D01*
X1619267Y1076250D01*
X1619558Y1076083D01*
X1619850Y1076000D01*
X1620142D01*
X1620433Y1076083D01*
X1620683Y1076208D01*
X1620892Y1076375D01*
G01X1622950Y1076000D02*
Y1078500D01*
X1622450Y1078000D01*
G01Y1076000D02*
X1623450D01*
G01X1625133Y1076375D02*
X1625383Y1076167D01*
X1625675Y1076042D01*
X1626050Y1076000D01*
X1626425Y1076083D01*
X1626717Y1076250D01*
X1626925Y1076542D01*
X1626967Y1076875D01*
X1626883Y1077208D01*
X1626675Y1077417D01*
X1626383Y1077583D01*
X1626092Y1077625D01*
X1625800Y1077583D01*
X1625425Y1077417D01*
X1625550Y1078500D01*
X1626675D01*
G01X1628358Y1077042D02*
X1628650Y1077333D01*
X1628900Y1077500D01*
X1629233Y1077583D01*
X1629525Y1077500D01*
X1629733Y1077333D01*
X1629900Y1077083D01*
X1629942Y1076792D01*
X1629900Y1076542D01*
X1629733Y1076292D01*
X1629483Y1076083D01*
X1629192Y1076000D01*
X1628858Y1076083D01*
X1628567Y1076333D01*
X1628400Y1076708D01*
X1628358Y1077125D01*
X1628442Y1077667D01*
X1628567Y1077958D01*
X1628775Y1078250D01*
X1629067Y1078458D01*
X1629358Y1078500D01*
X1629650Y1078417D01*
X1629858Y1078208D01*
G01X1620767Y1082292D02*
X1620517Y1082417D01*
X1620225Y1082500D01*
X1619892D01*
X1619517Y1082375D01*
X1619225Y1082167D01*
X1619017Y1081917D01*
X1618850Y1081500D01*
X1618808Y1081125D01*
X1618892Y1080750D01*
X1619017Y1080500D01*
X1619267Y1080250D01*
X1619558Y1080083D01*
X1619850Y1080000D01*
X1620142D01*
X1620433Y1080083D01*
X1620683Y1080208D01*
X1620892Y1080375D01*
G01X1622950Y1080000D02*
Y1082500D01*
X1622450Y1082000D01*
G01Y1080000D02*
X1623450D01*
G01X1625133Y1080375D02*
X1625383Y1080167D01*
X1625675Y1080042D01*
X1626050Y1080000D01*
X1626425Y1080083D01*
X1626717Y1080250D01*
X1626925Y1080542D01*
X1626967Y1080875D01*
X1626883Y1081208D01*
X1626675Y1081417D01*
X1626383Y1081583D01*
X1626092Y1081625D01*
X1625800Y1081583D01*
X1625425Y1081417D01*
X1625550Y1082500D01*
X1626675D01*
G01X1628233Y1080375D02*
X1628483Y1080167D01*
X1628775Y1080042D01*
X1629150Y1080000D01*
X1629525Y1080083D01*
X1629817Y1080250D01*
X1630025Y1080542D01*
X1630067Y1080875D01*
X1629983Y1081208D01*
X1629775Y1081417D01*
X1629483Y1081583D01*
X1629192Y1081625D01*
X1628900Y1081583D01*
X1628525Y1081417D01*
X1628650Y1082500D01*
X1629775D01*
G01X1612700Y1104917D02*
X1610200D01*
Y1105958D01*
X1610325Y1106292D01*
X1610492Y1106500D01*
X1610825Y1106583D01*
X1611158Y1106500D01*
X1611367Y1106250D01*
X1611492Y1105958D01*
Y1104917D01*
G01Y1105958D02*
X1612700Y1106583D01*
G01X1612200Y1107933D02*
X1612492Y1108183D01*
X1612658Y1108517D01*
X1612700Y1108892D01*
X1612658Y1109225D01*
X1612450Y1109558D01*
X1612200Y1109767D01*
X1611950Y1109808D01*
X1611658Y1109725D01*
X1611450Y1109433D01*
X1611367Y1109142D01*
Y1108767D01*
G01Y1109142D02*
X1611242Y1109392D01*
X1611033Y1109600D01*
X1610783Y1109683D01*
X1610533Y1109600D01*
X1610325Y1109392D01*
X1610200Y1109017D01*
X1610242Y1108642D01*
X1610408Y1108267D01*
G01X1610617Y1111158D02*
X1610367Y1111408D01*
X1610242Y1111700D01*
X1610200Y1112033D01*
X1610283Y1112450D01*
X1610492Y1112742D01*
X1610742Y1112825D01*
X1610992Y1112783D01*
X1611200Y1112617D01*
X1611617Y1111783D01*
X1611908Y1111408D01*
X1612325Y1111158D01*
X1612700Y1111075D01*
Y1112825D01*
G01X1612408Y1114342D02*
X1612617Y1114633D01*
X1612700Y1114967D01*
X1612617Y1115300D01*
X1612367Y1115592D01*
X1611992Y1115800D01*
X1611617Y1115883D01*
X1611158D01*
X1610783Y1115800D01*
X1610450Y1115592D01*
X1610283Y1115342D01*
X1610200Y1115050D01*
X1610283Y1114717D01*
X1610450Y1114467D01*
X1610700Y1114300D01*
X1611033Y1114217D01*
X1611325Y1114300D01*
X1611617Y1114508D01*
X1611783Y1114758D01*
X1611825Y1115050D01*
X1611742Y1115383D01*
X1611533Y1115633D01*
X1611158Y1115883D01*
G01X1604200Y1116600D02*
X1600200D01*
Y1109200D01*
G01X1597017Y1092500D02*
Y1095000D01*
X1598058D01*
X1598392Y1094875D01*
X1598600Y1094708D01*
X1598683Y1094375D01*
X1598600Y1094042D01*
X1598350Y1093833D01*
X1598058Y1093708D01*
X1597017D01*
G01X1598058D02*
X1598683Y1092500D01*
G01X1600033Y1093000D02*
X1600283Y1092708D01*
X1600617Y1092542D01*
X1600992Y1092500D01*
X1601325Y1092542D01*
X1601658Y1092750D01*
X1601867Y1093000D01*
X1601908Y1093250D01*
X1601825Y1093542D01*
X1601533Y1093750D01*
X1601242Y1093833D01*
X1600867D01*
G01X1601242D02*
X1601492Y1093958D01*
X1601700Y1094167D01*
X1601783Y1094417D01*
X1601700Y1094667D01*
X1601492Y1094875D01*
X1601117Y1095000D01*
X1600742Y1094958D01*
X1600367Y1094792D01*
G01X1603133Y1093000D02*
X1603383Y1092708D01*
X1603717Y1092542D01*
X1604092Y1092500D01*
X1604425Y1092542D01*
X1604758Y1092750D01*
X1604967Y1093000D01*
X1605008Y1093250D01*
X1604925Y1093542D01*
X1604633Y1093750D01*
X1604342Y1093833D01*
X1603967D01*
G01X1604342D02*
X1604592Y1093958D01*
X1604800Y1094167D01*
X1604883Y1094417D01*
X1604800Y1094667D01*
X1604592Y1094875D01*
X1604217Y1095000D01*
X1603842Y1094958D01*
X1603467Y1094792D01*
G01X1607150Y1095000D02*
X1606817Y1094917D01*
X1606567Y1094708D01*
X1606400Y1094458D01*
X1606275Y1094125D01*
X1606233Y1093750D01*
X1606275Y1093375D01*
X1606400Y1093042D01*
X1606567Y1092792D01*
X1606817Y1092583D01*
X1607150Y1092500D01*
X1607483Y1092583D01*
X1607733Y1092792D01*
X1607900Y1093042D01*
X1608025Y1093375D01*
X1608067Y1093750D01*
X1608025Y1094125D01*
X1607900Y1094458D01*
X1607733Y1094708D01*
X1607483Y1094917D01*
X1607150Y1095000D01*
G01X1584825Y1095873D02*
Y1091873D01*
X1592225D01*
G01X1619517Y1099000D02*
Y1101500D01*
X1620558D01*
X1620892Y1101375D01*
X1621100Y1101208D01*
X1621183Y1100875D01*
X1621100Y1100542D01*
X1620850Y1100333D01*
X1620558Y1100208D01*
X1619517D01*
G01X1620558D02*
X1621183Y1099000D01*
G01X1622533Y1099375D02*
X1622783Y1099167D01*
X1623075Y1099042D01*
X1623450Y1099000D01*
X1623825Y1099083D01*
X1624117Y1099250D01*
X1624325Y1099542D01*
X1624367Y1099875D01*
X1624283Y1100208D01*
X1624075Y1100417D01*
X1623783Y1100583D01*
X1623492Y1100625D01*
X1623200Y1100583D01*
X1622825Y1100417D01*
X1622950Y1101500D01*
X1624075D01*
G01X1626550Y1099000D02*
X1626842Y1099042D01*
X1627175Y1099167D01*
X1627383Y1099375D01*
X1627467Y1099667D01*
X1627383Y1099958D01*
X1627133Y1100208D01*
X1626758Y1100333D01*
X1626342D01*
X1626092Y1100417D01*
X1625883Y1100625D01*
X1625800Y1100917D01*
X1625925Y1101208D01*
X1626217Y1101417D01*
X1626550Y1101500D01*
X1626883Y1101417D01*
X1627175Y1101208D01*
X1627300Y1100917D01*
X1627217Y1100625D01*
X1627008Y1100417D01*
X1626758Y1100333D01*
X1626342D01*
X1625967Y1100208D01*
X1625717Y1099958D01*
X1625633Y1099667D01*
X1625717Y1099375D01*
X1625925Y1099167D01*
X1626258Y1099042D01*
X1626550Y1099000D01*
G01X1628733Y1099375D02*
X1628983Y1099167D01*
X1629275Y1099042D01*
X1629650Y1099000D01*
X1630025Y1099083D01*
X1630317Y1099250D01*
X1630525Y1099542D01*
X1630567Y1099875D01*
X1630483Y1100208D01*
X1630275Y1100417D01*
X1629983Y1100583D01*
X1629692Y1100625D01*
X1629400Y1100583D01*
X1629025Y1100417D01*
X1629150Y1101500D01*
X1630275D01*
G01X1617427Y1125199D02*
Y1111199D01*
G01X1630427Y1125199D02*
X1617427D01*
G01Y1111199D02*
X1630427D01*
G01X1594025Y1083873D02*
X1577925D01*
G01X1594025Y1090873D02*
Y1083873D01*
G01X1577925Y1090873D02*
X1594025D01*
G01X1577925Y1083873D02*
Y1090873D01*
G01X1580100Y1096500D02*
X1581900Y1098600D01*
X1584100Y1096500D01*
G01X1587700Y1096400D02*
Y1115600D01*
X1576500D01*
Y1096400D01*
X1587700D01*
Y1096800D01*
G01X1606608Y1106767D02*
X1606483Y1106517D01*
X1606400Y1106225D01*
Y1105892D01*
X1606525Y1105517D01*
X1606733Y1105225D01*
X1606983Y1105017D01*
X1607400Y1104850D01*
X1607775Y1104808D01*
X1608150Y1104892D01*
X1608400Y1105017D01*
X1608650Y1105267D01*
X1608817Y1105558D01*
X1608900Y1105850D01*
Y1106142D01*
X1608817Y1106433D01*
X1608692Y1106683D01*
X1608525Y1106892D01*
G01X1608900Y1108950D02*
X1606400D01*
X1606900Y1108450D01*
G01X1608900D02*
Y1109450D01*
G01X1608525Y1111133D02*
X1608733Y1111383D01*
X1608858Y1111675D01*
X1608900Y1112050D01*
X1608817Y1112425D01*
X1608650Y1112717D01*
X1608358Y1112925D01*
X1608025Y1112967D01*
X1607692Y1112883D01*
X1607483Y1112675D01*
X1607317Y1112383D01*
X1607275Y1112092D01*
X1607317Y1111800D01*
X1607483Y1111425D01*
X1606400Y1111550D01*
Y1112675D01*
G01X1608400Y1114233D02*
X1608692Y1114483D01*
X1608858Y1114817D01*
X1608900Y1115192D01*
X1608858Y1115525D01*
X1608650Y1115858D01*
X1608400Y1116067D01*
X1608150Y1116108D01*
X1607858Y1116025D01*
X1607650Y1115733D01*
X1607567Y1115442D01*
Y1115067D01*
G01Y1115442D02*
X1607442Y1115692D01*
X1607233Y1115900D01*
X1606983Y1115983D01*
X1606733Y1115900D01*
X1606525Y1115692D01*
X1606400Y1115317D01*
X1606442Y1114942D01*
X1606608Y1114567D01*
G01X1572017Y1178000D02*
Y1180500D01*
X1573058D01*
X1573392Y1180375D01*
X1573600Y1180208D01*
X1573683Y1179875D01*
X1573600Y1179542D01*
X1573350Y1179333D01*
X1573058Y1179208D01*
X1572017D01*
G01X1573058D02*
X1573683Y1178000D01*
G01X1575033Y1178500D02*
X1575283Y1178208D01*
X1575617Y1178042D01*
X1575992Y1178000D01*
X1576325Y1178042D01*
X1576658Y1178250D01*
X1576867Y1178500D01*
X1576908Y1178750D01*
X1576825Y1179042D01*
X1576533Y1179250D01*
X1576242Y1179333D01*
X1575867D01*
G01X1576242D02*
X1576492Y1179458D01*
X1576700Y1179667D01*
X1576783Y1179917D01*
X1576700Y1180167D01*
X1576492Y1180375D01*
X1576117Y1180500D01*
X1575742Y1180458D01*
X1575367Y1180292D01*
G01X1579050Y1178000D02*
Y1180500D01*
X1578550Y1180000D01*
G01Y1178000D02*
X1579550D01*
G01X1582067D02*
X1582150Y1178542D01*
X1582275Y1179000D01*
X1582442Y1179417D01*
X1582650Y1179875D01*
X1582983Y1180500D01*
X1581317D01*
G01X1620150Y1150500D02*
X1619817Y1150542D01*
X1619525Y1150708D01*
X1619275Y1150958D01*
X1619108Y1151250D01*
X1619025Y1151583D01*
Y1151917D01*
X1619108Y1152250D01*
X1619275Y1152542D01*
X1619525Y1152792D01*
X1619817Y1152958D01*
X1620150Y1153000D01*
X1620483Y1152958D01*
X1620775Y1152792D01*
X1621025Y1152542D01*
X1621192Y1152250D01*
X1621275Y1151917D01*
Y1151583D01*
X1621192Y1151250D01*
X1621025Y1150958D01*
X1620775Y1150708D01*
X1620483Y1150542D01*
X1620150Y1150500D01*
G01X1620483Y1151167D02*
X1620983Y1150500D01*
G01X1622458Y1152583D02*
X1622708Y1152833D01*
X1623000Y1152958D01*
X1623333Y1153000D01*
X1623750Y1152917D01*
X1624042Y1152708D01*
X1624125Y1152458D01*
X1624083Y1152208D01*
X1623917Y1152000D01*
X1623083Y1151583D01*
X1622708Y1151292D01*
X1622458Y1150875D01*
X1622375Y1150500D01*
X1624125D01*
G01X1625558Y1151542D02*
X1625850Y1151833D01*
X1626100Y1152000D01*
X1626433Y1152083D01*
X1626725Y1152000D01*
X1626933Y1151833D01*
X1627100Y1151583D01*
X1627142Y1151292D01*
X1627100Y1151042D01*
X1626933Y1150792D01*
X1626683Y1150583D01*
X1626392Y1150500D01*
X1626058Y1150583D01*
X1625767Y1150833D01*
X1625600Y1151208D01*
X1625558Y1151625D01*
X1625642Y1152167D01*
X1625767Y1152458D01*
X1625975Y1152750D01*
X1626267Y1152958D01*
X1626558Y1153000D01*
X1626850Y1152917D01*
X1627058Y1152708D01*
G01X1628658Y1152583D02*
X1628908Y1152833D01*
X1629200Y1152958D01*
X1629533Y1153000D01*
X1629950Y1152917D01*
X1630242Y1152708D01*
X1630325Y1152458D01*
X1630283Y1152208D01*
X1630117Y1152000D01*
X1629283Y1151583D01*
X1628908Y1151292D01*
X1628658Y1150875D01*
X1628575Y1150500D01*
X1630325D01*
G01X1616821Y1149317D02*
Y1135317D01*
G01X1629821Y1149317D02*
X1616821D01*
G01Y1135317D02*
X1629821D01*
G01X1614552Y1165723D02*
X1612052D01*
Y1166764D01*
X1612177Y1167098D01*
X1612344Y1167306D01*
X1612677Y1167389D01*
X1613010Y1167306D01*
X1613219Y1167056D01*
X1613344Y1166764D01*
Y1165723D01*
G01Y1166764D02*
X1614552Y1167389D01*
G01X1614052Y1168739D02*
X1614344Y1168989D01*
X1614510Y1169323D01*
X1614552Y1169698D01*
X1614510Y1170031D01*
X1614302Y1170364D01*
X1614052Y1170573D01*
X1613802Y1170614D01*
X1613510Y1170531D01*
X1613302Y1170239D01*
X1613219Y1169948D01*
Y1169573D01*
G01Y1169948D02*
X1613094Y1170198D01*
X1612885Y1170406D01*
X1612635Y1170489D01*
X1612385Y1170406D01*
X1612177Y1170198D01*
X1612052Y1169823D01*
X1612094Y1169448D01*
X1612260Y1169073D01*
G01X1614552Y1172756D02*
X1612052D01*
X1612552Y1172256D01*
G01X1614552D02*
Y1173256D01*
G01X1612052Y1175856D02*
X1612135Y1175523D01*
X1612344Y1175273D01*
X1612594Y1175106D01*
X1612927Y1174981D01*
X1613302Y1174939D01*
X1613677Y1174981D01*
X1614010Y1175106D01*
X1614260Y1175273D01*
X1614469Y1175523D01*
X1614552Y1175856D01*
X1614469Y1176189D01*
X1614260Y1176439D01*
X1614010Y1176606D01*
X1613677Y1176731D01*
X1613302Y1176773D01*
X1612927Y1176731D01*
X1612594Y1176606D01*
X1612344Y1176439D01*
X1612135Y1176189D01*
X1612052Y1175856D01*
G01X1619236Y1165723D02*
X1616736D01*
Y1166764D01*
X1616861Y1167098D01*
X1617028Y1167306D01*
X1617361Y1167389D01*
X1617694Y1167306D01*
X1617903Y1167056D01*
X1618028Y1166764D01*
Y1165723D01*
G01Y1166764D02*
X1619236Y1167389D01*
G01X1618736Y1168739D02*
X1619028Y1168989D01*
X1619194Y1169323D01*
X1619236Y1169698D01*
X1619194Y1170031D01*
X1618986Y1170364D01*
X1618736Y1170573D01*
X1618486Y1170614D01*
X1618194Y1170531D01*
X1617986Y1170239D01*
X1617903Y1169948D01*
Y1169573D01*
G01Y1169948D02*
X1617778Y1170198D01*
X1617569Y1170406D01*
X1617319Y1170489D01*
X1617069Y1170406D01*
X1616861Y1170198D01*
X1616736Y1169823D01*
X1616778Y1169448D01*
X1616944Y1169073D01*
G01X1616736Y1172756D02*
X1616819Y1172423D01*
X1617028Y1172173D01*
X1617278Y1172006D01*
X1617611Y1171881D01*
X1617986Y1171839D01*
X1618361Y1171881D01*
X1618694Y1172006D01*
X1618944Y1172173D01*
X1619153Y1172423D01*
X1619236Y1172756D01*
X1619153Y1173089D01*
X1618944Y1173339D01*
X1618694Y1173506D01*
X1618361Y1173631D01*
X1617986Y1173673D01*
X1617611Y1173631D01*
X1617278Y1173506D01*
X1617028Y1173339D01*
X1616819Y1173089D01*
X1616736Y1172756D01*
G01X1618736Y1174939D02*
X1619028Y1175189D01*
X1619194Y1175523D01*
X1619236Y1175898D01*
X1619194Y1176231D01*
X1618986Y1176564D01*
X1618736Y1176773D01*
X1618486Y1176814D01*
X1618194Y1176731D01*
X1617986Y1176439D01*
X1617903Y1176148D01*
Y1175773D01*
G01Y1176148D02*
X1617778Y1176398D01*
X1617569Y1176606D01*
X1617319Y1176689D01*
X1617069Y1176606D01*
X1616861Y1176398D01*
X1616736Y1176023D01*
X1616778Y1175648D01*
X1616944Y1175273D01*
G01X1574042Y1194767D02*
X1573917Y1194517D01*
X1573834Y1194225D01*
Y1193892D01*
X1573959Y1193517D01*
X1574167Y1193225D01*
X1574417Y1193017D01*
X1574834Y1192850D01*
X1575209Y1192808D01*
X1575584Y1192892D01*
X1575834Y1193017D01*
X1576084Y1193267D01*
X1576251Y1193558D01*
X1576334Y1193850D01*
Y1194142D01*
X1576251Y1194433D01*
X1576126Y1194683D01*
X1575959Y1194892D01*
G01X1576334Y1196950D02*
X1573834D01*
X1574334Y1196450D01*
G01X1576334D02*
Y1197450D01*
G01Y1200550D02*
X1573834D01*
X1575626Y1199008D01*
Y1201092D01*
G01X1576334Y1203150D02*
X1576292Y1203442D01*
X1576167Y1203775D01*
X1575959Y1203983D01*
X1575667Y1204067D01*
X1575376Y1203983D01*
X1575126Y1203733D01*
X1575001Y1203358D01*
Y1202942D01*
X1574917Y1202692D01*
X1574709Y1202483D01*
X1574417Y1202400D01*
X1574126Y1202525D01*
X1573917Y1202817D01*
X1573834Y1203150D01*
X1573917Y1203483D01*
X1574126Y1203775D01*
X1574417Y1203900D01*
X1574709Y1203817D01*
X1574917Y1203608D01*
X1575001Y1203358D01*
Y1202942D01*
X1575126Y1202567D01*
X1575376Y1202317D01*
X1575667Y1202233D01*
X1575959Y1202317D01*
X1576167Y1202525D01*
X1576292Y1202858D01*
X1576334Y1203150D01*
G01X1608986Y1271565D02*
Y1282765D01*
X1617786D01*
Y1271565D01*
X1608986D01*
G01X1604303Y1285665D02*
Y1288165D01*
X1605344D01*
X1605678Y1288040D01*
X1605886Y1287873D01*
X1605969Y1287540D01*
X1605886Y1287207D01*
X1605636Y1286998D01*
X1605344Y1286873D01*
X1604303D01*
G01X1605344D02*
X1605969Y1285665D01*
G01X1607403Y1288165D02*
Y1285665D01*
X1609069D01*
G01X1612169D02*
X1610503D01*
Y1288165D01*
X1612169D01*
G01X1611503Y1286957D02*
X1610503D01*
G01X1613519Y1285665D02*
Y1288165D01*
X1614353D01*
X1614686Y1288040D01*
X1614936Y1287873D01*
X1615144Y1287623D01*
X1615311Y1287332D01*
X1615353Y1286915D01*
X1615311Y1286498D01*
X1615144Y1286207D01*
X1614936Y1285957D01*
X1614686Y1285790D01*
X1614353Y1285665D01*
X1613519D01*
G01X1616619Y1286165D02*
X1616869Y1285873D01*
X1617203Y1285707D01*
X1617578Y1285665D01*
X1617911Y1285707D01*
X1618244Y1285915D01*
X1618453Y1286165D01*
X1618494Y1286415D01*
X1618411Y1286707D01*
X1618119Y1286915D01*
X1617828Y1286998D01*
X1617453D01*
G01X1617828D02*
X1618078Y1287123D01*
X1618286Y1287332D01*
X1618369Y1287582D01*
X1618286Y1287832D01*
X1618078Y1288040D01*
X1617703Y1288165D01*
X1617328Y1288123D01*
X1616953Y1287957D01*
G01X1621136Y1285665D02*
Y1288165D01*
X1619594Y1286373D01*
X1621678D01*
G01X1594345Y1653628D02*
X1594745Y1653295D01*
X1595212Y1653095D01*
X1595812Y1653028D01*
X1596412Y1653161D01*
X1596879Y1653428D01*
X1597212Y1653895D01*
X1597279Y1654428D01*
X1597145Y1654961D01*
X1596812Y1655295D01*
X1596345Y1655561D01*
X1595879Y1655628D01*
X1595412Y1655561D01*
X1594812Y1655295D01*
X1595012Y1657028D01*
X1596812D01*
G01X1637431Y221492D02*
X1642481D01*
Y320192D01*
X1667131D01*
Y135792D01*
X1642481D01*
Y194492D01*
X1637431D01*
Y221492D01*
G01X1623538Y246661D02*
Y242661D01*
X1630938D01*
G01X1642606Y329492D02*
Y331992D01*
G01X1644356D02*
Y329492D01*
G01Y330742D02*
X1642606D01*
G01X1645664Y329492D02*
Y331992D01*
X1646498D01*
X1646831Y331867D01*
X1647081Y331700D01*
X1647289Y331450D01*
X1647456Y331159D01*
X1647498Y330742D01*
X1647456Y330325D01*
X1647289Y330034D01*
X1647081Y329784D01*
X1646831Y329617D01*
X1646498Y329492D01*
X1645664D01*
G01X1648764D02*
Y331992D01*
X1649598D01*
X1649931Y331867D01*
X1650181Y331700D01*
X1650389Y331450D01*
X1650556Y331159D01*
X1650598Y330742D01*
X1650556Y330325D01*
X1650389Y330034D01*
X1650181Y329784D01*
X1649931Y329617D01*
X1649598Y329492D01*
X1648764D01*
G01X1651906Y329825D02*
X1652239Y329617D01*
X1652614Y329492D01*
X1652948D01*
X1653281Y329617D01*
X1653531Y329825D01*
X1653656Y330117D01*
X1653573Y330409D01*
X1653364Y330659D01*
X1652989Y330825D01*
X1652489Y330909D01*
X1652198Y331075D01*
X1652073Y331367D01*
X1652156Y331659D01*
X1652364Y331867D01*
X1652656Y331992D01*
X1652948D01*
X1653239Y331909D01*
X1653489Y331700D01*
G01X1654839Y329492D02*
X1655881Y331992D01*
X1656923Y329492D01*
G01X1656548Y330367D02*
X1655214D01*
G01X1658106Y329825D02*
X1658439Y329617D01*
X1658814Y329492D01*
X1659148D01*
X1659481Y329617D01*
X1659731Y329825D01*
X1659856Y330117D01*
X1659773Y330409D01*
X1659564Y330659D01*
X1659189Y330825D01*
X1658689Y330909D01*
X1658398Y331075D01*
X1658273Y331367D01*
X1658356Y331659D01*
X1658564Y331867D01*
X1658856Y331992D01*
X1659148D01*
X1659439Y331909D01*
X1659689Y331700D01*
G01X1661164Y329992D02*
X1661414Y329700D01*
X1661748Y329534D01*
X1662123Y329492D01*
X1662456Y329534D01*
X1662789Y329742D01*
X1662998Y329992D01*
X1663039Y330242D01*
X1662956Y330534D01*
X1662664Y330742D01*
X1662373Y330825D01*
X1661998D01*
G01X1662373D02*
X1662623Y330950D01*
X1662831Y331159D01*
X1662914Y331409D01*
X1662831Y331659D01*
X1662623Y331867D01*
X1662248Y331992D01*
X1661873Y331950D01*
X1661498Y331784D01*
G01X1664264Y329992D02*
X1664514Y329700D01*
X1664848Y329534D01*
X1665223Y329492D01*
X1665556Y329534D01*
X1665889Y329742D01*
X1666098Y329992D01*
X1666139Y330242D01*
X1666056Y330534D01*
X1665764Y330742D01*
X1665473Y330825D01*
X1665098D01*
G01X1665473D02*
X1665723Y330950D01*
X1665931Y331159D01*
X1666014Y331409D01*
X1665931Y331659D01*
X1665723Y331867D01*
X1665348Y331992D01*
X1664973Y331950D01*
X1664598Y331784D01*
G01X1626807Y495017D02*
X1624307D01*
Y496058D01*
X1624432Y496392D01*
X1624599Y496600D01*
X1624932Y496683D01*
X1625265Y496600D01*
X1625474Y496350D01*
X1625599Y496058D01*
Y495017D01*
G01Y496058D02*
X1626807Y496683D01*
G01X1626307Y498033D02*
X1626599Y498283D01*
X1626765Y498617D01*
X1626807Y498992D01*
X1626765Y499325D01*
X1626557Y499658D01*
X1626307Y499867D01*
X1626057Y499908D01*
X1625765Y499825D01*
X1625557Y499533D01*
X1625474Y499242D01*
Y498867D01*
G01Y499242D02*
X1625349Y499492D01*
X1625140Y499700D01*
X1624890Y499783D01*
X1624640Y499700D01*
X1624432Y499492D01*
X1624307Y499117D01*
X1624349Y498742D01*
X1624515Y498367D01*
G01X1626307Y501133D02*
X1626599Y501383D01*
X1626765Y501717D01*
X1626807Y502092D01*
X1626765Y502425D01*
X1626557Y502758D01*
X1626307Y502967D01*
X1626057Y503008D01*
X1625765Y502925D01*
X1625557Y502633D01*
X1625474Y502342D01*
Y501967D01*
G01Y502342D02*
X1625349Y502592D01*
X1625140Y502800D01*
X1624890Y502883D01*
X1624640Y502800D01*
X1624432Y502592D01*
X1624307Y502217D01*
X1624349Y501842D01*
X1624515Y501467D01*
G01X1626807Y505150D02*
X1626765Y505442D01*
X1626640Y505775D01*
X1626432Y505983D01*
X1626140Y506067D01*
X1625849Y505983D01*
X1625599Y505733D01*
X1625474Y505358D01*
Y504942D01*
X1625390Y504692D01*
X1625182Y504483D01*
X1624890Y504400D01*
X1624599Y504525D01*
X1624390Y504817D01*
X1624307Y505150D01*
X1624390Y505483D01*
X1624599Y505775D01*
X1624890Y505900D01*
X1625182Y505817D01*
X1625390Y505608D01*
X1625474Y505358D01*
Y504942D01*
X1625599Y504567D01*
X1625849Y504317D01*
X1626140Y504233D01*
X1626432Y504317D01*
X1626640Y504525D01*
X1626765Y504858D01*
X1626807Y505150D01*
G01X1637431Y674248D02*
X1642481D01*
Y772948D01*
X1667131D01*
Y588548D01*
X1642481D01*
Y647248D01*
X1637431D01*
Y674248D01*
G01X1621938Y699517D02*
Y695517D01*
X1629338D01*
G01X1627807Y948272D02*
X1625307D01*
Y949313D01*
X1625432Y949647D01*
X1625599Y949855D01*
X1625932Y949938D01*
X1626265Y949855D01*
X1626474Y949605D01*
X1626599Y949313D01*
Y948272D01*
G01Y949313D02*
X1627807Y949938D01*
G01X1625724Y951413D02*
X1625474Y951663D01*
X1625349Y951955D01*
X1625307Y952288D01*
X1625390Y952705D01*
X1625599Y952997D01*
X1625849Y953080D01*
X1626099Y953038D01*
X1626307Y952872D01*
X1626724Y952038D01*
X1627015Y951663D01*
X1627432Y951413D01*
X1627807Y951330D01*
Y953080D01*
G01X1626765Y954513D02*
X1626474Y954805D01*
X1626307Y955055D01*
X1626224Y955388D01*
X1626307Y955680D01*
X1626474Y955888D01*
X1626724Y956055D01*
X1627015Y956097D01*
X1627265Y956055D01*
X1627515Y955888D01*
X1627724Y955638D01*
X1627807Y955347D01*
X1627724Y955013D01*
X1627474Y954722D01*
X1627099Y954555D01*
X1626682Y954513D01*
X1626140Y954597D01*
X1625849Y954722D01*
X1625557Y954930D01*
X1625349Y955222D01*
X1625307Y955513D01*
X1625390Y955805D01*
X1625599Y956013D01*
G01X1627807Y958905D02*
X1625307D01*
X1627099Y957363D01*
Y959447D01*
G01X1622807Y948272D02*
X1620307D01*
Y949313D01*
X1620432Y949647D01*
X1620599Y949855D01*
X1620932Y949938D01*
X1621265Y949855D01*
X1621474Y949605D01*
X1621599Y949313D01*
Y948272D01*
G01Y949313D02*
X1622807Y949938D01*
G01X1620724Y951413D02*
X1620474Y951663D01*
X1620349Y951955D01*
X1620307Y952288D01*
X1620390Y952705D01*
X1620599Y952997D01*
X1620849Y953080D01*
X1621099Y953038D01*
X1621307Y952872D01*
X1621724Y952038D01*
X1622015Y951663D01*
X1622432Y951413D01*
X1622807Y951330D01*
Y953080D01*
G01X1621765Y954513D02*
X1621474Y954805D01*
X1621307Y955055D01*
X1621224Y955388D01*
X1621307Y955680D01*
X1621474Y955888D01*
X1621724Y956055D01*
X1622015Y956097D01*
X1622265Y956055D01*
X1622515Y955888D01*
X1622724Y955638D01*
X1622807Y955347D01*
X1622724Y955013D01*
X1622474Y954722D01*
X1622099Y954555D01*
X1621682Y954513D01*
X1621140Y954597D01*
X1620849Y954722D01*
X1620557Y954930D01*
X1620349Y955222D01*
X1620307Y955513D01*
X1620390Y955805D01*
X1620599Y956013D01*
G01X1622307Y957488D02*
X1622599Y957738D01*
X1622765Y958072D01*
X1622807Y958447D01*
X1622765Y958780D01*
X1622557Y959113D01*
X1622307Y959322D01*
X1622057Y959363D01*
X1621765Y959280D01*
X1621557Y958988D01*
X1621474Y958697D01*
Y958322D01*
G01Y958697D02*
X1621349Y958947D01*
X1621140Y959155D01*
X1620890Y959238D01*
X1620640Y959155D01*
X1620432Y958947D01*
X1620307Y958572D01*
X1620349Y958197D01*
X1620515Y957822D01*
G01X1637431Y1127004D02*
X1642481D01*
Y1225704D01*
X1667131D01*
Y1041304D01*
X1642481D01*
Y1100004D01*
X1637431D01*
Y1127004D01*
G01X1629517Y1130500D02*
Y1133000D01*
X1630558D01*
X1630892Y1132875D01*
X1631100Y1132708D01*
X1631183Y1132375D01*
X1631100Y1132042D01*
X1630850Y1131833D01*
X1630558Y1131708D01*
X1629517D01*
G01X1630558D02*
X1631183Y1130500D01*
G01X1632533Y1130875D02*
X1632783Y1130667D01*
X1633075Y1130542D01*
X1633450Y1130500D01*
X1633825Y1130583D01*
X1634117Y1130750D01*
X1634325Y1131042D01*
X1634367Y1131375D01*
X1634283Y1131708D01*
X1634075Y1131917D01*
X1633783Y1132083D01*
X1633492Y1132125D01*
X1633200Y1132083D01*
X1632825Y1131917D01*
X1632950Y1133000D01*
X1634075D01*
G01X1635842Y1130792D02*
X1636133Y1130583D01*
X1636467Y1130500D01*
X1636800Y1130583D01*
X1637092Y1130833D01*
X1637300Y1131208D01*
X1637383Y1131583D01*
Y1132042D01*
X1637300Y1132417D01*
X1637092Y1132750D01*
X1636842Y1132917D01*
X1636550Y1133000D01*
X1636217Y1132917D01*
X1635967Y1132750D01*
X1635800Y1132500D01*
X1635717Y1132167D01*
X1635800Y1131875D01*
X1636008Y1131583D01*
X1636258Y1131417D01*
X1636550Y1131375D01*
X1636883Y1131458D01*
X1637133Y1131667D01*
X1637383Y1132042D01*
G01X1638733Y1131000D02*
X1638983Y1130708D01*
X1639317Y1130542D01*
X1639692Y1130500D01*
X1640025Y1130542D01*
X1640358Y1130750D01*
X1640567Y1131000D01*
X1640608Y1131250D01*
X1640525Y1131542D01*
X1640233Y1131750D01*
X1639942Y1131833D01*
X1639567D01*
G01X1639942D02*
X1640192Y1131958D01*
X1640400Y1132167D01*
X1640483Y1132417D01*
X1640400Y1132667D01*
X1640192Y1132875D01*
X1639817Y1133000D01*
X1639442Y1132958D01*
X1639067Y1132792D01*
G01X1622113Y1130071D02*
Y1126071D01*
X1629513D01*
G01X1622348Y1108754D02*
Y1104754D01*
X1629748D01*
G01X1634334Y1113350D02*
X1634292Y1113017D01*
X1634126Y1112725D01*
X1633876Y1112475D01*
X1633584Y1112308D01*
X1633251Y1112225D01*
X1632917D01*
X1632584Y1112308D01*
X1632292Y1112475D01*
X1632042Y1112725D01*
X1631876Y1113017D01*
X1631834Y1113350D01*
X1631876Y1113683D01*
X1632042Y1113975D01*
X1632292Y1114225D01*
X1632584Y1114392D01*
X1632917Y1114475D01*
X1633251D01*
X1633584Y1114392D01*
X1633876Y1114225D01*
X1634126Y1113975D01*
X1634292Y1113683D01*
X1634334Y1113350D01*
G01X1633667Y1113683D02*
X1634334Y1114183D01*
G01X1632251Y1115658D02*
X1632001Y1115908D01*
X1631876Y1116200D01*
X1631834Y1116533D01*
X1631917Y1116950D01*
X1632126Y1117242D01*
X1632376Y1117325D01*
X1632626Y1117283D01*
X1632834Y1117117D01*
X1633251Y1116283D01*
X1633542Y1115908D01*
X1633959Y1115658D01*
X1634334Y1115575D01*
Y1117325D01*
G01X1634042Y1118842D02*
X1634251Y1119133D01*
X1634334Y1119467D01*
X1634251Y1119800D01*
X1634001Y1120092D01*
X1633626Y1120300D01*
X1633251Y1120383D01*
X1632792D01*
X1632417Y1120300D01*
X1632084Y1120092D01*
X1631917Y1119842D01*
X1631834Y1119550D01*
X1631917Y1119217D01*
X1632084Y1118967D01*
X1632334Y1118800D01*
X1632667Y1118717D01*
X1632959Y1118800D01*
X1633251Y1119008D01*
X1633417Y1119258D01*
X1633459Y1119550D01*
X1633376Y1119883D01*
X1633167Y1120133D01*
X1632792Y1120383D01*
G01X1633292Y1121858D02*
X1633001Y1122150D01*
X1632834Y1122400D01*
X1632751Y1122733D01*
X1632834Y1123025D01*
X1633001Y1123233D01*
X1633251Y1123400D01*
X1633542Y1123442D01*
X1633792Y1123400D01*
X1634042Y1123233D01*
X1634251Y1122983D01*
X1634334Y1122692D01*
X1634251Y1122358D01*
X1634001Y1122067D01*
X1633626Y1121900D01*
X1633209Y1121858D01*
X1632667Y1121942D01*
X1632376Y1122067D01*
X1632084Y1122275D01*
X1631876Y1122567D01*
X1631834Y1122858D01*
X1631917Y1123150D01*
X1632126Y1123358D01*
G01X1630427Y1111199D02*
Y1125199D01*
G01X1629455Y1171773D02*
Y1174273D01*
X1630496D01*
X1630830Y1174148D01*
X1631038Y1173981D01*
X1631121Y1173648D01*
X1631038Y1173315D01*
X1630788Y1173106D01*
X1630496Y1172981D01*
X1629455D01*
G01X1630496D02*
X1631121Y1171773D01*
G01X1632471Y1172273D02*
X1632721Y1171981D01*
X1633055Y1171815D01*
X1633430Y1171773D01*
X1633763Y1171815D01*
X1634096Y1172023D01*
X1634305Y1172273D01*
X1634346Y1172523D01*
X1634263Y1172815D01*
X1633971Y1173023D01*
X1633680Y1173106D01*
X1633305D01*
G01X1633680D02*
X1633930Y1173231D01*
X1634138Y1173440D01*
X1634221Y1173690D01*
X1634138Y1173940D01*
X1633930Y1174148D01*
X1633555Y1174273D01*
X1633180Y1174231D01*
X1632805Y1174065D01*
G01X1635571Y1172273D02*
X1635821Y1171981D01*
X1636155Y1171815D01*
X1636530Y1171773D01*
X1636863Y1171815D01*
X1637196Y1172023D01*
X1637405Y1172273D01*
X1637446Y1172523D01*
X1637363Y1172815D01*
X1637071Y1173023D01*
X1636780Y1173106D01*
X1636405D01*
G01X1636780D02*
X1637030Y1173231D01*
X1637238Y1173440D01*
X1637321Y1173690D01*
X1637238Y1173940D01*
X1637030Y1174148D01*
X1636655Y1174273D01*
X1636280Y1174231D01*
X1635905Y1174065D01*
G01X1639505Y1171773D02*
X1639588Y1172315D01*
X1639713Y1172773D01*
X1639880Y1173190D01*
X1640088Y1173648D01*
X1640421Y1174273D01*
X1638755D01*
G01X1633738Y1152273D02*
Y1148273D01*
X1641138D01*
G01X1629821Y1135317D02*
Y1149317D01*
G01X1624000Y1180350D02*
X1626500D01*
G01X1624000Y1179392D02*
Y1181308D01*
G01X1626500Y1182617D02*
X1624000D01*
Y1183617D01*
X1624125Y1183950D01*
X1624417Y1184200D01*
X1624750Y1184283D01*
X1625083Y1184200D01*
X1625333Y1183992D01*
X1625458Y1183617D01*
Y1182617D01*
G01X1626500Y1187050D02*
X1624000D01*
X1625792Y1185508D01*
Y1187592D01*
G01X1626500Y1189567D02*
X1625958Y1189650D01*
X1625500Y1189775D01*
X1625083Y1189942D01*
X1624625Y1190150D01*
X1624000Y1190483D01*
Y1188817D01*
G01X1629517Y1175500D02*
Y1178000D01*
X1630558D01*
X1630892Y1177875D01*
X1631100Y1177708D01*
X1631183Y1177375D01*
X1631100Y1177042D01*
X1630850Y1176833D01*
X1630558Y1176708D01*
X1629517D01*
G01X1630558D02*
X1631183Y1175500D01*
G01X1632533Y1176000D02*
X1632783Y1175708D01*
X1633117Y1175542D01*
X1633492Y1175500D01*
X1633825Y1175542D01*
X1634158Y1175750D01*
X1634367Y1176000D01*
X1634408Y1176250D01*
X1634325Y1176542D01*
X1634033Y1176750D01*
X1633742Y1176833D01*
X1633367D01*
G01X1633742D02*
X1633992Y1176958D01*
X1634200Y1177167D01*
X1634283Y1177417D01*
X1634200Y1177667D01*
X1633992Y1177875D01*
X1633617Y1178000D01*
X1633242Y1177958D01*
X1632867Y1177792D01*
G01X1637050Y1175500D02*
Y1178000D01*
X1635508Y1176208D01*
X1637592D01*
G01X1639650Y1175500D02*
Y1178000D01*
X1639150Y1177500D01*
G01Y1175500D02*
X1640150D01*
G01X1631205Y1169965D02*
X1630955Y1170090D01*
X1630663Y1170173D01*
X1630330D01*
X1629955Y1170048D01*
X1629663Y1169840D01*
X1629455Y1169590D01*
X1629288Y1169173D01*
X1629246Y1168798D01*
X1629330Y1168423D01*
X1629455Y1168173D01*
X1629705Y1167923D01*
X1629996Y1167756D01*
X1630288Y1167673D01*
X1630580D01*
X1630871Y1167756D01*
X1631121Y1167881D01*
X1631330Y1168048D01*
G01X1633388Y1167673D02*
Y1170173D01*
X1632888Y1169673D01*
G01Y1167673D02*
X1633888D01*
G01X1635696Y1168715D02*
X1635988Y1169006D01*
X1636238Y1169173D01*
X1636571Y1169256D01*
X1636863Y1169173D01*
X1637071Y1169006D01*
X1637238Y1168756D01*
X1637280Y1168465D01*
X1637238Y1168215D01*
X1637071Y1167965D01*
X1636821Y1167756D01*
X1636530Y1167673D01*
X1636196Y1167756D01*
X1635905Y1168006D01*
X1635738Y1168381D01*
X1635696Y1168798D01*
X1635780Y1169340D01*
X1635905Y1169631D01*
X1636113Y1169923D01*
X1636405Y1170131D01*
X1636696Y1170173D01*
X1636988Y1170090D01*
X1637196Y1169881D01*
G01X1638671Y1168173D02*
X1638921Y1167881D01*
X1639255Y1167715D01*
X1639630Y1167673D01*
X1639963Y1167715D01*
X1640296Y1167923D01*
X1640505Y1168173D01*
X1640546Y1168423D01*
X1640463Y1168715D01*
X1640171Y1168923D01*
X1639880Y1169006D01*
X1639505D01*
G01X1639880D02*
X1640130Y1169131D01*
X1640338Y1169340D01*
X1640421Y1169590D01*
X1640338Y1169840D01*
X1640130Y1170048D01*
X1639755Y1170173D01*
X1639380Y1170131D01*
X1639005Y1169965D01*
G01X1644325Y1232500D02*
Y1235000D01*
G01X1646075D02*
Y1232500D01*
G01Y1233750D02*
X1644325D01*
G01X1647383Y1232500D02*
Y1235000D01*
X1648217D01*
X1648550Y1234875D01*
X1648800Y1234708D01*
X1649008Y1234458D01*
X1649175Y1234167D01*
X1649217Y1233750D01*
X1649175Y1233333D01*
X1649008Y1233042D01*
X1648800Y1232792D01*
X1648550Y1232625D01*
X1648217Y1232500D01*
X1647383D01*
G01X1650483D02*
Y1235000D01*
X1651317D01*
X1651650Y1234875D01*
X1651900Y1234708D01*
X1652108Y1234458D01*
X1652275Y1234167D01*
X1652317Y1233750D01*
X1652275Y1233333D01*
X1652108Y1233042D01*
X1651900Y1232792D01*
X1651650Y1232625D01*
X1651317Y1232500D01*
X1650483D01*
G01X1653625Y1232833D02*
X1653958Y1232625D01*
X1654333Y1232500D01*
X1654667D01*
X1655000Y1232625D01*
X1655250Y1232833D01*
X1655375Y1233125D01*
X1655292Y1233417D01*
X1655083Y1233667D01*
X1654708Y1233833D01*
X1654208Y1233917D01*
X1653917Y1234083D01*
X1653792Y1234375D01*
X1653875Y1234667D01*
X1654083Y1234875D01*
X1654375Y1235000D01*
X1654667D01*
X1654958Y1234917D01*
X1655208Y1234708D01*
G01X1656558Y1232500D02*
X1657600Y1235000D01*
X1658642Y1232500D01*
G01X1658267Y1233375D02*
X1656933D01*
G01X1659825Y1232833D02*
X1660158Y1232625D01*
X1660533Y1232500D01*
X1660867D01*
X1661200Y1232625D01*
X1661450Y1232833D01*
X1661575Y1233125D01*
X1661492Y1233417D01*
X1661283Y1233667D01*
X1660908Y1233833D01*
X1660408Y1233917D01*
X1660117Y1234083D01*
X1659992Y1234375D01*
X1660075Y1234667D01*
X1660283Y1234875D01*
X1660575Y1235000D01*
X1660867D01*
X1661158Y1234917D01*
X1661408Y1234708D01*
G01X1663092Y1232792D02*
X1663383Y1232583D01*
X1663717Y1232500D01*
X1664050Y1232583D01*
X1664342Y1232833D01*
X1664550Y1233208D01*
X1664633Y1233583D01*
Y1234042D01*
X1664550Y1234417D01*
X1664342Y1234750D01*
X1664092Y1234917D01*
X1663800Y1235000D01*
X1663467Y1234917D01*
X1663217Y1234750D01*
X1663050Y1234500D01*
X1662967Y1234167D01*
X1663050Y1233875D01*
X1663258Y1233583D01*
X1663508Y1233417D01*
X1663800Y1233375D01*
X1664133Y1233458D01*
X1664383Y1233667D01*
X1664633Y1234042D01*
G01X1626041Y1654695D02*
X1626508Y1655161D01*
X1626908Y1655428D01*
X1627441Y1655561D01*
X1627908Y1655428D01*
X1628241Y1655161D01*
X1628508Y1654761D01*
X1628575Y1654295D01*
X1628508Y1653895D01*
X1628241Y1653495D01*
X1627841Y1653161D01*
X1627375Y1653028D01*
X1626841Y1653161D01*
X1626375Y1653561D01*
X1626108Y1654161D01*
X1626041Y1654828D01*
X1626175Y1655695D01*
X1626375Y1656161D01*
X1626708Y1656628D01*
X1627175Y1656961D01*
X1627641Y1657028D01*
X1628108Y1656895D01*
X1628441Y1656561D01*
G01X1686138Y149678D02*
X1683638D01*
Y150719D01*
X1683763Y151053D01*
X1683930Y151261D01*
X1684263Y151344D01*
X1684596Y151261D01*
X1684805Y151011D01*
X1684930Y150719D01*
Y149678D01*
G01Y150719D02*
X1686138Y151344D01*
G01Y153611D02*
X1686096Y153903D01*
X1685971Y154236D01*
X1685763Y154444D01*
X1685471Y154528D01*
X1685180Y154444D01*
X1684930Y154194D01*
X1684805Y153819D01*
Y153403D01*
X1684721Y153153D01*
X1684513Y152944D01*
X1684221Y152861D01*
X1683930Y152986D01*
X1683721Y153278D01*
X1683638Y153611D01*
X1683721Y153944D01*
X1683930Y154236D01*
X1684221Y154361D01*
X1684513Y154278D01*
X1684721Y154069D01*
X1684805Y153819D01*
Y153403D01*
X1684930Y153028D01*
X1685180Y152778D01*
X1685471Y152694D01*
X1685763Y152778D01*
X1685971Y152986D01*
X1686096Y153319D01*
X1686138Y153611D01*
G01X1685846Y156003D02*
X1686055Y156294D01*
X1686138Y156628D01*
X1686055Y156961D01*
X1685805Y157253D01*
X1685430Y157461D01*
X1685055Y157544D01*
X1684596D01*
X1684221Y157461D01*
X1683888Y157253D01*
X1683721Y157003D01*
X1683638Y156711D01*
X1683721Y156378D01*
X1683888Y156128D01*
X1684138Y155961D01*
X1684471Y155878D01*
X1684763Y155961D01*
X1685055Y156169D01*
X1685221Y156419D01*
X1685263Y156711D01*
X1685180Y157044D01*
X1684971Y157294D01*
X1684596Y157544D01*
G01X1686138Y159728D02*
X1685596Y159811D01*
X1685138Y159936D01*
X1684721Y160103D01*
X1684263Y160311D01*
X1683638Y160644D01*
Y158978D01*
G01X1682638Y163961D02*
X1686638D01*
Y171361D01*
G01X1696000Y150017D02*
X1693500D01*
Y151058D01*
X1693625Y151392D01*
X1693792Y151600D01*
X1694125Y151683D01*
X1694458Y151600D01*
X1694667Y151350D01*
X1694792Y151058D01*
Y150017D01*
G01Y151058D02*
X1696000Y151683D01*
G01Y153950D02*
X1695958Y154242D01*
X1695833Y154575D01*
X1695625Y154783D01*
X1695333Y154867D01*
X1695042Y154783D01*
X1694792Y154533D01*
X1694667Y154158D01*
Y153742D01*
X1694583Y153492D01*
X1694375Y153283D01*
X1694083Y153200D01*
X1693792Y153325D01*
X1693583Y153617D01*
X1693500Y153950D01*
X1693583Y154283D01*
X1693792Y154575D01*
X1694083Y154700D01*
X1694375Y154617D01*
X1694583Y154408D01*
X1694667Y154158D01*
Y153742D01*
X1694792Y153367D01*
X1695042Y153117D01*
X1695333Y153033D01*
X1695625Y153117D01*
X1695833Y153325D01*
X1695958Y153658D01*
X1696000Y153950D01*
G01X1695708Y156342D02*
X1695917Y156633D01*
X1696000Y156967D01*
X1695917Y157300D01*
X1695667Y157592D01*
X1695292Y157800D01*
X1694917Y157883D01*
X1694458D01*
X1694083Y157800D01*
X1693750Y157592D01*
X1693583Y157342D01*
X1693500Y157050D01*
X1693583Y156717D01*
X1693750Y156467D01*
X1694000Y156300D01*
X1694333Y156217D01*
X1694625Y156300D01*
X1694917Y156508D01*
X1695083Y156758D01*
X1695125Y157050D01*
X1695042Y157383D01*
X1694833Y157633D01*
X1694458Y157883D01*
G01X1695708Y159442D02*
X1695917Y159733D01*
X1696000Y160067D01*
X1695917Y160400D01*
X1695667Y160692D01*
X1695292Y160900D01*
X1694917Y160983D01*
X1694458D01*
X1694083Y160900D01*
X1693750Y160692D01*
X1693583Y160442D01*
X1693500Y160150D01*
X1693583Y159817D01*
X1693750Y159567D01*
X1694000Y159400D01*
X1694333Y159317D01*
X1694625Y159400D01*
X1694917Y159608D01*
X1695083Y159858D01*
X1695125Y160150D01*
X1695042Y160483D01*
X1694833Y160733D01*
X1694458Y160983D01*
G01X1692638Y163961D02*
X1696638D01*
Y171361D01*
G01X1681638Y149678D02*
X1679138D01*
Y150719D01*
X1679263Y151053D01*
X1679430Y151261D01*
X1679763Y151344D01*
X1680096Y151261D01*
X1680305Y151011D01*
X1680430Y150719D01*
Y149678D01*
G01Y150719D02*
X1681638Y151344D01*
G01X1681346Y152903D02*
X1681555Y153194D01*
X1681638Y153528D01*
X1681555Y153861D01*
X1681305Y154153D01*
X1680930Y154361D01*
X1680555Y154444D01*
X1680096D01*
X1679721Y154361D01*
X1679388Y154153D01*
X1679221Y153903D01*
X1679138Y153611D01*
X1679221Y153278D01*
X1679388Y153028D01*
X1679638Y152861D01*
X1679971Y152778D01*
X1680263Y152861D01*
X1680555Y153069D01*
X1680721Y153319D01*
X1680763Y153611D01*
X1680680Y153944D01*
X1680471Y154194D01*
X1680096Y154444D01*
G01X1679138Y156711D02*
X1679221Y156378D01*
X1679430Y156128D01*
X1679680Y155961D01*
X1680013Y155836D01*
X1680388Y155794D01*
X1680763Y155836D01*
X1681096Y155961D01*
X1681346Y156128D01*
X1681555Y156378D01*
X1681638Y156711D01*
X1681555Y157044D01*
X1681346Y157294D01*
X1681096Y157461D01*
X1680763Y157586D01*
X1680388Y157628D01*
X1680013Y157586D01*
X1679680Y157461D01*
X1679430Y157294D01*
X1679221Y157044D01*
X1679138Y156711D01*
G01X1681638Y159811D02*
X1679138D01*
X1679638Y159311D01*
G01X1681638D02*
Y160311D01*
G01X1682138Y171361D02*
X1678138D01*
Y163961D01*
G01X1713155Y189161D02*
Y191661D01*
X1714196D01*
X1714530Y191536D01*
X1714738Y191369D01*
X1714821Y191036D01*
X1714738Y190703D01*
X1714488Y190494D01*
X1714196Y190369D01*
X1713155D01*
G01X1714196D02*
X1714821Y189161D01*
G01X1717088D02*
X1717380Y189203D01*
X1717713Y189328D01*
X1717921Y189536D01*
X1718005Y189828D01*
X1717921Y190119D01*
X1717671Y190369D01*
X1717296Y190494D01*
X1716880D01*
X1716630Y190578D01*
X1716421Y190786D01*
X1716338Y191078D01*
X1716463Y191369D01*
X1716755Y191578D01*
X1717088Y191661D01*
X1717421Y191578D01*
X1717713Y191369D01*
X1717838Y191078D01*
X1717755Y190786D01*
X1717546Y190578D01*
X1717296Y190494D01*
X1716880D01*
X1716505Y190369D01*
X1716255Y190119D01*
X1716171Y189828D01*
X1716255Y189536D01*
X1716463Y189328D01*
X1716796Y189203D01*
X1717088Y189161D01*
G01X1719480Y189453D02*
X1719771Y189244D01*
X1720105Y189161D01*
X1720438Y189244D01*
X1720730Y189494D01*
X1720938Y189869D01*
X1721021Y190244D01*
Y190703D01*
X1720938Y191078D01*
X1720730Y191411D01*
X1720480Y191578D01*
X1720188Y191661D01*
X1719855Y191578D01*
X1719605Y191411D01*
X1719438Y191161D01*
X1719355Y190828D01*
X1719438Y190536D01*
X1719646Y190244D01*
X1719896Y190078D01*
X1720188Y190036D01*
X1720521Y190119D01*
X1720771Y190328D01*
X1721021Y190703D01*
G01X1722496Y190203D02*
X1722788Y190494D01*
X1723038Y190661D01*
X1723371Y190744D01*
X1723663Y190661D01*
X1723871Y190494D01*
X1724038Y190244D01*
X1724080Y189953D01*
X1724038Y189703D01*
X1723871Y189453D01*
X1723621Y189244D01*
X1723330Y189161D01*
X1722996Y189244D01*
X1722705Y189494D01*
X1722538Y189869D01*
X1722496Y190286D01*
X1722580Y190828D01*
X1722705Y191119D01*
X1722913Y191411D01*
X1723205Y191619D01*
X1723496Y191661D01*
X1723788Y191578D01*
X1723996Y191369D01*
G01X1686338Y189161D02*
Y193161D01*
X1678938D01*
G01X1709138Y172078D02*
X1706638D01*
Y173119D01*
X1706763Y173453D01*
X1706930Y173661D01*
X1707263Y173744D01*
X1707596Y173661D01*
X1707805Y173411D01*
X1707930Y173119D01*
Y172078D01*
G01Y173119D02*
X1709138Y173744D01*
G01X1708846Y175303D02*
X1709055Y175594D01*
X1709138Y175928D01*
X1709055Y176261D01*
X1708805Y176553D01*
X1708430Y176761D01*
X1708055Y176844D01*
X1707596D01*
X1707221Y176761D01*
X1706888Y176553D01*
X1706721Y176303D01*
X1706638Y176011D01*
X1706721Y175678D01*
X1706888Y175428D01*
X1707138Y175261D01*
X1707471Y175178D01*
X1707763Y175261D01*
X1708055Y175469D01*
X1708221Y175719D01*
X1708263Y176011D01*
X1708180Y176344D01*
X1707971Y176594D01*
X1707596Y176844D01*
G01X1706638Y179111D02*
X1706721Y178778D01*
X1706930Y178528D01*
X1707180Y178361D01*
X1707513Y178236D01*
X1707888Y178194D01*
X1708263Y178236D01*
X1708596Y178361D01*
X1708846Y178528D01*
X1709055Y178778D01*
X1709138Y179111D01*
X1709055Y179444D01*
X1708846Y179694D01*
X1708596Y179861D01*
X1708263Y179986D01*
X1707888Y180028D01*
X1707513Y179986D01*
X1707180Y179861D01*
X1706930Y179694D01*
X1706721Y179444D01*
X1706638Y179111D01*
G01X1707055Y181419D02*
X1706805Y181669D01*
X1706680Y181961D01*
X1706638Y182294D01*
X1706721Y182711D01*
X1706930Y183003D01*
X1707180Y183086D01*
X1707430Y183044D01*
X1707638Y182878D01*
X1708055Y182044D01*
X1708346Y181669D01*
X1708763Y181419D01*
X1709138Y181336D01*
Y183086D01*
G01X1697138Y176361D02*
X1701138D01*
Y183761D01*
G01X1699938Y196661D02*
Y192661D01*
X1707338D01*
G01X1704438Y172078D02*
X1701938D01*
Y173119D01*
X1702063Y173453D01*
X1702230Y173661D01*
X1702563Y173744D01*
X1702896Y173661D01*
X1703105Y173411D01*
X1703230Y173119D01*
Y172078D01*
G01Y173119D02*
X1704438Y173744D01*
G01X1704146Y175303D02*
X1704355Y175594D01*
X1704438Y175928D01*
X1704355Y176261D01*
X1704105Y176553D01*
X1703730Y176761D01*
X1703355Y176844D01*
X1702896D01*
X1702521Y176761D01*
X1702188Y176553D01*
X1702021Y176303D01*
X1701938Y176011D01*
X1702021Y175678D01*
X1702188Y175428D01*
X1702438Y175261D01*
X1702771Y175178D01*
X1703063Y175261D01*
X1703355Y175469D01*
X1703521Y175719D01*
X1703563Y176011D01*
X1703480Y176344D01*
X1703271Y176594D01*
X1702896Y176844D01*
G01X1701938Y179111D02*
X1702021Y178778D01*
X1702230Y178528D01*
X1702480Y178361D01*
X1702813Y178236D01*
X1703188Y178194D01*
X1703563Y178236D01*
X1703896Y178361D01*
X1704146Y178528D01*
X1704355Y178778D01*
X1704438Y179111D01*
X1704355Y179444D01*
X1704146Y179694D01*
X1703896Y179861D01*
X1703563Y179986D01*
X1703188Y180028D01*
X1702813Y179986D01*
X1702480Y179861D01*
X1702230Y179694D01*
X1702021Y179444D01*
X1701938Y179111D01*
G01X1703396Y181419D02*
X1703105Y181711D01*
X1702938Y181961D01*
X1702855Y182294D01*
X1702938Y182586D01*
X1703105Y182794D01*
X1703355Y182961D01*
X1703646Y183003D01*
X1703896Y182961D01*
X1704146Y182794D01*
X1704355Y182544D01*
X1704438Y182253D01*
X1704355Y181919D01*
X1704105Y181628D01*
X1703730Y181461D01*
X1703313Y181419D01*
X1702771Y181503D01*
X1702480Y181628D01*
X1702188Y181836D01*
X1701980Y182128D01*
X1701938Y182419D01*
X1702021Y182711D01*
X1702230Y182919D01*
G01X1692438Y176361D02*
X1696438D01*
Y183761D01*
G01X1672000Y174350D02*
X1671958Y174017D01*
X1671792Y173725D01*
X1671542Y173475D01*
X1671250Y173308D01*
X1670917Y173225D01*
X1670583D01*
X1670250Y173308D01*
X1669958Y173475D01*
X1669708Y173725D01*
X1669542Y174017D01*
X1669500Y174350D01*
X1669542Y174683D01*
X1669708Y174975D01*
X1669958Y175225D01*
X1670250Y175392D01*
X1670583Y175475D01*
X1670917D01*
X1671250Y175392D01*
X1671542Y175225D01*
X1671792Y174975D01*
X1671958Y174683D01*
X1672000Y174350D01*
G01X1671333Y174683D02*
X1672000Y175183D01*
G01Y177450D02*
X1669500D01*
X1670000Y176950D01*
G01X1672000D02*
Y177950D01*
G01X1671708Y179842D02*
X1671917Y180133D01*
X1672000Y180467D01*
X1671917Y180800D01*
X1671667Y181092D01*
X1671292Y181300D01*
X1670917Y181383D01*
X1670458D01*
X1670083Y181300D01*
X1669750Y181092D01*
X1669583Y180842D01*
X1669500Y180550D01*
X1669583Y180217D01*
X1669750Y179967D01*
X1670000Y179800D01*
X1670333Y179717D01*
X1670625Y179800D01*
X1670917Y180008D01*
X1671083Y180258D01*
X1671125Y180550D01*
X1671042Y180883D01*
X1670833Y181133D01*
X1670458Y181383D01*
G01X1671708Y182942D02*
X1671917Y183233D01*
X1672000Y183567D01*
X1671917Y183900D01*
X1671667Y184192D01*
X1671292Y184400D01*
X1670917Y184483D01*
X1670458D01*
X1670083Y184400D01*
X1669750Y184192D01*
X1669583Y183942D01*
X1669500Y183650D01*
X1669583Y183317D01*
X1669750Y183067D01*
X1670000Y182900D01*
X1670333Y182817D01*
X1670625Y182900D01*
X1670917Y183108D01*
X1671083Y183358D01*
X1671125Y183650D01*
X1671042Y183983D01*
X1670833Y184233D01*
X1670458Y184483D01*
G01X1673438Y183861D02*
Y172461D01*
G01X1686838Y183861D02*
X1673438D01*
G01X1686838Y172461D02*
Y183861D01*
G01X1673438Y172461D02*
X1686838D01*
G01X1709138Y184661D02*
X1693038D01*
G01X1709138Y191661D02*
Y184661D01*
G01X1693038Y191661D02*
X1709138D01*
G01X1693038Y184661D02*
Y191661D01*
G01X1685538Y218961D02*
Y199761D01*
X1696738D01*
Y218961D01*
X1685538D01*
Y218561D01*
G01X1714905Y195553D02*
X1714655Y195678D01*
X1714363Y195761D01*
X1714030D01*
X1713655Y195636D01*
X1713363Y195428D01*
X1713155Y195178D01*
X1712988Y194761D01*
X1712946Y194386D01*
X1713030Y194011D01*
X1713155Y193761D01*
X1713405Y193511D01*
X1713696Y193344D01*
X1713988Y193261D01*
X1714280D01*
X1714571Y193344D01*
X1714821Y193469D01*
X1715030Y193636D01*
G01X1717588Y193261D02*
Y195761D01*
X1716046Y193969D01*
X1718130D01*
G01X1720105Y193261D02*
X1720188Y193803D01*
X1720313Y194261D01*
X1720480Y194678D01*
X1720688Y195136D01*
X1721021Y195761D01*
X1719355D01*
G01X1723205Y193261D02*
X1723288Y193803D01*
X1723413Y194261D01*
X1723580Y194678D01*
X1723788Y195136D01*
X1724121Y195761D01*
X1722455D01*
G01X1711655Y222161D02*
Y224661D01*
X1712696D01*
X1713030Y224536D01*
X1713238Y224369D01*
X1713321Y224036D01*
X1713238Y223703D01*
X1712988Y223494D01*
X1712696Y223369D01*
X1711655D01*
G01X1712696D02*
X1713321Y222161D01*
G01X1714880Y222453D02*
X1715171Y222244D01*
X1715505Y222161D01*
X1715838Y222244D01*
X1716130Y222494D01*
X1716338Y222869D01*
X1716421Y223244D01*
Y223703D01*
X1716338Y224078D01*
X1716130Y224411D01*
X1715880Y224578D01*
X1715588Y224661D01*
X1715255Y224578D01*
X1715005Y224411D01*
X1714838Y224161D01*
X1714755Y223828D01*
X1714838Y223536D01*
X1715046Y223244D01*
X1715296Y223078D01*
X1715588Y223036D01*
X1715921Y223119D01*
X1716171Y223328D01*
X1716421Y223703D01*
G01X1718688Y224661D02*
X1718355Y224578D01*
X1718105Y224369D01*
X1717938Y224119D01*
X1717813Y223786D01*
X1717771Y223411D01*
X1717813Y223036D01*
X1717938Y222703D01*
X1718105Y222453D01*
X1718355Y222244D01*
X1718688Y222161D01*
X1719021Y222244D01*
X1719271Y222453D01*
X1719438Y222703D01*
X1719563Y223036D01*
X1719605Y223411D01*
X1719563Y223786D01*
X1719438Y224119D01*
X1719271Y224369D01*
X1719021Y224578D01*
X1718688Y224661D01*
G01X1720871Y222661D02*
X1721121Y222369D01*
X1721455Y222203D01*
X1721830Y222161D01*
X1722163Y222203D01*
X1722496Y222411D01*
X1722705Y222661D01*
X1722746Y222911D01*
X1722663Y223203D01*
X1722371Y223411D01*
X1722080Y223494D01*
X1721705D01*
G01X1722080D02*
X1722330Y223619D01*
X1722538Y223828D01*
X1722621Y224078D01*
X1722538Y224328D01*
X1722330Y224536D01*
X1721955Y224661D01*
X1721580Y224619D01*
X1721205Y224453D01*
G01X1709838Y221661D02*
Y225661D01*
X1702438D01*
G01X1672517Y233000D02*
Y235500D01*
X1673558D01*
X1673892Y235375D01*
X1674100Y235208D01*
X1674183Y234875D01*
X1674100Y234542D01*
X1673850Y234333D01*
X1673558Y234208D01*
X1672517D01*
G01X1673558D02*
X1674183Y233000D01*
G01X1676450D02*
X1676742Y233042D01*
X1677075Y233167D01*
X1677283Y233375D01*
X1677367Y233667D01*
X1677283Y233958D01*
X1677033Y234208D01*
X1676658Y234333D01*
X1676242D01*
X1675992Y234417D01*
X1675783Y234625D01*
X1675700Y234917D01*
X1675825Y235208D01*
X1676117Y235417D01*
X1676450Y235500D01*
X1676783Y235417D01*
X1677075Y235208D01*
X1677200Y234917D01*
X1677117Y234625D01*
X1676908Y234417D01*
X1676658Y234333D01*
X1676242D01*
X1675867Y234208D01*
X1675617Y233958D01*
X1675533Y233667D01*
X1675617Y233375D01*
X1675825Y233167D01*
X1676158Y233042D01*
X1676450Y233000D01*
G01X1679550D02*
X1679842Y233042D01*
X1680175Y233167D01*
X1680383Y233375D01*
X1680467Y233667D01*
X1680383Y233958D01*
X1680133Y234208D01*
X1679758Y234333D01*
X1679342D01*
X1679092Y234417D01*
X1678883Y234625D01*
X1678800Y234917D01*
X1678925Y235208D01*
X1679217Y235417D01*
X1679550Y235500D01*
X1679883Y235417D01*
X1680175Y235208D01*
X1680300Y234917D01*
X1680217Y234625D01*
X1680008Y234417D01*
X1679758Y234333D01*
X1679342D01*
X1678967Y234208D01*
X1678717Y233958D01*
X1678633Y233667D01*
X1678717Y233375D01*
X1678925Y233167D01*
X1679258Y233042D01*
X1679550Y233000D01*
G01X1682650D02*
X1682942Y233042D01*
X1683275Y233167D01*
X1683483Y233375D01*
X1683567Y233667D01*
X1683483Y233958D01*
X1683233Y234208D01*
X1682858Y234333D01*
X1682442D01*
X1682192Y234417D01*
X1681983Y234625D01*
X1681900Y234917D01*
X1682025Y235208D01*
X1682317Y235417D01*
X1682650Y235500D01*
X1682983Y235417D01*
X1683275Y235208D01*
X1683400Y234917D01*
X1683317Y234625D01*
X1683108Y234417D01*
X1682858Y234333D01*
X1682442D01*
X1682067Y234208D01*
X1681817Y233958D01*
X1681733Y233667D01*
X1681817Y233375D01*
X1682025Y233167D01*
X1682358Y233042D01*
X1682650Y233000D01*
G01X1686438Y244661D02*
Y236661D01*
X1668838D01*
Y244661D01*
X1686438D01*
G01X1673708Y247767D02*
X1673583Y247517D01*
X1673500Y247225D01*
Y246892D01*
X1673625Y246517D01*
X1673833Y246225D01*
X1674083Y246017D01*
X1674500Y245850D01*
X1674875Y245808D01*
X1675250Y245892D01*
X1675500Y246017D01*
X1675750Y246267D01*
X1675917Y246558D01*
X1676000Y246850D01*
Y247142D01*
X1675917Y247433D01*
X1675792Y247683D01*
X1675625Y247892D01*
G01X1676000Y250450D02*
X1673500D01*
X1675292Y248908D01*
Y250992D01*
G01X1676000Y252967D02*
X1675458Y253050D01*
X1675000Y253175D01*
X1674583Y253342D01*
X1674125Y253550D01*
X1673500Y253883D01*
Y252217D01*
G01Y256150D02*
X1673583Y255817D01*
X1673792Y255567D01*
X1674042Y255400D01*
X1674375Y255275D01*
X1674750Y255233D01*
X1675125Y255275D01*
X1675458Y255400D01*
X1675708Y255567D01*
X1675917Y255817D01*
X1676000Y256150D01*
X1675917Y256483D01*
X1675708Y256733D01*
X1675458Y256900D01*
X1675125Y257025D01*
X1674750Y257067D01*
X1674375Y257025D01*
X1674042Y256900D01*
X1673792Y256733D01*
X1673583Y256483D01*
X1673500Y256150D01*
G01X1677138Y250361D02*
Y255861D01*
G01X1685138Y250361D02*
X1677138D01*
G01X1685138Y255861D02*
Y250361D01*
G01X1713000Y238350D02*
X1712958Y238017D01*
X1712792Y237725D01*
X1712542Y237475D01*
X1712250Y237308D01*
X1711917Y237225D01*
X1711583D01*
X1711250Y237308D01*
X1710958Y237475D01*
X1710708Y237725D01*
X1710542Y238017D01*
X1710500Y238350D01*
X1710542Y238683D01*
X1710708Y238975D01*
X1710958Y239225D01*
X1711250Y239392D01*
X1711583Y239475D01*
X1711917D01*
X1712250Y239392D01*
X1712542Y239225D01*
X1712792Y238975D01*
X1712958Y238683D01*
X1713000Y238350D01*
G01X1712333Y238683D02*
X1713000Y239183D01*
G01X1710917Y240658D02*
X1710667Y240908D01*
X1710542Y241200D01*
X1710500Y241533D01*
X1710583Y241950D01*
X1710792Y242242D01*
X1711042Y242325D01*
X1711292Y242283D01*
X1711500Y242117D01*
X1711917Y241283D01*
X1712208Y240908D01*
X1712625Y240658D01*
X1713000Y240575D01*
Y242325D01*
G01X1710500Y244550D02*
X1710583Y244217D01*
X1710792Y243967D01*
X1711042Y243800D01*
X1711375Y243675D01*
X1711750Y243633D01*
X1712125Y243675D01*
X1712458Y243800D01*
X1712708Y243967D01*
X1712917Y244217D01*
X1713000Y244550D01*
X1712917Y244883D01*
X1712708Y245133D01*
X1712458Y245300D01*
X1712125Y245425D01*
X1711750Y245467D01*
X1711375Y245425D01*
X1711042Y245300D01*
X1710792Y245133D01*
X1710583Y244883D01*
X1710500Y244550D01*
G01Y247650D02*
X1710583Y247317D01*
X1710792Y247067D01*
X1711042Y246900D01*
X1711375Y246775D01*
X1711750Y246733D01*
X1712125Y246775D01*
X1712458Y246900D01*
X1712708Y247067D01*
X1712917Y247317D01*
X1713000Y247650D01*
X1712917Y247983D01*
X1712708Y248233D01*
X1712458Y248400D01*
X1712125Y248525D01*
X1711750Y248567D01*
X1711375Y248525D01*
X1711042Y248400D01*
X1710792Y248233D01*
X1710583Y247983D01*
X1710500Y247650D01*
G01X1687938Y246161D02*
X1690038Y244361D01*
X1687938Y242161D01*
G01X1687838Y238561D02*
X1707038D01*
Y249761D01*
X1687838D01*
Y238561D01*
X1688238D01*
G01X1677850Y220500D02*
X1677517Y220542D01*
X1677225Y220708D01*
X1676975Y220958D01*
X1676808Y221250D01*
X1676725Y221583D01*
Y221917D01*
X1676808Y222250D01*
X1676975Y222542D01*
X1677225Y222792D01*
X1677517Y222958D01*
X1677850Y223000D01*
X1678183Y222958D01*
X1678475Y222792D01*
X1678725Y222542D01*
X1678892Y222250D01*
X1678975Y221917D01*
Y221583D01*
X1678892Y221250D01*
X1678725Y220958D01*
X1678475Y220708D01*
X1678183Y220542D01*
X1677850Y220500D01*
G01X1678183Y221167D02*
X1678683Y220500D01*
G01X1680950D02*
Y223000D01*
X1680450Y222500D01*
G01Y220500D02*
X1681450D01*
G01X1683342Y220792D02*
X1683633Y220583D01*
X1683967Y220500D01*
X1684300Y220583D01*
X1684592Y220833D01*
X1684800Y221208D01*
X1684883Y221583D01*
Y222042D01*
X1684800Y222417D01*
X1684592Y222750D01*
X1684342Y222917D01*
X1684050Y223000D01*
X1683717Y222917D01*
X1683467Y222750D01*
X1683300Y222500D01*
X1683217Y222167D01*
X1683300Y221875D01*
X1683508Y221583D01*
X1683758Y221417D01*
X1684050Y221375D01*
X1684383Y221458D01*
X1684633Y221667D01*
X1684883Y222042D01*
G01X1687067Y220500D02*
X1687150Y221042D01*
X1687275Y221500D01*
X1687442Y221917D01*
X1687650Y222375D01*
X1687983Y223000D01*
X1686317D01*
G01X1693138Y218861D02*
X1691338Y216761D01*
X1689138Y218861D01*
G01X1713405Y228553D02*
X1713155Y228678D01*
X1712863Y228761D01*
X1712530D01*
X1712155Y228636D01*
X1711863Y228428D01*
X1711655Y228178D01*
X1711488Y227761D01*
X1711446Y227386D01*
X1711530Y227011D01*
X1711655Y226761D01*
X1711905Y226511D01*
X1712196Y226344D01*
X1712488Y226261D01*
X1712780D01*
X1713071Y226344D01*
X1713321Y226469D01*
X1713530Y226636D01*
G01X1716088Y226261D02*
Y228761D01*
X1714546Y226969D01*
X1716630D01*
G01X1718605Y226261D02*
X1718688Y226803D01*
X1718813Y227261D01*
X1718980Y227678D01*
X1719188Y228136D01*
X1719521Y228761D01*
X1717855D01*
G01X1721788Y226261D02*
X1722080Y226303D01*
X1722413Y226428D01*
X1722621Y226636D01*
X1722705Y226928D01*
X1722621Y227219D01*
X1722371Y227469D01*
X1721996Y227594D01*
X1721580D01*
X1721330Y227678D01*
X1721121Y227886D01*
X1721038Y228178D01*
X1721163Y228469D01*
X1721455Y228678D01*
X1721788Y228761D01*
X1722121Y228678D01*
X1722413Y228469D01*
X1722538Y228178D01*
X1722455Y227886D01*
X1722246Y227678D01*
X1721996Y227594D01*
X1721580D01*
X1721205Y227469D01*
X1720955Y227219D01*
X1720871Y226928D01*
X1720955Y226636D01*
X1721163Y226428D01*
X1721496Y226303D01*
X1721788Y226261D01*
G01X1688017Y265500D02*
Y268000D01*
X1689058D01*
X1689392Y267875D01*
X1689600Y267708D01*
X1689683Y267375D01*
X1689600Y267042D01*
X1689350Y266833D01*
X1689058Y266708D01*
X1688017D01*
G01X1689058D02*
X1689683Y265500D01*
G01X1691950D02*
X1692242Y265542D01*
X1692575Y265667D01*
X1692783Y265875D01*
X1692867Y266167D01*
X1692783Y266458D01*
X1692533Y266708D01*
X1692158Y266833D01*
X1691742D01*
X1691492Y266917D01*
X1691283Y267125D01*
X1691200Y267417D01*
X1691325Y267708D01*
X1691617Y267917D01*
X1691950Y268000D01*
X1692283Y267917D01*
X1692575Y267708D01*
X1692700Y267417D01*
X1692617Y267125D01*
X1692408Y266917D01*
X1692158Y266833D01*
X1691742D01*
X1691367Y266708D01*
X1691117Y266458D01*
X1691033Y266167D01*
X1691117Y265875D01*
X1691325Y265667D01*
X1691658Y265542D01*
X1691950Y265500D01*
G01X1694342Y265792D02*
X1694633Y265583D01*
X1694967Y265500D01*
X1695300Y265583D01*
X1695592Y265833D01*
X1695800Y266208D01*
X1695883Y266583D01*
Y267042D01*
X1695800Y267417D01*
X1695592Y267750D01*
X1695342Y267917D01*
X1695050Y268000D01*
X1694717Y267917D01*
X1694467Y267750D01*
X1694300Y267500D01*
X1694217Y267167D01*
X1694300Y266875D01*
X1694508Y266583D01*
X1694758Y266417D01*
X1695050Y266375D01*
X1695383Y266458D01*
X1695633Y266667D01*
X1695883Y267042D01*
G01X1698150Y268000D02*
X1697817Y267917D01*
X1697567Y267708D01*
X1697400Y267458D01*
X1697275Y267125D01*
X1697233Y266750D01*
X1697275Y266375D01*
X1697400Y266042D01*
X1697567Y265792D01*
X1697817Y265583D01*
X1698150Y265500D01*
X1698483Y265583D01*
X1698733Y265792D01*
X1698900Y266042D01*
X1699025Y266375D01*
X1699067Y266750D01*
X1699025Y267125D01*
X1698900Y267458D01*
X1698733Y267708D01*
X1698483Y267917D01*
X1698150Y268000D01*
G01X1694596Y277366D02*
Y269366D01*
X1676996D01*
Y277366D01*
X1694596D01*
G01X1699708Y288767D02*
X1699583Y288517D01*
X1699500Y288225D01*
Y287892D01*
X1699625Y287517D01*
X1699833Y287225D01*
X1700083Y287017D01*
X1700500Y286850D01*
X1700875Y286808D01*
X1701250Y286892D01*
X1701500Y287017D01*
X1701750Y287267D01*
X1701917Y287558D01*
X1702000Y287850D01*
Y288142D01*
X1701917Y288433D01*
X1701792Y288683D01*
X1701625Y288892D01*
G01X1702000Y291450D02*
X1699500D01*
X1701292Y289908D01*
Y291992D01*
G01X1702000Y293967D02*
X1701458Y294050D01*
X1701000Y294175D01*
X1700583Y294342D01*
X1700125Y294550D01*
X1699500Y294883D01*
Y293217D01*
G01X1701625Y296233D02*
X1701833Y296483D01*
X1701958Y296775D01*
X1702000Y297150D01*
X1701917Y297525D01*
X1701750Y297817D01*
X1701458Y298025D01*
X1701125Y298067D01*
X1700792Y297983D01*
X1700583Y297775D01*
X1700417Y297483D01*
X1700375Y297192D01*
X1700417Y296900D01*
X1700583Y296525D01*
X1699500Y296650D01*
Y297775D01*
G01X1695346Y288928D02*
X1695221Y288678D01*
X1695138Y288386D01*
Y288053D01*
X1695263Y287678D01*
X1695471Y287386D01*
X1695721Y287178D01*
X1696138Y287011D01*
X1696513Y286969D01*
X1696888Y287053D01*
X1697138Y287178D01*
X1697388Y287428D01*
X1697555Y287719D01*
X1697638Y288011D01*
Y288303D01*
X1697555Y288594D01*
X1697430Y288844D01*
X1697263Y289053D01*
G01X1697638Y291611D02*
X1695138D01*
X1696930Y290069D01*
Y292153D01*
G01X1697638Y294128D02*
X1697096Y294211D01*
X1696638Y294336D01*
X1696221Y294503D01*
X1695763Y294711D01*
X1695138Y295044D01*
Y293378D01*
G01X1697138Y296394D02*
X1697430Y296644D01*
X1697596Y296978D01*
X1697638Y297353D01*
X1697596Y297686D01*
X1697388Y298019D01*
X1697138Y298228D01*
X1696888Y298269D01*
X1696596Y298186D01*
X1696388Y297894D01*
X1696305Y297603D01*
Y297228D01*
G01Y297603D02*
X1696180Y297853D01*
X1695971Y298061D01*
X1695721Y298144D01*
X1695471Y298061D01*
X1695263Y297853D01*
X1695138Y297478D01*
X1695180Y297103D01*
X1695346Y296728D01*
G01X1685138Y267961D02*
Y262461D01*
G01X1677138Y267961D02*
X1685138D01*
G01X1677138Y262461D02*
Y267961D01*
G01X1691208Y288767D02*
X1691083Y288517D01*
X1691000Y288225D01*
Y287892D01*
X1691125Y287517D01*
X1691333Y287225D01*
X1691583Y287017D01*
X1692000Y286850D01*
X1692375Y286808D01*
X1692750Y286892D01*
X1693000Y287017D01*
X1693250Y287267D01*
X1693417Y287558D01*
X1693500Y287850D01*
Y288142D01*
X1693417Y288433D01*
X1693292Y288683D01*
X1693125Y288892D01*
G01X1693500Y291450D02*
X1691000D01*
X1692792Y289908D01*
Y291992D01*
G01X1693500Y293967D02*
X1692958Y294050D01*
X1692500Y294175D01*
X1692083Y294342D01*
X1691625Y294550D01*
X1691000Y294883D01*
Y293217D01*
G01X1692458Y296358D02*
X1692167Y296650D01*
X1692000Y296900D01*
X1691917Y297233D01*
X1692000Y297525D01*
X1692167Y297733D01*
X1692417Y297900D01*
X1692708Y297942D01*
X1692958Y297900D01*
X1693208Y297733D01*
X1693417Y297483D01*
X1693500Y297192D01*
X1693417Y296858D01*
X1693167Y296567D01*
X1692792Y296400D01*
X1692375Y296358D01*
X1691833Y296442D01*
X1691542Y296567D01*
X1691250Y296775D01*
X1691042Y297067D01*
X1691000Y297358D01*
X1691083Y297650D01*
X1691292Y297858D01*
G01X1669708Y271267D02*
X1669583Y271017D01*
X1669500Y270725D01*
Y270392D01*
X1669625Y270017D01*
X1669833Y269725D01*
X1670083Y269517D01*
X1670500Y269350D01*
X1670875Y269308D01*
X1671250Y269392D01*
X1671500Y269517D01*
X1671750Y269767D01*
X1671917Y270058D01*
X1672000Y270350D01*
Y270642D01*
X1671917Y270933D01*
X1671792Y271183D01*
X1671625Y271392D01*
G01X1672000Y273950D02*
X1669500D01*
X1671292Y272408D01*
Y274492D01*
G01X1670958Y275758D02*
X1670667Y276050D01*
X1670500Y276300D01*
X1670417Y276633D01*
X1670500Y276925D01*
X1670667Y277133D01*
X1670917Y277300D01*
X1671208Y277342D01*
X1671458Y277300D01*
X1671708Y277133D01*
X1671917Y276883D01*
X1672000Y276592D01*
X1671917Y276258D01*
X1671667Y275967D01*
X1671292Y275800D01*
X1670875Y275758D01*
X1670333Y275842D01*
X1670042Y275967D01*
X1669750Y276175D01*
X1669542Y276467D01*
X1669500Y276758D01*
X1669583Y277050D01*
X1669792Y277258D01*
G01X1671708Y278942D02*
X1671917Y279233D01*
X1672000Y279567D01*
X1671917Y279900D01*
X1671667Y280192D01*
X1671292Y280400D01*
X1670917Y280483D01*
X1670458D01*
X1670083Y280400D01*
X1669750Y280192D01*
X1669583Y279942D01*
X1669500Y279650D01*
X1669583Y279317D01*
X1669750Y279067D01*
X1670000Y278900D01*
X1670333Y278817D01*
X1670625Y278900D01*
X1670917Y279108D01*
X1671083Y279358D01*
X1671125Y279650D01*
X1671042Y279983D01*
X1670833Y280233D01*
X1670458Y280483D01*
G01X1706807Y490353D02*
X1706474Y490395D01*
X1706182Y490561D01*
X1705932Y490811D01*
X1705765Y491103D01*
X1705682Y491436D01*
Y491770D01*
X1705765Y492103D01*
X1705932Y492395D01*
X1706182Y492645D01*
X1706474Y492811D01*
X1706807Y492853D01*
X1707140Y492811D01*
X1707432Y492645D01*
X1707682Y492395D01*
X1707849Y492103D01*
X1707932Y491770D01*
Y491436D01*
X1707849Y491103D01*
X1707682Y490811D01*
X1707432Y490561D01*
X1707140Y490395D01*
X1706807Y490353D01*
G01X1707140Y491020D02*
X1707640Y490353D01*
G01X1709115Y492436D02*
X1709365Y492686D01*
X1709657Y492811D01*
X1709990Y492853D01*
X1710407Y492770D01*
X1710699Y492561D01*
X1710782Y492311D01*
X1710740Y492061D01*
X1710574Y491853D01*
X1709740Y491436D01*
X1709365Y491145D01*
X1709115Y490728D01*
X1709032Y490353D01*
X1710782D01*
G01X1713007D02*
X1713299Y490395D01*
X1713632Y490520D01*
X1713840Y490728D01*
X1713924Y491020D01*
X1713840Y491311D01*
X1713590Y491561D01*
X1713215Y491686D01*
X1712799D01*
X1712549Y491770D01*
X1712340Y491978D01*
X1712257Y492270D01*
X1712382Y492561D01*
X1712674Y492770D01*
X1713007Y492853D01*
X1713340Y492770D01*
X1713632Y492561D01*
X1713757Y492270D01*
X1713674Y491978D01*
X1713465Y491770D01*
X1713215Y491686D01*
X1712799D01*
X1712424Y491561D01*
X1712174Y491311D01*
X1712090Y491020D01*
X1712174Y490728D01*
X1712382Y490520D01*
X1712715Y490395D01*
X1713007Y490353D01*
G01X1715190Y490728D02*
X1715440Y490520D01*
X1715732Y490395D01*
X1716107Y490353D01*
X1716482Y490436D01*
X1716774Y490603D01*
X1716982Y490895D01*
X1717024Y491228D01*
X1716940Y491561D01*
X1716732Y491770D01*
X1716440Y491936D01*
X1716149Y491978D01*
X1715857Y491936D01*
X1715482Y491770D01*
X1715607Y492853D01*
X1716732D01*
G01X1704957Y495853D02*
X1717957D01*
G01X1704957Y509853D02*
Y495853D01*
G01X1703840Y520634D02*
Y523134D01*
X1704881D01*
X1705215Y523009D01*
X1705423Y522842D01*
X1705506Y522509D01*
X1705423Y522176D01*
X1705173Y521967D01*
X1704881Y521842D01*
X1703840D01*
G01X1704881D02*
X1705506Y520634D01*
G01X1706856Y521009D02*
X1707106Y520801D01*
X1707398Y520676D01*
X1707773Y520634D01*
X1708148Y520717D01*
X1708440Y520884D01*
X1708648Y521176D01*
X1708690Y521509D01*
X1708606Y521842D01*
X1708398Y522051D01*
X1708106Y522217D01*
X1707815Y522259D01*
X1707523Y522217D01*
X1707148Y522051D01*
X1707273Y523134D01*
X1708398D01*
G01X1711373Y520634D02*
Y523134D01*
X1709831Y521342D01*
X1711915D01*
G01X1713181Y522717D02*
X1713431Y522967D01*
X1713723Y523092D01*
X1714056Y523134D01*
X1714473Y523051D01*
X1714765Y522842D01*
X1714848Y522592D01*
X1714806Y522342D01*
X1714640Y522134D01*
X1713806Y521717D01*
X1713431Y521426D01*
X1713181Y521009D01*
X1713098Y520634D01*
X1714848D01*
G01X1713023Y511134D02*
Y515134D01*
X1705623D01*
G01X1717957Y509853D02*
X1704957D01*
G01X1678017Y638500D02*
Y641000D01*
X1679058D01*
X1679392Y640875D01*
X1679600Y640708D01*
X1679683Y640375D01*
X1679600Y640042D01*
X1679350Y639833D01*
X1679058Y639708D01*
X1678017D01*
G01X1679058D02*
X1679683Y638500D01*
G01X1681158Y639542D02*
X1681450Y639833D01*
X1681700Y640000D01*
X1682033Y640083D01*
X1682325Y640000D01*
X1682533Y639833D01*
X1682700Y639583D01*
X1682742Y639292D01*
X1682700Y639042D01*
X1682533Y638792D01*
X1682283Y638583D01*
X1681992Y638500D01*
X1681658Y638583D01*
X1681367Y638833D01*
X1681200Y639208D01*
X1681158Y639625D01*
X1681242Y640167D01*
X1681367Y640458D01*
X1681575Y640750D01*
X1681867Y640958D01*
X1682158Y641000D01*
X1682450Y640917D01*
X1682658Y640708D01*
G01X1684258Y640583D02*
X1684508Y640833D01*
X1684800Y640958D01*
X1685133Y641000D01*
X1685550Y640917D01*
X1685842Y640708D01*
X1685925Y640458D01*
X1685883Y640208D01*
X1685717Y640000D01*
X1684883Y639583D01*
X1684508Y639292D01*
X1684258Y638875D01*
X1684175Y638500D01*
X1685925D01*
G01X1688150Y641000D02*
X1687817Y640917D01*
X1687567Y640708D01*
X1687400Y640458D01*
X1687275Y640125D01*
X1687233Y639750D01*
X1687275Y639375D01*
X1687400Y639042D01*
X1687567Y638792D01*
X1687817Y638583D01*
X1688150Y638500D01*
X1688483Y638583D01*
X1688733Y638792D01*
X1688900Y639042D01*
X1689025Y639375D01*
X1689067Y639750D01*
X1689025Y640125D01*
X1688900Y640458D01*
X1688733Y640708D01*
X1688483Y640917D01*
X1688150Y641000D01*
G01X1686338Y641917D02*
Y645917D01*
X1678938D01*
G01X1685334Y603017D02*
X1682834D01*
Y604058D01*
X1682959Y604392D01*
X1683126Y604600D01*
X1683459Y604683D01*
X1683792Y604600D01*
X1684001Y604350D01*
X1684126Y604058D01*
Y603017D01*
G01Y604058D02*
X1685334Y604683D01*
G01X1684292Y606158D02*
X1684001Y606450D01*
X1683834Y606700D01*
X1683751Y607033D01*
X1683834Y607325D01*
X1684001Y607533D01*
X1684251Y607700D01*
X1684542Y607742D01*
X1684792Y607700D01*
X1685042Y607533D01*
X1685251Y607283D01*
X1685334Y606992D01*
X1685251Y606658D01*
X1685001Y606367D01*
X1684626Y606200D01*
X1684209Y606158D01*
X1683667Y606242D01*
X1683376Y606367D01*
X1683084Y606575D01*
X1682876Y606867D01*
X1682834Y607158D01*
X1682917Y607450D01*
X1683126Y607658D01*
G01X1683251Y609258D02*
X1683001Y609508D01*
X1682876Y609800D01*
X1682834Y610133D01*
X1682917Y610550D01*
X1683126Y610842D01*
X1683376Y610925D01*
X1683626Y610883D01*
X1683834Y610717D01*
X1684251Y609883D01*
X1684542Y609508D01*
X1684959Y609258D01*
X1685334Y609175D01*
Y610925D01*
G01Y613150D02*
X1682834D01*
X1683334Y612650D01*
G01X1685334D02*
Y613650D01*
G01X1682638Y616717D02*
X1686638D01*
Y624117D01*
G01X1691334Y608517D02*
X1688834D01*
Y609558D01*
X1688959Y609892D01*
X1689126Y610100D01*
X1689459Y610183D01*
X1689792Y610100D01*
X1690001Y609850D01*
X1690126Y609558D01*
Y608517D01*
G01Y609558D02*
X1691334Y610183D01*
G01X1690292Y611658D02*
X1690001Y611950D01*
X1689834Y612200D01*
X1689751Y612533D01*
X1689834Y612825D01*
X1690001Y613033D01*
X1690251Y613200D01*
X1690542Y613242D01*
X1690792Y613200D01*
X1691042Y613033D01*
X1691251Y612783D01*
X1691334Y612492D01*
X1691251Y612158D01*
X1691001Y611867D01*
X1690626Y611700D01*
X1690209Y611658D01*
X1689667Y611742D01*
X1689376Y611867D01*
X1689084Y612075D01*
X1688876Y612367D01*
X1688834Y612658D01*
X1688917Y612950D01*
X1689126Y613158D01*
G01X1689251Y614758D02*
X1689001Y615008D01*
X1688876Y615300D01*
X1688834Y615633D01*
X1688917Y616050D01*
X1689126Y616342D01*
X1689376Y616425D01*
X1689626Y616383D01*
X1689834Y616217D01*
X1690251Y615383D01*
X1690542Y615008D01*
X1690959Y614758D01*
X1691334Y614675D01*
Y616425D01*
G01Y619150D02*
X1688834D01*
X1690626Y617608D01*
Y619692D01*
G01X1692638Y616717D02*
X1696638D01*
Y624117D01*
G01X1680834Y602517D02*
X1678334D01*
Y603558D01*
X1678459Y603892D01*
X1678626Y604100D01*
X1678959Y604183D01*
X1679292Y604100D01*
X1679501Y603850D01*
X1679626Y603558D01*
Y602517D01*
G01Y603558D02*
X1680834Y604183D01*
G01X1679792Y605658D02*
X1679501Y605950D01*
X1679334Y606200D01*
X1679251Y606533D01*
X1679334Y606825D01*
X1679501Y607033D01*
X1679751Y607200D01*
X1680042Y607242D01*
X1680292Y607200D01*
X1680542Y607033D01*
X1680751Y606783D01*
X1680834Y606492D01*
X1680751Y606158D01*
X1680501Y605867D01*
X1680126Y605700D01*
X1679709Y605658D01*
X1679167Y605742D01*
X1678876Y605867D01*
X1678584Y606075D01*
X1678376Y606367D01*
X1678334Y606658D01*
X1678417Y606950D01*
X1678626Y607158D01*
G01X1678751Y608758D02*
X1678501Y609008D01*
X1678376Y609300D01*
X1678334Y609633D01*
X1678417Y610050D01*
X1678626Y610342D01*
X1678876Y610425D01*
X1679126Y610383D01*
X1679334Y610217D01*
X1679751Y609383D01*
X1680042Y609008D01*
X1680459Y608758D01*
X1680834Y608675D01*
Y610425D01*
G01X1680459Y611733D02*
X1680667Y611983D01*
X1680792Y612275D01*
X1680834Y612650D01*
X1680751Y613025D01*
X1680584Y613317D01*
X1680292Y613525D01*
X1679959Y613567D01*
X1679626Y613483D01*
X1679417Y613275D01*
X1679251Y612983D01*
X1679209Y612692D01*
X1679251Y612400D01*
X1679417Y612025D01*
X1678334Y612150D01*
Y613275D01*
G01X1682138Y624117D02*
X1678138D01*
Y616717D01*
G01X1709000Y625017D02*
X1706500D01*
Y626058D01*
X1706625Y626392D01*
X1706792Y626600D01*
X1707125Y626683D01*
X1707458Y626600D01*
X1707667Y626350D01*
X1707792Y626058D01*
Y625017D01*
G01Y626058D02*
X1709000Y626683D01*
G01X1707958Y628158D02*
X1707667Y628450D01*
X1707500Y628700D01*
X1707417Y629033D01*
X1707500Y629325D01*
X1707667Y629533D01*
X1707917Y629700D01*
X1708208Y629742D01*
X1708458Y629700D01*
X1708708Y629533D01*
X1708917Y629283D01*
X1709000Y628992D01*
X1708917Y628658D01*
X1708667Y628367D01*
X1708292Y628200D01*
X1707875Y628158D01*
X1707333Y628242D01*
X1707042Y628367D01*
X1706750Y628575D01*
X1706542Y628867D01*
X1706500Y629158D01*
X1706583Y629450D01*
X1706792Y629658D01*
G01X1706917Y631258D02*
X1706667Y631508D01*
X1706542Y631800D01*
X1706500Y632133D01*
X1706583Y632550D01*
X1706792Y632842D01*
X1707042Y632925D01*
X1707292Y632883D01*
X1707500Y632717D01*
X1707917Y631883D01*
X1708208Y631508D01*
X1708625Y631258D01*
X1709000Y631175D01*
Y632925D01*
G01Y635067D02*
X1708458Y635150D01*
X1708000Y635275D01*
X1707583Y635442D01*
X1707125Y635650D01*
X1706500Y635983D01*
Y634317D01*
G01X1697138Y629117D02*
X1701138D01*
Y636517D01*
G01X1711017Y643500D02*
Y646000D01*
X1712058D01*
X1712392Y645875D01*
X1712600Y645708D01*
X1712683Y645375D01*
X1712600Y645042D01*
X1712350Y644833D01*
X1712058Y644708D01*
X1711017D01*
G01X1712058D02*
X1712683Y643500D01*
G01X1714158Y644542D02*
X1714450Y644833D01*
X1714700Y645000D01*
X1715033Y645083D01*
X1715325Y645000D01*
X1715533Y644833D01*
X1715700Y644583D01*
X1715742Y644292D01*
X1715700Y644042D01*
X1715533Y643792D01*
X1715283Y643583D01*
X1714992Y643500D01*
X1714658Y643583D01*
X1714367Y643833D01*
X1714200Y644208D01*
X1714158Y644625D01*
X1714242Y645167D01*
X1714367Y645458D01*
X1714575Y645750D01*
X1714867Y645958D01*
X1715158Y646000D01*
X1715450Y645917D01*
X1715658Y645708D01*
G01X1717258Y645583D02*
X1717508Y645833D01*
X1717800Y645958D01*
X1718133Y646000D01*
X1718550Y645917D01*
X1718842Y645708D01*
X1718925Y645458D01*
X1718883Y645208D01*
X1718717Y645000D01*
X1717883Y644583D01*
X1717508Y644292D01*
X1717258Y643875D01*
X1717175Y643500D01*
X1718925D01*
G01X1720442Y643792D02*
X1720733Y643583D01*
X1721067Y643500D01*
X1721400Y643583D01*
X1721692Y643833D01*
X1721900Y644208D01*
X1721983Y644583D01*
Y645042D01*
X1721900Y645417D01*
X1721692Y645750D01*
X1721442Y645917D01*
X1721150Y646000D01*
X1720817Y645917D01*
X1720567Y645750D01*
X1720400Y645500D01*
X1720317Y645167D01*
X1720400Y644875D01*
X1720608Y644583D01*
X1720858Y644417D01*
X1721150Y644375D01*
X1721483Y644458D01*
X1721733Y644667D01*
X1721983Y645042D01*
G01X1699938Y649417D02*
Y645417D01*
X1707338D01*
G01X1705000Y625017D02*
X1702500D01*
Y626058D01*
X1702625Y626392D01*
X1702792Y626600D01*
X1703125Y626683D01*
X1703458Y626600D01*
X1703667Y626350D01*
X1703792Y626058D01*
Y625017D01*
G01Y626058D02*
X1705000Y626683D01*
G01X1703958Y628158D02*
X1703667Y628450D01*
X1703500Y628700D01*
X1703417Y629033D01*
X1703500Y629325D01*
X1703667Y629533D01*
X1703917Y629700D01*
X1704208Y629742D01*
X1704458Y629700D01*
X1704708Y629533D01*
X1704917Y629283D01*
X1705000Y628992D01*
X1704917Y628658D01*
X1704667Y628367D01*
X1704292Y628200D01*
X1703875Y628158D01*
X1703333Y628242D01*
X1703042Y628367D01*
X1702750Y628575D01*
X1702542Y628867D01*
X1702500Y629158D01*
X1702583Y629450D01*
X1702792Y629658D01*
G01X1704500Y631133D02*
X1704792Y631383D01*
X1704958Y631717D01*
X1705000Y632092D01*
X1704958Y632425D01*
X1704750Y632758D01*
X1704500Y632967D01*
X1704250Y633008D01*
X1703958Y632925D01*
X1703750Y632633D01*
X1703667Y632342D01*
Y631967D01*
G01Y632342D02*
X1703542Y632592D01*
X1703333Y632800D01*
X1703083Y632883D01*
X1702833Y632800D01*
X1702625Y632592D01*
X1702500Y632217D01*
X1702542Y631842D01*
X1702708Y631467D01*
G01X1702500Y635150D02*
X1702583Y634817D01*
X1702792Y634567D01*
X1703042Y634400D01*
X1703375Y634275D01*
X1703750Y634233D01*
X1704125Y634275D01*
X1704458Y634400D01*
X1704708Y634567D01*
X1704917Y634817D01*
X1705000Y635150D01*
X1704917Y635483D01*
X1704708Y635733D01*
X1704458Y635900D01*
X1704125Y636025D01*
X1703750Y636067D01*
X1703375Y636025D01*
X1703042Y635900D01*
X1702792Y635733D01*
X1702583Y635483D01*
X1702500Y635150D01*
G01X1692438Y629117D02*
X1696438D01*
Y636517D01*
G01X1671833Y626350D02*
X1671791Y626017D01*
X1671625Y625725D01*
X1671375Y625475D01*
X1671083Y625308D01*
X1670750Y625225D01*
X1670416D01*
X1670083Y625308D01*
X1669791Y625475D01*
X1669541Y625725D01*
X1669375Y626017D01*
X1669333Y626350D01*
X1669375Y626683D01*
X1669541Y626975D01*
X1669791Y627225D01*
X1670083Y627392D01*
X1670416Y627475D01*
X1670750D01*
X1671083Y627392D01*
X1671375Y627225D01*
X1671625Y626975D01*
X1671791Y626683D01*
X1671833Y626350D01*
G01X1671166Y626683D02*
X1671833Y627183D01*
G01Y629450D02*
X1669333D01*
X1669833Y628950D01*
G01X1671833D02*
Y629950D01*
G01X1669750Y631758D02*
X1669500Y632008D01*
X1669375Y632300D01*
X1669333Y632633D01*
X1669416Y633050D01*
X1669625Y633342D01*
X1669875Y633425D01*
X1670125Y633383D01*
X1670333Y633217D01*
X1670750Y632383D01*
X1671041Y632008D01*
X1671458Y631758D01*
X1671833Y631675D01*
Y633425D01*
G01Y635567D02*
X1671291Y635650D01*
X1670833Y635775D01*
X1670416Y635942D01*
X1669958Y636150D01*
X1669333Y636483D01*
Y634817D01*
G01X1673438Y636617D02*
Y625217D01*
G01X1686838Y636617D02*
X1673438D01*
G01X1686838Y625217D02*
Y636617D01*
G01X1673438Y625217D02*
X1686838D01*
G01X1711121Y639917D02*
Y642417D01*
X1711955D01*
X1712288Y642292D01*
X1712538Y642125D01*
X1712746Y641875D01*
X1712913Y641584D01*
X1712955Y641167D01*
X1712913Y640750D01*
X1712746Y640459D01*
X1712538Y640209D01*
X1712288Y640042D01*
X1711955Y639917D01*
X1711121D01*
G01X1714346Y642000D02*
X1714596Y642250D01*
X1714888Y642375D01*
X1715221Y642417D01*
X1715638Y642334D01*
X1715930Y642125D01*
X1716013Y641875D01*
X1715971Y641625D01*
X1715805Y641417D01*
X1714971Y641000D01*
X1714596Y640709D01*
X1714346Y640292D01*
X1714263Y639917D01*
X1716013D01*
G01X1718238D02*
Y642417D01*
X1717738Y641917D01*
G01Y639917D02*
X1718738D01*
G01X1709138Y637417D02*
X1693038D01*
G01X1709138Y644417D02*
Y637417D01*
G01X1693038Y644417D02*
X1709138D01*
G01X1693038Y637417D02*
Y644417D01*
G01X1718395Y624940D02*
X1718145Y625065D01*
X1717853Y625148D01*
X1717520D01*
X1717145Y625023D01*
X1716853Y624815D01*
X1716645Y624565D01*
X1716478Y624148D01*
X1716436Y623773D01*
X1716520Y623398D01*
X1716645Y623148D01*
X1716895Y622898D01*
X1717186Y622731D01*
X1717478Y622648D01*
X1717770D01*
X1718061Y622731D01*
X1718311Y622856D01*
X1718520Y623023D01*
G01X1719661Y623148D02*
X1719911Y622856D01*
X1720245Y622690D01*
X1720620Y622648D01*
X1720953Y622690D01*
X1721286Y622898D01*
X1721495Y623148D01*
X1721536Y623398D01*
X1721453Y623690D01*
X1721161Y623898D01*
X1720870Y623981D01*
X1720495D01*
G01X1720870D02*
X1721120Y624106D01*
X1721328Y624315D01*
X1721411Y624565D01*
X1721328Y624815D01*
X1721120Y625023D01*
X1720745Y625148D01*
X1720370Y625106D01*
X1719995Y624940D01*
G01X1722886Y624731D02*
X1723136Y624981D01*
X1723428Y625106D01*
X1723761Y625148D01*
X1724178Y625065D01*
X1724470Y624856D01*
X1724553Y624606D01*
X1724511Y624356D01*
X1724345Y624148D01*
X1723511Y623731D01*
X1723136Y623440D01*
X1722886Y623023D01*
X1722803Y622648D01*
X1724553D01*
G01X1725861Y623023D02*
X1726111Y622815D01*
X1726403Y622690D01*
X1726778Y622648D01*
X1727153Y622731D01*
X1727445Y622898D01*
X1727653Y623190D01*
X1727695Y623523D01*
X1727611Y623856D01*
X1727403Y624065D01*
X1727111Y624231D01*
X1726820Y624273D01*
X1726528Y624231D01*
X1726153Y624065D01*
X1726278Y625148D01*
X1727403D01*
G01X1718267Y628792D02*
X1718017Y628917D01*
X1717725Y629000D01*
X1717392D01*
X1717017Y628875D01*
X1716725Y628667D01*
X1716517Y628417D01*
X1716350Y628000D01*
X1716308Y627625D01*
X1716392Y627250D01*
X1716517Y627000D01*
X1716767Y626750D01*
X1717058Y626583D01*
X1717350Y626500D01*
X1717642D01*
X1717933Y626583D01*
X1718183Y626708D01*
X1718392Y626875D01*
G01X1719533Y627000D02*
X1719783Y626708D01*
X1720117Y626542D01*
X1720492Y626500D01*
X1720825Y626542D01*
X1721158Y626750D01*
X1721367Y627000D01*
X1721408Y627250D01*
X1721325Y627542D01*
X1721033Y627750D01*
X1720742Y627833D01*
X1720367D01*
G01X1720742D02*
X1720992Y627958D01*
X1721200Y628167D01*
X1721283Y628417D01*
X1721200Y628667D01*
X1720992Y628875D01*
X1720617Y629000D01*
X1720242Y628958D01*
X1719867Y628792D01*
G01X1722758Y628583D02*
X1723008Y628833D01*
X1723300Y628958D01*
X1723633Y629000D01*
X1724050Y628917D01*
X1724342Y628708D01*
X1724425Y628458D01*
X1724383Y628208D01*
X1724217Y628000D01*
X1723383Y627583D01*
X1723008Y627292D01*
X1722758Y626875D01*
X1722675Y626500D01*
X1724425D01*
G01X1727150D02*
Y629000D01*
X1725608Y627208D01*
X1727692D01*
G01X1673208Y647267D02*
X1673083Y647017D01*
X1673000Y646725D01*
Y646392D01*
X1673125Y646017D01*
X1673333Y645725D01*
X1673583Y645517D01*
X1674000Y645350D01*
X1674375Y645308D01*
X1674750Y645392D01*
X1675000Y645517D01*
X1675250Y645767D01*
X1675417Y646058D01*
X1675500Y646350D01*
Y646642D01*
X1675417Y646933D01*
X1675292Y647183D01*
X1675125Y647392D01*
G01X1675000Y648533D02*
X1675292Y648783D01*
X1675458Y649117D01*
X1675500Y649492D01*
X1675458Y649825D01*
X1675250Y650158D01*
X1675000Y650367D01*
X1674750Y650408D01*
X1674458Y650325D01*
X1674250Y650033D01*
X1674167Y649742D01*
Y649367D01*
G01Y649742D02*
X1674042Y649992D01*
X1673833Y650200D01*
X1673583Y650283D01*
X1673333Y650200D01*
X1673125Y649992D01*
X1673000Y649617D01*
X1673042Y649242D01*
X1673208Y648867D01*
G01X1673417Y651758D02*
X1673167Y652008D01*
X1673042Y652300D01*
X1673000Y652633D01*
X1673083Y653050D01*
X1673292Y653342D01*
X1673542Y653425D01*
X1673792Y653383D01*
X1674000Y653217D01*
X1674417Y652383D01*
X1674708Y652008D01*
X1675125Y651758D01*
X1675500Y651675D01*
Y653425D01*
G01Y655650D02*
X1673000D01*
X1673500Y655150D01*
G01X1675500D02*
Y656150D01*
G01X1690155Y675417D02*
Y677917D01*
X1691196D01*
X1691530Y677792D01*
X1691738Y677625D01*
X1691821Y677292D01*
X1691738Y676959D01*
X1691488Y676750D01*
X1691196Y676625D01*
X1690155D01*
G01X1691196D02*
X1691821Y675417D01*
G01X1693296Y676459D02*
X1693588Y676750D01*
X1693838Y676917D01*
X1694171Y677000D01*
X1694463Y676917D01*
X1694671Y676750D01*
X1694838Y676500D01*
X1694880Y676209D01*
X1694838Y675959D01*
X1694671Y675709D01*
X1694421Y675500D01*
X1694130Y675417D01*
X1693796Y675500D01*
X1693505Y675750D01*
X1693338Y676125D01*
X1693296Y676542D01*
X1693380Y677084D01*
X1693505Y677375D01*
X1693713Y677667D01*
X1694005Y677875D01*
X1694296Y677917D01*
X1694588Y677834D01*
X1694796Y677625D01*
G01X1696396Y677500D02*
X1696646Y677750D01*
X1696938Y677875D01*
X1697271Y677917D01*
X1697688Y677834D01*
X1697980Y677625D01*
X1698063Y677375D01*
X1698021Y677125D01*
X1697855Y676917D01*
X1697021Y676500D01*
X1696646Y676209D01*
X1696396Y675792D01*
X1696313Y675417D01*
X1698063D01*
G01X1700288D02*
X1700580Y675459D01*
X1700913Y675584D01*
X1701121Y675792D01*
X1701205Y676084D01*
X1701121Y676375D01*
X1700871Y676625D01*
X1700496Y676750D01*
X1700080D01*
X1699830Y676834D01*
X1699621Y677042D01*
X1699538Y677334D01*
X1699663Y677625D01*
X1699955Y677834D01*
X1700288Y677917D01*
X1700621Y677834D01*
X1700913Y677625D01*
X1701038Y677334D01*
X1700955Y677042D01*
X1700746Y676834D01*
X1700496Y676750D01*
X1700080D01*
X1699705Y676625D01*
X1699455Y676375D01*
X1699371Y676084D01*
X1699455Y675792D01*
X1699663Y675584D01*
X1699996Y675459D01*
X1700288Y675417D01*
G01X1709838Y674417D02*
Y678417D01*
X1702438D01*
G01X1671517Y685500D02*
Y688000D01*
X1672558D01*
X1672892Y687875D01*
X1673100Y687708D01*
X1673183Y687375D01*
X1673100Y687042D01*
X1672850Y686833D01*
X1672558Y686708D01*
X1671517D01*
G01X1672558D02*
X1673183Y685500D01*
G01X1674658Y686542D02*
X1674950Y686833D01*
X1675200Y687000D01*
X1675533Y687083D01*
X1675825Y687000D01*
X1676033Y686833D01*
X1676200Y686583D01*
X1676242Y686292D01*
X1676200Y686042D01*
X1676033Y685792D01*
X1675783Y685583D01*
X1675492Y685500D01*
X1675158Y685583D01*
X1674867Y685833D01*
X1674700Y686208D01*
X1674658Y686625D01*
X1674742Y687167D01*
X1674867Y687458D01*
X1675075Y687750D01*
X1675367Y687958D01*
X1675658Y688000D01*
X1675950Y687917D01*
X1676158Y687708D01*
G01X1678550Y685500D02*
Y688000D01*
X1678050Y687500D01*
G01Y685500D02*
X1679050D01*
G01X1680858Y687583D02*
X1681108Y687833D01*
X1681400Y687958D01*
X1681733Y688000D01*
X1682150Y687917D01*
X1682442Y687708D01*
X1682525Y687458D01*
X1682483Y687208D01*
X1682317Y687000D01*
X1681483Y686583D01*
X1681108Y686292D01*
X1680858Y685875D01*
X1680775Y685500D01*
X1682525D01*
G01X1686438Y697417D02*
Y689417D01*
X1668838D01*
Y697417D01*
X1686438D01*
G01X1687938Y698917D02*
X1690038Y697117D01*
X1687938Y694917D01*
G01X1687838Y691317D02*
X1707038D01*
Y702517D01*
X1687838D01*
Y691317D01*
X1688238D01*
G01X1677350Y673000D02*
X1677017Y673042D01*
X1676725Y673208D01*
X1676475Y673458D01*
X1676308Y673750D01*
X1676225Y674083D01*
Y674417D01*
X1676308Y674750D01*
X1676475Y675042D01*
X1676725Y675292D01*
X1677017Y675458D01*
X1677350Y675500D01*
X1677683Y675458D01*
X1677975Y675292D01*
X1678225Y675042D01*
X1678392Y674750D01*
X1678475Y674417D01*
Y674083D01*
X1678392Y673750D01*
X1678225Y673458D01*
X1677975Y673208D01*
X1677683Y673042D01*
X1677350Y673000D01*
G01X1677683Y673667D02*
X1678183Y673000D01*
G01X1680450D02*
Y675500D01*
X1679950Y675000D01*
G01Y673000D02*
X1680950D01*
G01X1682758Y675083D02*
X1683008Y675333D01*
X1683300Y675458D01*
X1683633Y675500D01*
X1684050Y675417D01*
X1684342Y675208D01*
X1684425Y674958D01*
X1684383Y674708D01*
X1684217Y674500D01*
X1683383Y674083D01*
X1683008Y673792D01*
X1682758Y673375D01*
X1682675Y673000D01*
X1684425D01*
G01X1685733Y673375D02*
X1685983Y673167D01*
X1686275Y673042D01*
X1686650Y673000D01*
X1687025Y673083D01*
X1687317Y673250D01*
X1687525Y673542D01*
X1687567Y673875D01*
X1687483Y674208D01*
X1687275Y674417D01*
X1686983Y674583D01*
X1686692Y674625D01*
X1686400Y674583D01*
X1686025Y674417D01*
X1686150Y675500D01*
X1687275D01*
G01X1693138Y671617D02*
X1691338Y669517D01*
X1689138Y671617D01*
G01X1685538Y671717D02*
Y652517D01*
X1696738D01*
Y671717D01*
X1685538D01*
Y671317D01*
G01X1691905Y681809D02*
X1691655Y681934D01*
X1691363Y682017D01*
X1691030D01*
X1690655Y681892D01*
X1690363Y681684D01*
X1690155Y681434D01*
X1689988Y681017D01*
X1689946Y680642D01*
X1690030Y680267D01*
X1690155Y680017D01*
X1690405Y679767D01*
X1690696Y679600D01*
X1690988Y679517D01*
X1691280D01*
X1691571Y679600D01*
X1691821Y679725D01*
X1692030Y679892D01*
G01X1693171Y680017D02*
X1693421Y679725D01*
X1693755Y679559D01*
X1694130Y679517D01*
X1694463Y679559D01*
X1694796Y679767D01*
X1695005Y680017D01*
X1695046Y680267D01*
X1694963Y680559D01*
X1694671Y680767D01*
X1694380Y680850D01*
X1694005D01*
G01X1694380D02*
X1694630Y680975D01*
X1694838Y681184D01*
X1694921Y681434D01*
X1694838Y681684D01*
X1694630Y681892D01*
X1694255Y682017D01*
X1693880Y681975D01*
X1693505Y681809D01*
G01X1696396Y681600D02*
X1696646Y681850D01*
X1696938Y681975D01*
X1697271Y682017D01*
X1697688Y681934D01*
X1697980Y681725D01*
X1698063Y681475D01*
X1698021Y681225D01*
X1697855Y681017D01*
X1697021Y680600D01*
X1696646Y680309D01*
X1696396Y679892D01*
X1696313Y679517D01*
X1698063D01*
G01X1699496Y681600D02*
X1699746Y681850D01*
X1700038Y681975D01*
X1700371Y682017D01*
X1700788Y681934D01*
X1701080Y681725D01*
X1701163Y681475D01*
X1701121Y681225D01*
X1700955Y681017D01*
X1700121Y680600D01*
X1699746Y680309D01*
X1699496Y679892D01*
X1699413Y679517D01*
X1701163D01*
G01X1688017Y718500D02*
Y721000D01*
X1689058D01*
X1689392Y720875D01*
X1689600Y720708D01*
X1689683Y720375D01*
X1689600Y720042D01*
X1689350Y719833D01*
X1689058Y719708D01*
X1688017D01*
G01X1689058D02*
X1689683Y718500D01*
G01X1691158Y719542D02*
X1691450Y719833D01*
X1691700Y720000D01*
X1692033Y720083D01*
X1692325Y720000D01*
X1692533Y719833D01*
X1692700Y719583D01*
X1692742Y719292D01*
X1692700Y719042D01*
X1692533Y718792D01*
X1692283Y718583D01*
X1691992Y718500D01*
X1691658Y718583D01*
X1691367Y718833D01*
X1691200Y719208D01*
X1691158Y719625D01*
X1691242Y720167D01*
X1691367Y720458D01*
X1691575Y720750D01*
X1691867Y720958D01*
X1692158Y721000D01*
X1692450Y720917D01*
X1692658Y720708D01*
G01X1695050Y718500D02*
Y721000D01*
X1694550Y720500D01*
G01Y718500D02*
X1695550D01*
G01X1698650D02*
Y721000D01*
X1697108Y719208D01*
X1699192D01*
G01X1694713Y730063D02*
Y722063D01*
X1677113D01*
Y730063D01*
X1694713D01*
G01X1698708Y741767D02*
X1698583Y741517D01*
X1698500Y741225D01*
Y740892D01*
X1698625Y740517D01*
X1698833Y740225D01*
X1699083Y740017D01*
X1699500Y739850D01*
X1699875Y739808D01*
X1700250Y739892D01*
X1700500Y740017D01*
X1700750Y740267D01*
X1700917Y740558D01*
X1701000Y740850D01*
Y741142D01*
X1700917Y741433D01*
X1700792Y741683D01*
X1700625Y741892D01*
G01X1700500Y743033D02*
X1700792Y743283D01*
X1700958Y743617D01*
X1701000Y743992D01*
X1700958Y744325D01*
X1700750Y744658D01*
X1700500Y744867D01*
X1700250Y744908D01*
X1699958Y744825D01*
X1699750Y744533D01*
X1699667Y744242D01*
Y743867D01*
G01Y744242D02*
X1699542Y744492D01*
X1699333Y744700D01*
X1699083Y744783D01*
X1698833Y744700D01*
X1698625Y744492D01*
X1698500Y744117D01*
X1698542Y743742D01*
X1698708Y743367D01*
G01X1701000Y747050D02*
X1698500D01*
X1699000Y746550D01*
G01X1701000D02*
Y747550D01*
G01X1700708Y749442D02*
X1700917Y749733D01*
X1701000Y750067D01*
X1700917Y750400D01*
X1700667Y750692D01*
X1700292Y750900D01*
X1699917Y750983D01*
X1699458D01*
X1699083Y750900D01*
X1698750Y750692D01*
X1698583Y750442D01*
X1698500Y750150D01*
X1698583Y749817D01*
X1698750Y749567D01*
X1699000Y749400D01*
X1699333Y749317D01*
X1699625Y749400D01*
X1699917Y749608D01*
X1700083Y749858D01*
X1700125Y750150D01*
X1700042Y750483D01*
X1699833Y750733D01*
X1699458Y750983D01*
G01X1694708Y741767D02*
X1694583Y741517D01*
X1694500Y741225D01*
Y740892D01*
X1694625Y740517D01*
X1694833Y740225D01*
X1695083Y740017D01*
X1695500Y739850D01*
X1695875Y739808D01*
X1696250Y739892D01*
X1696500Y740017D01*
X1696750Y740267D01*
X1696917Y740558D01*
X1697000Y740850D01*
Y741142D01*
X1696917Y741433D01*
X1696792Y741683D01*
X1696625Y741892D01*
G01X1696500Y743033D02*
X1696792Y743283D01*
X1696958Y743617D01*
X1697000Y743992D01*
X1696958Y744325D01*
X1696750Y744658D01*
X1696500Y744867D01*
X1696250Y744908D01*
X1695958Y744825D01*
X1695750Y744533D01*
X1695667Y744242D01*
Y743867D01*
G01Y744242D02*
X1695542Y744492D01*
X1695333Y744700D01*
X1695083Y744783D01*
X1694833Y744700D01*
X1694625Y744492D01*
X1694500Y744117D01*
X1694542Y743742D01*
X1694708Y743367D01*
G01X1697000Y747050D02*
X1694500D01*
X1695000Y746550D01*
G01X1697000D02*
Y747550D01*
G01Y750150D02*
X1696958Y750442D01*
X1696833Y750775D01*
X1696625Y750983D01*
X1696333Y751067D01*
X1696042Y750983D01*
X1695792Y750733D01*
X1695667Y750358D01*
Y749942D01*
X1695583Y749692D01*
X1695375Y749483D01*
X1695083Y749400D01*
X1694792Y749525D01*
X1694583Y749817D01*
X1694500Y750150D01*
X1694583Y750483D01*
X1694792Y750775D01*
X1695083Y750900D01*
X1695375Y750817D01*
X1695583Y750608D01*
X1695667Y750358D01*
Y749942D01*
X1695792Y749567D01*
X1696042Y749317D01*
X1696333Y749233D01*
X1696625Y749317D01*
X1696833Y749525D01*
X1696958Y749858D01*
X1697000Y750150D01*
G01X1673208Y700767D02*
X1673083Y700517D01*
X1673000Y700225D01*
Y699892D01*
X1673125Y699517D01*
X1673333Y699225D01*
X1673583Y699017D01*
X1674000Y698850D01*
X1674375Y698808D01*
X1674750Y698892D01*
X1675000Y699017D01*
X1675250Y699267D01*
X1675417Y699558D01*
X1675500Y699850D01*
Y700142D01*
X1675417Y700433D01*
X1675292Y700683D01*
X1675125Y700892D01*
G01X1675000Y702033D02*
X1675292Y702283D01*
X1675458Y702617D01*
X1675500Y702992D01*
X1675458Y703325D01*
X1675250Y703658D01*
X1675000Y703867D01*
X1674750Y703908D01*
X1674458Y703825D01*
X1674250Y703533D01*
X1674167Y703242D01*
Y702867D01*
G01Y703242D02*
X1674042Y703492D01*
X1673833Y703700D01*
X1673583Y703783D01*
X1673333Y703700D01*
X1673125Y703492D01*
X1673000Y703117D01*
X1673042Y702742D01*
X1673208Y702367D01*
G01X1675500Y706050D02*
X1673000D01*
X1673500Y705550D01*
G01X1675500D02*
Y706550D01*
G01Y709650D02*
X1673000D01*
X1674792Y708108D01*
Y710192D01*
G01X1677138Y703117D02*
Y708617D01*
G01X1685138Y703117D02*
X1677138D01*
G01X1685138Y708617D02*
Y703117D01*
G01Y720717D02*
Y715217D01*
G01X1677138Y720717D02*
X1685138D01*
G01X1677138Y715217D02*
Y720717D01*
G01X1699850Y712000D02*
X1699517Y712042D01*
X1699225Y712208D01*
X1698975Y712458D01*
X1698808Y712750D01*
X1698725Y713083D01*
Y713417D01*
X1698808Y713750D01*
X1698975Y714042D01*
X1699225Y714292D01*
X1699517Y714458D01*
X1699850Y714500D01*
X1700183Y714458D01*
X1700475Y714292D01*
X1700725Y714042D01*
X1700892Y713750D01*
X1700975Y713417D01*
Y713083D01*
X1700892Y712750D01*
X1700725Y712458D01*
X1700475Y712208D01*
X1700183Y712042D01*
X1699850Y712000D01*
G01X1700183Y712667D02*
X1700683Y712000D01*
G01X1702950D02*
Y714500D01*
X1702450Y714000D01*
G01Y712000D02*
X1703450D01*
G01X1705258Y714083D02*
X1705508Y714333D01*
X1705800Y714458D01*
X1706133Y714500D01*
X1706550Y714417D01*
X1706842Y714208D01*
X1706925Y713958D01*
X1706883Y713708D01*
X1706717Y713500D01*
X1705883Y713083D01*
X1705508Y712792D01*
X1705258Y712375D01*
X1705175Y712000D01*
X1706925D01*
G01X1709150D02*
X1709442Y712042D01*
X1709775Y712167D01*
X1709983Y712375D01*
X1710067Y712667D01*
X1709983Y712958D01*
X1709733Y713208D01*
X1709358Y713333D01*
X1708942D01*
X1708692Y713417D01*
X1708483Y713625D01*
X1708400Y713917D01*
X1708525Y714208D01*
X1708817Y714417D01*
X1709150Y714500D01*
X1709483Y714417D01*
X1709775Y714208D01*
X1709900Y713917D01*
X1709817Y713625D01*
X1709608Y713417D01*
X1709358Y713333D01*
X1708942D01*
X1708567Y713208D01*
X1708317Y712958D01*
X1708233Y712667D01*
X1708317Y712375D01*
X1708525Y712167D01*
X1708858Y712042D01*
X1709150Y712000D01*
G01X1690708Y741767D02*
X1690583Y741517D01*
X1690500Y741225D01*
Y740892D01*
X1690625Y740517D01*
X1690833Y740225D01*
X1691083Y740017D01*
X1691500Y739850D01*
X1691875Y739808D01*
X1692250Y739892D01*
X1692500Y740017D01*
X1692750Y740267D01*
X1692917Y740558D01*
X1693000Y740850D01*
Y741142D01*
X1692917Y741433D01*
X1692792Y741683D01*
X1692625Y741892D01*
G01X1692500Y743033D02*
X1692792Y743283D01*
X1692958Y743617D01*
X1693000Y743992D01*
X1692958Y744325D01*
X1692750Y744658D01*
X1692500Y744867D01*
X1692250Y744908D01*
X1691958Y744825D01*
X1691750Y744533D01*
X1691667Y744242D01*
Y743867D01*
G01Y744242D02*
X1691542Y744492D01*
X1691333Y744700D01*
X1691083Y744783D01*
X1690833Y744700D01*
X1690625Y744492D01*
X1690500Y744117D01*
X1690542Y743742D01*
X1690708Y743367D01*
G01X1690917Y746258D02*
X1690667Y746508D01*
X1690542Y746800D01*
X1690500Y747133D01*
X1690583Y747550D01*
X1690792Y747842D01*
X1691042Y747925D01*
X1691292Y747883D01*
X1691500Y747717D01*
X1691917Y746883D01*
X1692208Y746508D01*
X1692625Y746258D01*
X1693000Y746175D01*
Y747925D01*
G01X1690500Y750150D02*
X1690583Y749817D01*
X1690792Y749567D01*
X1691042Y749400D01*
X1691375Y749275D01*
X1691750Y749233D01*
X1692125Y749275D01*
X1692458Y749400D01*
X1692708Y749567D01*
X1692917Y749817D01*
X1693000Y750150D01*
X1692917Y750483D01*
X1692708Y750733D01*
X1692458Y750900D01*
X1692125Y751025D01*
X1691750Y751067D01*
X1691375Y751025D01*
X1691042Y750900D01*
X1690792Y750733D01*
X1690583Y750483D01*
X1690500Y750150D01*
G01X1670208Y723767D02*
X1670083Y723517D01*
X1670000Y723225D01*
Y722892D01*
X1670125Y722517D01*
X1670333Y722225D01*
X1670583Y722017D01*
X1671000Y721850D01*
X1671375Y721808D01*
X1671750Y721892D01*
X1672000Y722017D01*
X1672250Y722267D01*
X1672417Y722558D01*
X1672500Y722850D01*
Y723142D01*
X1672417Y723433D01*
X1672292Y723683D01*
X1672125Y723892D01*
G01X1672000Y725033D02*
X1672292Y725283D01*
X1672458Y725617D01*
X1672500Y725992D01*
X1672458Y726325D01*
X1672250Y726658D01*
X1672000Y726867D01*
X1671750Y726908D01*
X1671458Y726825D01*
X1671250Y726533D01*
X1671167Y726242D01*
Y725867D01*
G01Y726242D02*
X1671042Y726492D01*
X1670833Y726700D01*
X1670583Y726783D01*
X1670333Y726700D01*
X1670125Y726492D01*
X1670000Y726117D01*
X1670042Y725742D01*
X1670208Y725367D01*
G01X1672500Y729050D02*
X1670000D01*
X1670500Y728550D01*
G01X1672500D02*
Y729550D01*
G01X1672000Y731233D02*
X1672292Y731483D01*
X1672458Y731817D01*
X1672500Y732192D01*
X1672458Y732525D01*
X1672250Y732858D01*
X1672000Y733067D01*
X1671750Y733108D01*
X1671458Y733025D01*
X1671250Y732733D01*
X1671167Y732442D01*
Y732067D01*
G01Y732442D02*
X1671042Y732692D01*
X1670833Y732900D01*
X1670583Y732983D01*
X1670333Y732900D01*
X1670125Y732692D01*
X1670000Y732317D01*
X1670042Y731942D01*
X1670208Y731567D01*
G01X1683638Y1055690D02*
X1681138D01*
Y1056731D01*
X1681263Y1057065D01*
X1681430Y1057273D01*
X1681763Y1057356D01*
X1682096Y1057273D01*
X1682305Y1057023D01*
X1682430Y1056731D01*
Y1055690D01*
G01Y1056731D02*
X1683638Y1057356D01*
G01X1683138Y1058706D02*
X1683430Y1058956D01*
X1683596Y1059290D01*
X1683638Y1059665D01*
X1683596Y1059998D01*
X1683388Y1060331D01*
X1683138Y1060540D01*
X1682888Y1060581D01*
X1682596Y1060498D01*
X1682388Y1060206D01*
X1682305Y1059915D01*
Y1059540D01*
G01Y1059915D02*
X1682180Y1060165D01*
X1681971Y1060373D01*
X1681721Y1060456D01*
X1681471Y1060373D01*
X1681263Y1060165D01*
X1681138Y1059790D01*
X1681180Y1059415D01*
X1681346Y1059040D01*
G01X1683638Y1063223D02*
X1681138D01*
X1682930Y1061681D01*
Y1063765D01*
G01X1683263Y1064906D02*
X1683471Y1065156D01*
X1683596Y1065448D01*
X1683638Y1065823D01*
X1683555Y1066198D01*
X1683388Y1066490D01*
X1683096Y1066698D01*
X1682763Y1066740D01*
X1682430Y1066656D01*
X1682221Y1066448D01*
X1682055Y1066156D01*
X1682013Y1065865D01*
X1682055Y1065573D01*
X1682221Y1065198D01*
X1681138Y1065323D01*
Y1066448D01*
G01X1682638Y1069473D02*
X1686638D01*
Y1076873D01*
G01X1700500Y1066517D02*
X1698000D01*
Y1067558D01*
X1698125Y1067892D01*
X1698292Y1068100D01*
X1698625Y1068183D01*
X1698958Y1068100D01*
X1699167Y1067850D01*
X1699292Y1067558D01*
Y1066517D01*
G01Y1067558D02*
X1700500Y1068183D01*
G01X1700000Y1069533D02*
X1700292Y1069783D01*
X1700458Y1070117D01*
X1700500Y1070492D01*
X1700458Y1070825D01*
X1700250Y1071158D01*
X1700000Y1071367D01*
X1699750Y1071408D01*
X1699458Y1071325D01*
X1699250Y1071033D01*
X1699167Y1070742D01*
Y1070367D01*
G01Y1070742D02*
X1699042Y1070992D01*
X1698833Y1071200D01*
X1698583Y1071283D01*
X1698333Y1071200D01*
X1698125Y1070992D01*
X1698000Y1070617D01*
X1698042Y1070242D01*
X1698208Y1069867D01*
G01X1700500Y1074050D02*
X1698000D01*
X1699792Y1072508D01*
Y1074592D01*
G01X1700500Y1076650D02*
X1700458Y1076942D01*
X1700333Y1077275D01*
X1700125Y1077483D01*
X1699833Y1077567D01*
X1699542Y1077483D01*
X1699292Y1077233D01*
X1699167Y1076858D01*
Y1076442D01*
X1699083Y1076192D01*
X1698875Y1075983D01*
X1698583Y1075900D01*
X1698292Y1076025D01*
X1698083Y1076317D01*
X1698000Y1076650D01*
X1698083Y1076983D01*
X1698292Y1077275D01*
X1698583Y1077400D01*
X1698875Y1077317D01*
X1699083Y1077108D01*
X1699167Y1076858D01*
Y1076442D01*
X1699292Y1076067D01*
X1699542Y1075817D01*
X1699833Y1075733D01*
X1700125Y1075817D01*
X1700333Y1076025D01*
X1700458Y1076358D01*
X1700500Y1076650D01*
G01X1692638Y1069473D02*
X1696638D01*
Y1076873D01*
G01X1679138Y1055690D02*
X1676638D01*
Y1056731D01*
X1676763Y1057065D01*
X1676930Y1057273D01*
X1677263Y1057356D01*
X1677596Y1057273D01*
X1677805Y1057023D01*
X1677930Y1056731D01*
Y1055690D01*
G01Y1056731D02*
X1679138Y1057356D01*
G01X1678638Y1058706D02*
X1678930Y1058956D01*
X1679096Y1059290D01*
X1679138Y1059665D01*
X1679096Y1059998D01*
X1678888Y1060331D01*
X1678638Y1060540D01*
X1678388Y1060581D01*
X1678096Y1060498D01*
X1677888Y1060206D01*
X1677805Y1059915D01*
Y1059540D01*
G01Y1059915D02*
X1677680Y1060165D01*
X1677471Y1060373D01*
X1677221Y1060456D01*
X1676971Y1060373D01*
X1676763Y1060165D01*
X1676638Y1059790D01*
X1676680Y1059415D01*
X1676846Y1059040D01*
G01X1678763Y1061806D02*
X1678971Y1062056D01*
X1679096Y1062348D01*
X1679138Y1062723D01*
X1679055Y1063098D01*
X1678888Y1063390D01*
X1678596Y1063598D01*
X1678263Y1063640D01*
X1677930Y1063556D01*
X1677721Y1063348D01*
X1677555Y1063056D01*
X1677513Y1062765D01*
X1677555Y1062473D01*
X1677721Y1062098D01*
X1676638Y1062223D01*
Y1063348D01*
G01Y1065823D02*
X1676721Y1065490D01*
X1676930Y1065240D01*
X1677180Y1065073D01*
X1677513Y1064948D01*
X1677888Y1064906D01*
X1678263Y1064948D01*
X1678596Y1065073D01*
X1678846Y1065240D01*
X1679055Y1065490D01*
X1679138Y1065823D01*
X1679055Y1066156D01*
X1678846Y1066406D01*
X1678596Y1066573D01*
X1678263Y1066698D01*
X1677888Y1066740D01*
X1677513Y1066698D01*
X1677180Y1066573D01*
X1676930Y1066406D01*
X1676721Y1066156D01*
X1676638Y1065823D01*
G01X1682138Y1076873D02*
X1678138D01*
Y1069473D01*
G01X1708920Y1077467D02*
X1706420D01*
Y1078508D01*
X1706545Y1078842D01*
X1706712Y1079050D01*
X1707045Y1079133D01*
X1707378Y1079050D01*
X1707587Y1078800D01*
X1707712Y1078508D01*
Y1077467D01*
G01Y1078508D02*
X1708920Y1079133D01*
G01X1708420Y1080483D02*
X1708712Y1080733D01*
X1708878Y1081067D01*
X1708920Y1081442D01*
X1708878Y1081775D01*
X1708670Y1082108D01*
X1708420Y1082317D01*
X1708170Y1082358D01*
X1707878Y1082275D01*
X1707670Y1081983D01*
X1707587Y1081692D01*
Y1081317D01*
G01Y1081692D02*
X1707462Y1081942D01*
X1707253Y1082150D01*
X1707003Y1082233D01*
X1706753Y1082150D01*
X1706545Y1081942D01*
X1706420Y1081567D01*
X1706462Y1081192D01*
X1706628Y1080817D01*
G01X1708545Y1083583D02*
X1708753Y1083833D01*
X1708878Y1084125D01*
X1708920Y1084500D01*
X1708837Y1084875D01*
X1708670Y1085167D01*
X1708378Y1085375D01*
X1708045Y1085417D01*
X1707712Y1085333D01*
X1707503Y1085125D01*
X1707337Y1084833D01*
X1707295Y1084542D01*
X1707337Y1084250D01*
X1707503Y1083875D01*
X1706420Y1084000D01*
Y1085125D01*
G01X1708920Y1087600D02*
X1706420D01*
X1706920Y1087100D01*
G01X1708920D02*
Y1088100D01*
G01X1697138Y1081873D02*
X1701138D01*
Y1089273D01*
G01X1705220Y1077467D02*
X1702720D01*
Y1078508D01*
X1702845Y1078842D01*
X1703012Y1079050D01*
X1703345Y1079133D01*
X1703678Y1079050D01*
X1703887Y1078800D01*
X1704012Y1078508D01*
Y1077467D01*
G01Y1078508D02*
X1705220Y1079133D01*
G01X1704720Y1080483D02*
X1705012Y1080733D01*
X1705178Y1081067D01*
X1705220Y1081442D01*
X1705178Y1081775D01*
X1704970Y1082108D01*
X1704720Y1082317D01*
X1704470Y1082358D01*
X1704178Y1082275D01*
X1703970Y1081983D01*
X1703887Y1081692D01*
Y1081317D01*
G01Y1081692D02*
X1703762Y1081942D01*
X1703553Y1082150D01*
X1703303Y1082233D01*
X1703053Y1082150D01*
X1702845Y1081942D01*
X1702720Y1081567D01*
X1702762Y1081192D01*
X1702928Y1080817D01*
G01X1704845Y1083583D02*
X1705053Y1083833D01*
X1705178Y1084125D01*
X1705220Y1084500D01*
X1705137Y1084875D01*
X1704970Y1085167D01*
X1704678Y1085375D01*
X1704345Y1085417D01*
X1704012Y1085333D01*
X1703803Y1085125D01*
X1703637Y1084833D01*
X1703595Y1084542D01*
X1703637Y1084250D01*
X1703803Y1083875D01*
X1702720Y1084000D01*
Y1085125D01*
G01X1705220Y1088100D02*
X1702720D01*
X1704512Y1086558D01*
Y1088642D01*
G01X1692438Y1081873D02*
X1696438D01*
Y1089273D01*
G01X1671833Y1080900D02*
X1671791Y1080567D01*
X1671625Y1080275D01*
X1671375Y1080025D01*
X1671083Y1079858D01*
X1670750Y1079775D01*
X1670416D01*
X1670083Y1079858D01*
X1669791Y1080025D01*
X1669541Y1080275D01*
X1669375Y1080567D01*
X1669333Y1080900D01*
X1669375Y1081233D01*
X1669541Y1081525D01*
X1669791Y1081775D01*
X1670083Y1081942D01*
X1670416Y1082025D01*
X1670750D01*
X1671083Y1081942D01*
X1671375Y1081775D01*
X1671625Y1081525D01*
X1671791Y1081233D01*
X1671833Y1080900D01*
G01X1671166Y1081233D02*
X1671833Y1081733D01*
G01X1671458Y1083083D02*
X1671666Y1083333D01*
X1671791Y1083625D01*
X1671833Y1084000D01*
X1671750Y1084375D01*
X1671583Y1084667D01*
X1671291Y1084875D01*
X1670958Y1084917D01*
X1670625Y1084833D01*
X1670416Y1084625D01*
X1670250Y1084333D01*
X1670208Y1084042D01*
X1670250Y1083750D01*
X1670416Y1083375D01*
X1669333Y1083500D01*
Y1084625D01*
G01X1671458Y1086183D02*
X1671666Y1086433D01*
X1671791Y1086725D01*
X1671833Y1087100D01*
X1671750Y1087475D01*
X1671583Y1087767D01*
X1671291Y1087975D01*
X1670958Y1088017D01*
X1670625Y1087933D01*
X1670416Y1087725D01*
X1670250Y1087433D01*
X1670208Y1087142D01*
X1670250Y1086850D01*
X1670416Y1086475D01*
X1669333Y1086600D01*
Y1087725D01*
G01X1673438Y1089373D02*
Y1077973D01*
G01X1686838D02*
Y1089373D01*
G01X1673438Y1077973D02*
X1686838D01*
G01X1712017Y1096000D02*
Y1098500D01*
X1713058D01*
X1713392Y1098375D01*
X1713600Y1098208D01*
X1713683Y1097875D01*
X1713600Y1097542D01*
X1713350Y1097333D01*
X1713058Y1097208D01*
X1712017D01*
G01X1713058D02*
X1713683Y1096000D01*
G01X1715033Y1096500D02*
X1715283Y1096208D01*
X1715617Y1096042D01*
X1715992Y1096000D01*
X1716325Y1096042D01*
X1716658Y1096250D01*
X1716867Y1096500D01*
X1716908Y1096750D01*
X1716825Y1097042D01*
X1716533Y1097250D01*
X1716242Y1097333D01*
X1715867D01*
G01X1716242D02*
X1716492Y1097458D01*
X1716700Y1097667D01*
X1716783Y1097917D01*
X1716700Y1098167D01*
X1716492Y1098375D01*
X1716117Y1098500D01*
X1715742Y1098458D01*
X1715367Y1098292D01*
G01X1719550Y1096000D02*
Y1098500D01*
X1718008Y1096708D01*
X1720092D01*
G01X1722650Y1096000D02*
Y1098500D01*
X1721108Y1096708D01*
X1723192D01*
G01X1686338Y1094673D02*
Y1098673D01*
X1678938D01*
G01X1711155Y1127673D02*
Y1130173D01*
X1712196D01*
X1712530Y1130048D01*
X1712738Y1129881D01*
X1712821Y1129548D01*
X1712738Y1129215D01*
X1712488Y1129006D01*
X1712196Y1128881D01*
X1711155D01*
G01X1712196D02*
X1712821Y1127673D01*
G01X1714171Y1128173D02*
X1714421Y1127881D01*
X1714755Y1127715D01*
X1715130Y1127673D01*
X1715463Y1127715D01*
X1715796Y1127923D01*
X1716005Y1128173D01*
X1716046Y1128423D01*
X1715963Y1128715D01*
X1715671Y1128923D01*
X1715380Y1129006D01*
X1715005D01*
G01X1715380D02*
X1715630Y1129131D01*
X1715838Y1129340D01*
X1715921Y1129590D01*
X1715838Y1129840D01*
X1715630Y1130048D01*
X1715255Y1130173D01*
X1714880Y1130131D01*
X1714505Y1129965D01*
G01X1717271Y1128048D02*
X1717521Y1127840D01*
X1717813Y1127715D01*
X1718188Y1127673D01*
X1718563Y1127756D01*
X1718855Y1127923D01*
X1719063Y1128215D01*
X1719105Y1128548D01*
X1719021Y1128881D01*
X1718813Y1129090D01*
X1718521Y1129256D01*
X1718230Y1129298D01*
X1717938Y1129256D01*
X1717563Y1129090D01*
X1717688Y1130173D01*
X1718813D01*
G01X1720496Y1129756D02*
X1720746Y1130006D01*
X1721038Y1130131D01*
X1721371Y1130173D01*
X1721788Y1130090D01*
X1722080Y1129881D01*
X1722163Y1129631D01*
X1722121Y1129381D01*
X1721955Y1129173D01*
X1721121Y1128756D01*
X1720746Y1128465D01*
X1720496Y1128048D01*
X1720413Y1127673D01*
X1722163D01*
G01X1709838Y1127173D02*
Y1131173D01*
X1702438D01*
G01X1699938Y1102173D02*
Y1098173D01*
X1707338D01*
G01X1686838Y1089373D02*
X1673438D01*
G01X1709138Y1090173D02*
X1693038D01*
G01X1709138Y1097173D02*
Y1090173D01*
G01X1693038Y1097173D02*
X1709138D01*
G01X1693038Y1090173D02*
Y1097173D01*
G01X1687900Y1126500D02*
X1687567Y1126542D01*
X1687275Y1126708D01*
X1687025Y1126958D01*
X1686858Y1127250D01*
X1686775Y1127583D01*
Y1127917D01*
X1686858Y1128250D01*
X1687025Y1128542D01*
X1687275Y1128792D01*
X1687567Y1128958D01*
X1687900Y1129000D01*
X1688233Y1128958D01*
X1688525Y1128792D01*
X1688775Y1128542D01*
X1688942Y1128250D01*
X1689025Y1127917D01*
Y1127583D01*
X1688942Y1127250D01*
X1688775Y1126958D01*
X1688525Y1126708D01*
X1688233Y1126542D01*
X1687900Y1126500D01*
G01X1688233Y1127167D02*
X1688733Y1126500D01*
G01X1690083Y1126875D02*
X1690333Y1126667D01*
X1690625Y1126542D01*
X1691000Y1126500D01*
X1691375Y1126583D01*
X1691667Y1126750D01*
X1691875Y1127042D01*
X1691917Y1127375D01*
X1691833Y1127708D01*
X1691625Y1127917D01*
X1691333Y1128083D01*
X1691042Y1128125D01*
X1690750Y1128083D01*
X1690375Y1127917D01*
X1690500Y1129000D01*
X1691625D01*
G01X1694600Y1126500D02*
Y1129000D01*
X1693058Y1127208D01*
X1695142D01*
G01X1693138Y1124373D02*
X1691338Y1122273D01*
X1689138Y1124373D01*
G01X1685538Y1124473D02*
Y1105273D01*
X1696738D01*
Y1124473D01*
X1685538D01*
Y1124073D01*
G01X1712905Y1134065D02*
X1712655Y1134190D01*
X1712363Y1134273D01*
X1712030D01*
X1711655Y1134148D01*
X1711363Y1133940D01*
X1711155Y1133690D01*
X1710988Y1133273D01*
X1710946Y1132898D01*
X1711030Y1132523D01*
X1711155Y1132273D01*
X1711405Y1132023D01*
X1711696Y1131856D01*
X1711988Y1131773D01*
X1712280D01*
X1712571Y1131856D01*
X1712821Y1131981D01*
X1713030Y1132148D01*
G01X1715088Y1131773D02*
Y1134273D01*
X1714588Y1133773D01*
G01Y1131773D02*
X1715588D01*
G01X1717396Y1132815D02*
X1717688Y1133106D01*
X1717938Y1133273D01*
X1718271Y1133356D01*
X1718563Y1133273D01*
X1718771Y1133106D01*
X1718938Y1132856D01*
X1718980Y1132565D01*
X1718938Y1132315D01*
X1718771Y1132065D01*
X1718521Y1131856D01*
X1718230Y1131773D01*
X1717896Y1131856D01*
X1717605Y1132106D01*
X1717438Y1132481D01*
X1717396Y1132898D01*
X1717480Y1133440D01*
X1717605Y1133731D01*
X1717813Y1134023D01*
X1718105Y1134231D01*
X1718396Y1134273D01*
X1718688Y1134190D01*
X1718896Y1133981D01*
G01X1720496Y1132815D02*
X1720788Y1133106D01*
X1721038Y1133273D01*
X1721371Y1133356D01*
X1721663Y1133273D01*
X1721871Y1133106D01*
X1722038Y1132856D01*
X1722080Y1132565D01*
X1722038Y1132315D01*
X1721871Y1132065D01*
X1721621Y1131856D01*
X1721330Y1131773D01*
X1720996Y1131856D01*
X1720705Y1132106D01*
X1720538Y1132481D01*
X1720496Y1132898D01*
X1720580Y1133440D01*
X1720705Y1133731D01*
X1720913Y1134023D01*
X1721205Y1134231D01*
X1721496Y1134273D01*
X1721788Y1134190D01*
X1721996Y1133981D01*
G01X1713905Y1102565D02*
X1713655Y1102690D01*
X1713363Y1102773D01*
X1713030D01*
X1712655Y1102648D01*
X1712363Y1102440D01*
X1712155Y1102190D01*
X1711988Y1101773D01*
X1711946Y1101398D01*
X1712030Y1101023D01*
X1712155Y1100773D01*
X1712405Y1100523D01*
X1712696Y1100356D01*
X1712988Y1100273D01*
X1713280D01*
X1713571Y1100356D01*
X1713821Y1100481D01*
X1714030Y1100648D01*
G01X1716088Y1100273D02*
Y1102773D01*
X1715588Y1102273D01*
G01Y1100273D02*
X1716588D01*
G01X1718396Y1101315D02*
X1718688Y1101606D01*
X1718938Y1101773D01*
X1719271Y1101856D01*
X1719563Y1101773D01*
X1719771Y1101606D01*
X1719938Y1101356D01*
X1719980Y1101065D01*
X1719938Y1100815D01*
X1719771Y1100565D01*
X1719521Y1100356D01*
X1719230Y1100273D01*
X1718896Y1100356D01*
X1718605Y1100606D01*
X1718438Y1100981D01*
X1718396Y1101398D01*
X1718480Y1101940D01*
X1718605Y1102231D01*
X1718813Y1102523D01*
X1719105Y1102731D01*
X1719396Y1102773D01*
X1719688Y1102690D01*
X1719896Y1102481D01*
G01X1721371Y1100648D02*
X1721621Y1100440D01*
X1721913Y1100315D01*
X1722288Y1100273D01*
X1722663Y1100356D01*
X1722955Y1100523D01*
X1723163Y1100815D01*
X1723205Y1101148D01*
X1723121Y1101481D01*
X1722913Y1101690D01*
X1722621Y1101856D01*
X1722330Y1101898D01*
X1722038Y1101856D01*
X1721663Y1101690D01*
X1721788Y1102773D01*
X1722913D01*
G01X1713517Y1144000D02*
Y1146500D01*
X1714558D01*
X1714892Y1146375D01*
X1715100Y1146208D01*
X1715183Y1145875D01*
X1715100Y1145542D01*
X1714850Y1145333D01*
X1714558Y1145208D01*
X1713517D01*
G01X1714558D02*
X1715183Y1144000D01*
G01X1716533Y1144375D02*
X1716783Y1144167D01*
X1717075Y1144042D01*
X1717450Y1144000D01*
X1717825Y1144083D01*
X1718117Y1144250D01*
X1718325Y1144542D01*
X1718367Y1144875D01*
X1718283Y1145208D01*
X1718075Y1145417D01*
X1717783Y1145583D01*
X1717492Y1145625D01*
X1717200Y1145583D01*
X1716825Y1145417D01*
X1716950Y1146500D01*
X1718075D01*
G01X1719842Y1144292D02*
X1720133Y1144083D01*
X1720467Y1144000D01*
X1720800Y1144083D01*
X1721092Y1144333D01*
X1721300Y1144708D01*
X1721383Y1145083D01*
Y1145542D01*
X1721300Y1145917D01*
X1721092Y1146250D01*
X1720842Y1146417D01*
X1720550Y1146500D01*
X1720217Y1146417D01*
X1719967Y1146250D01*
X1719800Y1146000D01*
X1719717Y1145667D01*
X1719800Y1145375D01*
X1720008Y1145083D01*
X1720258Y1144917D01*
X1720550Y1144875D01*
X1720883Y1144958D01*
X1721133Y1145167D01*
X1721383Y1145542D01*
G01X1722733Y1144375D02*
X1722983Y1144167D01*
X1723275Y1144042D01*
X1723650Y1144000D01*
X1724025Y1144083D01*
X1724317Y1144250D01*
X1724525Y1144542D01*
X1724567Y1144875D01*
X1724483Y1145208D01*
X1724275Y1145417D01*
X1723983Y1145583D01*
X1723692Y1145625D01*
X1723400Y1145583D01*
X1723025Y1145417D01*
X1723150Y1146500D01*
X1724275D01*
G01X1672017Y1138000D02*
Y1140500D01*
X1673058D01*
X1673392Y1140375D01*
X1673600Y1140208D01*
X1673683Y1139875D01*
X1673600Y1139542D01*
X1673350Y1139333D01*
X1673058Y1139208D01*
X1672017D01*
G01X1673058D02*
X1673683Y1138000D01*
G01X1675033Y1138500D02*
X1675283Y1138208D01*
X1675617Y1138042D01*
X1675992Y1138000D01*
X1676325Y1138042D01*
X1676658Y1138250D01*
X1676867Y1138500D01*
X1676908Y1138750D01*
X1676825Y1139042D01*
X1676533Y1139250D01*
X1676242Y1139333D01*
X1675867D01*
G01X1676242D02*
X1676492Y1139458D01*
X1676700Y1139667D01*
X1676783Y1139917D01*
X1676700Y1140167D01*
X1676492Y1140375D01*
X1676117Y1140500D01*
X1675742Y1140458D01*
X1675367Y1140292D01*
G01X1678133Y1138500D02*
X1678383Y1138208D01*
X1678717Y1138042D01*
X1679092Y1138000D01*
X1679425Y1138042D01*
X1679758Y1138250D01*
X1679967Y1138500D01*
X1680008Y1138750D01*
X1679925Y1139042D01*
X1679633Y1139250D01*
X1679342Y1139333D01*
X1678967D01*
G01X1679342D02*
X1679592Y1139458D01*
X1679800Y1139667D01*
X1679883Y1139917D01*
X1679800Y1140167D01*
X1679592Y1140375D01*
X1679217Y1140500D01*
X1678842Y1140458D01*
X1678467Y1140292D01*
G01X1681358Y1139042D02*
X1681650Y1139333D01*
X1681900Y1139500D01*
X1682233Y1139583D01*
X1682525Y1139500D01*
X1682733Y1139333D01*
X1682900Y1139083D01*
X1682942Y1138792D01*
X1682900Y1138542D01*
X1682733Y1138292D01*
X1682483Y1138083D01*
X1682192Y1138000D01*
X1681858Y1138083D01*
X1681567Y1138333D01*
X1681400Y1138708D01*
X1681358Y1139125D01*
X1681442Y1139667D01*
X1681567Y1139958D01*
X1681775Y1140250D01*
X1682067Y1140458D01*
X1682358Y1140500D01*
X1682650Y1140417D01*
X1682858Y1140208D01*
G01X1686438Y1150173D02*
Y1142173D01*
X1668838D01*
Y1150173D01*
X1686438D01*
G01X1694890Y1182879D02*
Y1174879D01*
X1677290D01*
Y1182879D01*
X1694890D01*
G01X1673208Y1153267D02*
X1673083Y1153017D01*
X1673000Y1152725D01*
Y1152392D01*
X1673125Y1152017D01*
X1673333Y1151725D01*
X1673583Y1151517D01*
X1674000Y1151350D01*
X1674375Y1151308D01*
X1674750Y1151392D01*
X1675000Y1151517D01*
X1675250Y1151767D01*
X1675417Y1152058D01*
X1675500Y1152350D01*
Y1152642D01*
X1675417Y1152933D01*
X1675292Y1153183D01*
X1675125Y1153392D01*
G01X1675500Y1155450D02*
X1673000D01*
X1673500Y1154950D01*
G01X1675500D02*
Y1155950D01*
G01X1675125Y1157633D02*
X1675333Y1157883D01*
X1675458Y1158175D01*
X1675500Y1158550D01*
X1675417Y1158925D01*
X1675250Y1159217D01*
X1674958Y1159425D01*
X1674625Y1159467D01*
X1674292Y1159383D01*
X1674083Y1159175D01*
X1673917Y1158883D01*
X1673875Y1158592D01*
X1673917Y1158300D01*
X1674083Y1157925D01*
X1673000Y1158050D01*
Y1159175D01*
G01X1675500Y1161650D02*
X1675458Y1161942D01*
X1675333Y1162275D01*
X1675125Y1162483D01*
X1674833Y1162567D01*
X1674542Y1162483D01*
X1674292Y1162233D01*
X1674167Y1161858D01*
Y1161442D01*
X1674083Y1161192D01*
X1673875Y1160983D01*
X1673583Y1160900D01*
X1673292Y1161025D01*
X1673083Y1161317D01*
X1673000Y1161650D01*
X1673083Y1161983D01*
X1673292Y1162275D01*
X1673583Y1162400D01*
X1673875Y1162317D01*
X1674083Y1162108D01*
X1674167Y1161858D01*
Y1161442D01*
X1674292Y1161067D01*
X1674542Y1160817D01*
X1674833Y1160733D01*
X1675125Y1160817D01*
X1675333Y1161025D01*
X1675458Y1161358D01*
X1675500Y1161650D01*
G01X1677138Y1155873D02*
Y1161373D01*
G01X1685138Y1155873D02*
X1677138D01*
G01X1685138Y1161373D02*
Y1155873D01*
G01Y1173473D02*
Y1167973D01*
G01X1677138Y1173473D02*
X1685138D01*
G01X1677138Y1167973D02*
Y1173473D01*
G01X1694400Y1165500D02*
X1694067Y1165542D01*
X1693775Y1165708D01*
X1693525Y1165958D01*
X1693358Y1166250D01*
X1693275Y1166583D01*
Y1166917D01*
X1693358Y1167250D01*
X1693525Y1167542D01*
X1693775Y1167792D01*
X1694067Y1167958D01*
X1694400Y1168000D01*
X1694733Y1167958D01*
X1695025Y1167792D01*
X1695275Y1167542D01*
X1695442Y1167250D01*
X1695525Y1166917D01*
Y1166583D01*
X1695442Y1166250D01*
X1695275Y1165958D01*
X1695025Y1165708D01*
X1694733Y1165542D01*
X1694400Y1165500D01*
G01X1694733Y1166167D02*
X1695233Y1165500D01*
G01X1696583Y1165875D02*
X1696833Y1165667D01*
X1697125Y1165542D01*
X1697500Y1165500D01*
X1697875Y1165583D01*
X1698167Y1165750D01*
X1698375Y1166042D01*
X1698417Y1166375D01*
X1698333Y1166708D01*
X1698125Y1166917D01*
X1697833Y1167083D01*
X1697542Y1167125D01*
X1697250Y1167083D01*
X1696875Y1166917D01*
X1697000Y1168000D01*
X1698125D01*
G01X1699808Y1166542D02*
X1700100Y1166833D01*
X1700350Y1167000D01*
X1700683Y1167083D01*
X1700975Y1167000D01*
X1701183Y1166833D01*
X1701350Y1166583D01*
X1701392Y1166292D01*
X1701350Y1166042D01*
X1701183Y1165792D01*
X1700933Y1165583D01*
X1700642Y1165500D01*
X1700308Y1165583D01*
X1700017Y1165833D01*
X1699850Y1166208D01*
X1699808Y1166625D01*
X1699892Y1167167D01*
X1700017Y1167458D01*
X1700225Y1167750D01*
X1700517Y1167958D01*
X1700808Y1168000D01*
X1701100Y1167917D01*
X1701308Y1167708D01*
G01X1687938Y1151673D02*
X1690038Y1149873D01*
X1687938Y1147673D01*
G01X1687838Y1144073D02*
X1707038D01*
Y1155273D01*
X1687838D01*
Y1144073D01*
X1688238D01*
G01X1670208Y1177767D02*
X1670083Y1177517D01*
X1670000Y1177225D01*
Y1176892D01*
X1670125Y1176517D01*
X1670333Y1176225D01*
X1670583Y1176017D01*
X1671000Y1175850D01*
X1671375Y1175808D01*
X1671750Y1175892D01*
X1672000Y1176017D01*
X1672250Y1176267D01*
X1672417Y1176558D01*
X1672500Y1176850D01*
Y1177142D01*
X1672417Y1177433D01*
X1672292Y1177683D01*
X1672125Y1177892D01*
G01X1672500Y1179950D02*
X1670000D01*
X1670500Y1179450D01*
G01X1672500D02*
Y1180450D01*
G01X1672125Y1182133D02*
X1672333Y1182383D01*
X1672458Y1182675D01*
X1672500Y1183050D01*
X1672417Y1183425D01*
X1672250Y1183717D01*
X1671958Y1183925D01*
X1671625Y1183967D01*
X1671292Y1183883D01*
X1671083Y1183675D01*
X1670917Y1183383D01*
X1670875Y1183092D01*
X1670917Y1182800D01*
X1671083Y1182425D01*
X1670000Y1182550D01*
Y1183675D01*
G01X1672500Y1186067D02*
X1671958Y1186150D01*
X1671500Y1186275D01*
X1671083Y1186442D01*
X1670625Y1186650D01*
X1670000Y1186983D01*
Y1185317D01*
G01X1686517Y1184500D02*
Y1187000D01*
X1687558D01*
X1687892Y1186875D01*
X1688100Y1186708D01*
X1688183Y1186375D01*
X1688100Y1186042D01*
X1687850Y1185833D01*
X1687558Y1185708D01*
X1686517D01*
G01X1687558D02*
X1688183Y1184500D01*
G01X1689533Y1185000D02*
X1689783Y1184708D01*
X1690117Y1184542D01*
X1690492Y1184500D01*
X1690825Y1184542D01*
X1691158Y1184750D01*
X1691367Y1185000D01*
X1691408Y1185250D01*
X1691325Y1185542D01*
X1691033Y1185750D01*
X1690742Y1185833D01*
X1690367D01*
G01X1690742D02*
X1690992Y1185958D01*
X1691200Y1186167D01*
X1691283Y1186417D01*
X1691200Y1186667D01*
X1690992Y1186875D01*
X1690617Y1187000D01*
X1690242Y1186958D01*
X1689867Y1186792D01*
G01X1694050Y1184500D02*
Y1187000D01*
X1692508Y1185208D01*
X1694592D01*
G01X1696650Y1187000D02*
X1696317Y1186917D01*
X1696067Y1186708D01*
X1695900Y1186458D01*
X1695775Y1186125D01*
X1695733Y1185750D01*
X1695775Y1185375D01*
X1695900Y1185042D01*
X1696067Y1184792D01*
X1696317Y1184583D01*
X1696650Y1184500D01*
X1696983Y1184583D01*
X1697233Y1184792D01*
X1697400Y1185042D01*
X1697525Y1185375D01*
X1697567Y1185750D01*
X1697525Y1186125D01*
X1697400Y1186458D01*
X1697233Y1186708D01*
X1696983Y1186917D01*
X1696650Y1187000D01*
G01X1698208Y1194767D02*
X1698083Y1194517D01*
X1698000Y1194225D01*
Y1193892D01*
X1698125Y1193517D01*
X1698333Y1193225D01*
X1698583Y1193017D01*
X1699000Y1192850D01*
X1699375Y1192808D01*
X1699750Y1192892D01*
X1700000Y1193017D01*
X1700250Y1193267D01*
X1700417Y1193558D01*
X1700500Y1193850D01*
Y1194142D01*
X1700417Y1194433D01*
X1700292Y1194683D01*
X1700125Y1194892D01*
G01X1700500Y1196950D02*
X1698000D01*
X1698500Y1196450D01*
G01X1700500D02*
Y1197450D01*
G01X1699458Y1199258D02*
X1699167Y1199550D01*
X1699000Y1199800D01*
X1698917Y1200133D01*
X1699000Y1200425D01*
X1699167Y1200633D01*
X1699417Y1200800D01*
X1699708Y1200842D01*
X1699958Y1200800D01*
X1700208Y1200633D01*
X1700417Y1200383D01*
X1700500Y1200092D01*
X1700417Y1199758D01*
X1700167Y1199467D01*
X1699792Y1199300D01*
X1699375Y1199258D01*
X1698833Y1199342D01*
X1698542Y1199467D01*
X1698250Y1199675D01*
X1698042Y1199967D01*
X1698000Y1200258D01*
X1698083Y1200550D01*
X1698292Y1200758D01*
G01X1698417Y1202358D02*
X1698167Y1202608D01*
X1698042Y1202900D01*
X1698000Y1203233D01*
X1698083Y1203650D01*
X1698292Y1203942D01*
X1698542Y1204025D01*
X1698792Y1203983D01*
X1699000Y1203817D01*
X1699417Y1202983D01*
X1699708Y1202608D01*
X1700125Y1202358D01*
X1700500Y1202275D01*
Y1204025D01*
G01X1694208Y1194767D02*
X1694083Y1194517D01*
X1694000Y1194225D01*
Y1193892D01*
X1694125Y1193517D01*
X1694333Y1193225D01*
X1694583Y1193017D01*
X1695000Y1192850D01*
X1695375Y1192808D01*
X1695750Y1192892D01*
X1696000Y1193017D01*
X1696250Y1193267D01*
X1696417Y1193558D01*
X1696500Y1193850D01*
Y1194142D01*
X1696417Y1194433D01*
X1696292Y1194683D01*
X1696125Y1194892D01*
G01X1696500Y1196950D02*
X1694000D01*
X1694500Y1196450D01*
G01X1696500D02*
Y1197450D01*
G01X1695458Y1199258D02*
X1695167Y1199550D01*
X1695000Y1199800D01*
X1694917Y1200133D01*
X1695000Y1200425D01*
X1695167Y1200633D01*
X1695417Y1200800D01*
X1695708Y1200842D01*
X1695958Y1200800D01*
X1696208Y1200633D01*
X1696417Y1200383D01*
X1696500Y1200092D01*
X1696417Y1199758D01*
X1696167Y1199467D01*
X1695792Y1199300D01*
X1695375Y1199258D01*
X1694833Y1199342D01*
X1694542Y1199467D01*
X1694250Y1199675D01*
X1694042Y1199967D01*
X1694000Y1200258D01*
X1694083Y1200550D01*
X1694292Y1200758D01*
G01X1696500Y1203150D02*
X1694000D01*
X1694500Y1202650D01*
G01X1696500D02*
Y1203650D01*
G01X1690208Y1194767D02*
X1690083Y1194517D01*
X1690000Y1194225D01*
Y1193892D01*
X1690125Y1193517D01*
X1690333Y1193225D01*
X1690583Y1193017D01*
X1691000Y1192850D01*
X1691375Y1192808D01*
X1691750Y1192892D01*
X1692000Y1193017D01*
X1692250Y1193267D01*
X1692417Y1193558D01*
X1692500Y1193850D01*
Y1194142D01*
X1692417Y1194433D01*
X1692292Y1194683D01*
X1692125Y1194892D01*
G01X1692500Y1196950D02*
X1690000D01*
X1690500Y1196450D01*
G01X1692500D02*
Y1197450D01*
G01X1691458Y1199258D02*
X1691167Y1199550D01*
X1691000Y1199800D01*
X1690917Y1200133D01*
X1691000Y1200425D01*
X1691167Y1200633D01*
X1691417Y1200800D01*
X1691708Y1200842D01*
X1691958Y1200800D01*
X1692208Y1200633D01*
X1692417Y1200383D01*
X1692500Y1200092D01*
X1692417Y1199758D01*
X1692167Y1199467D01*
X1691792Y1199300D01*
X1691375Y1199258D01*
X1690833Y1199342D01*
X1690542Y1199467D01*
X1690250Y1199675D01*
X1690042Y1199967D01*
X1690000Y1200258D01*
X1690083Y1200550D01*
X1690292Y1200758D01*
G01X1692500Y1203650D02*
X1690000D01*
X1691792Y1202108D01*
Y1204192D01*
G01X1761643Y221492D02*
X1766693D01*
Y320192D01*
X1791343D01*
Y135792D01*
X1766693D01*
Y194492D01*
X1761643D01*
Y221492D01*
G01X1727017Y193000D02*
Y195500D01*
X1728058D01*
X1728392Y195375D01*
X1728600Y195208D01*
X1728683Y194875D01*
X1728600Y194542D01*
X1728350Y194333D01*
X1728058Y194208D01*
X1727017D01*
G01X1728058D02*
X1728683Y193000D01*
G01X1730242Y193292D02*
X1730533Y193083D01*
X1730867Y193000D01*
X1731200Y193083D01*
X1731492Y193333D01*
X1731700Y193708D01*
X1731783Y194083D01*
Y194542D01*
X1731700Y194917D01*
X1731492Y195250D01*
X1731242Y195417D01*
X1730950Y195500D01*
X1730617Y195417D01*
X1730367Y195250D01*
X1730200Y195000D01*
X1730117Y194667D01*
X1730200Y194375D01*
X1730408Y194083D01*
X1730658Y193917D01*
X1730950Y193875D01*
X1731283Y193958D01*
X1731533Y194167D01*
X1731783Y194542D01*
G01X1734050Y195500D02*
X1733717Y195417D01*
X1733467Y195208D01*
X1733300Y194958D01*
X1733175Y194625D01*
X1733133Y194250D01*
X1733175Y193875D01*
X1733300Y193542D01*
X1733467Y193292D01*
X1733717Y193083D01*
X1734050Y193000D01*
X1734383Y193083D01*
X1734633Y193292D01*
X1734800Y193542D01*
X1734925Y193875D01*
X1734967Y194250D01*
X1734925Y194625D01*
X1734800Y194958D01*
X1734633Y195208D01*
X1734383Y195417D01*
X1734050Y195500D01*
G01X1736233Y193375D02*
X1736483Y193167D01*
X1736775Y193042D01*
X1737150Y193000D01*
X1737525Y193083D01*
X1737817Y193250D01*
X1738025Y193542D01*
X1738067Y193875D01*
X1737983Y194208D01*
X1737775Y194417D01*
X1737483Y194583D01*
X1737192Y194625D01*
X1736900Y194583D01*
X1736525Y194417D01*
X1736650Y195500D01*
X1737775D01*
G01X1727121Y189161D02*
Y191661D01*
X1727955D01*
X1728288Y191536D01*
X1728538Y191369D01*
X1728746Y191119D01*
X1728913Y190828D01*
X1728955Y190411D01*
X1728913Y189994D01*
X1728746Y189703D01*
X1728538Y189453D01*
X1728288Y189286D01*
X1727955Y189161D01*
X1727121D01*
G01X1730221Y189661D02*
X1730471Y189369D01*
X1730805Y189203D01*
X1731180Y189161D01*
X1731513Y189203D01*
X1731846Y189411D01*
X1732055Y189661D01*
X1732096Y189911D01*
X1732013Y190203D01*
X1731721Y190411D01*
X1731430Y190494D01*
X1731055D01*
G01X1731430D02*
X1731680Y190619D01*
X1731888Y190828D01*
X1731971Y191078D01*
X1731888Y191328D01*
X1731680Y191536D01*
X1731305Y191661D01*
X1730930Y191619D01*
X1730555Y191453D01*
G01X1733321Y189661D02*
X1733571Y189369D01*
X1733905Y189203D01*
X1734280Y189161D01*
X1734613Y189203D01*
X1734946Y189411D01*
X1735155Y189661D01*
X1735196Y189911D01*
X1735113Y190203D01*
X1734821Y190411D01*
X1734530Y190494D01*
X1734155D01*
G01X1734530D02*
X1734780Y190619D01*
X1734988Y190828D01*
X1735071Y191078D01*
X1734988Y191328D01*
X1734780Y191536D01*
X1734405Y191661D01*
X1734030Y191619D01*
X1733655Y191453D01*
G01X1742895Y172684D02*
X1742645Y172809D01*
X1742353Y172892D01*
X1742020D01*
X1741645Y172767D01*
X1741353Y172559D01*
X1741145Y172309D01*
X1740978Y171892D01*
X1740936Y171517D01*
X1741020Y171142D01*
X1741145Y170892D01*
X1741395Y170642D01*
X1741686Y170475D01*
X1741978Y170392D01*
X1742270D01*
X1742561Y170475D01*
X1742811Y170600D01*
X1743020Y170767D01*
G01X1745578Y170392D02*
Y172892D01*
X1744036Y171100D01*
X1746120D01*
G01X1748178Y170392D02*
X1748470Y170434D01*
X1748803Y170559D01*
X1749011Y170767D01*
X1749095Y171059D01*
X1749011Y171350D01*
X1748761Y171600D01*
X1748386Y171725D01*
X1747970D01*
X1747720Y171809D01*
X1747511Y172017D01*
X1747428Y172309D01*
X1747553Y172600D01*
X1747845Y172809D01*
X1748178Y172892D01*
X1748511Y172809D01*
X1748803Y172600D01*
X1748928Y172309D01*
X1748845Y172017D01*
X1748636Y171809D01*
X1748386Y171725D01*
X1747970D01*
X1747595Y171600D01*
X1747345Y171350D01*
X1747261Y171059D01*
X1747345Y170767D01*
X1747553Y170559D01*
X1747886Y170434D01*
X1748178Y170392D01*
G01X1751278D02*
Y172892D01*
X1750778Y172392D01*
G01Y170392D02*
X1751778D01*
G01X1742767Y176792D02*
X1742517Y176917D01*
X1742225Y177000D01*
X1741892D01*
X1741517Y176875D01*
X1741225Y176667D01*
X1741017Y176417D01*
X1740850Y176000D01*
X1740808Y175625D01*
X1740892Y175250D01*
X1741017Y175000D01*
X1741267Y174750D01*
X1741558Y174583D01*
X1741850Y174500D01*
X1742142D01*
X1742433Y174583D01*
X1742683Y174708D01*
X1742892Y174875D01*
G01X1745450Y174500D02*
Y177000D01*
X1743908Y175208D01*
X1745992D01*
G01X1748050Y174500D02*
X1748342Y174542D01*
X1748675Y174667D01*
X1748883Y174875D01*
X1748967Y175167D01*
X1748883Y175458D01*
X1748633Y175708D01*
X1748258Y175833D01*
X1747842D01*
X1747592Y175917D01*
X1747383Y176125D01*
X1747300Y176417D01*
X1747425Y176708D01*
X1747717Y176917D01*
X1748050Y177000D01*
X1748383Y176917D01*
X1748675Y176708D01*
X1748800Y176417D01*
X1748717Y176125D01*
X1748508Y175917D01*
X1748258Y175833D01*
X1747842D01*
X1747467Y175708D01*
X1747217Y175458D01*
X1747133Y175167D01*
X1747217Y174875D01*
X1747425Y174667D01*
X1747758Y174542D01*
X1748050Y174500D01*
G01X1751150Y177000D02*
X1750817Y176917D01*
X1750567Y176708D01*
X1750400Y176458D01*
X1750275Y176125D01*
X1750233Y175750D01*
X1750275Y175375D01*
X1750400Y175042D01*
X1750567Y174792D01*
X1750817Y174583D01*
X1751150Y174500D01*
X1751483Y174583D01*
X1751733Y174792D01*
X1751900Y175042D01*
X1752025Y175375D01*
X1752067Y175750D01*
X1752025Y176125D01*
X1751900Y176458D01*
X1751733Y176708D01*
X1751483Y176917D01*
X1751150Y177000D01*
G01X1732567Y243661D02*
Y246161D01*
X1733608D01*
X1733942Y246036D01*
X1734150Y245869D01*
X1734233Y245536D01*
X1734150Y245203D01*
X1733900Y244994D01*
X1733608Y244869D01*
X1732567D01*
G01X1733608D02*
X1734233Y243661D01*
G01X1735792Y243953D02*
X1736083Y243744D01*
X1736417Y243661D01*
X1736750Y243744D01*
X1737042Y243994D01*
X1737250Y244369D01*
X1737333Y244744D01*
Y245203D01*
X1737250Y245578D01*
X1737042Y245911D01*
X1736792Y246078D01*
X1736500Y246161D01*
X1736167Y246078D01*
X1735917Y245911D01*
X1735750Y245661D01*
X1735667Y245328D01*
X1735750Y245036D01*
X1735958Y244744D01*
X1736208Y244578D01*
X1736500Y244536D01*
X1736833Y244619D01*
X1737083Y244828D01*
X1737333Y245203D01*
G01X1739600Y243661D02*
Y246161D01*
X1739100Y245661D01*
G01Y243661D02*
X1740100D01*
G01X1741908Y245744D02*
X1742158Y245994D01*
X1742450Y246119D01*
X1742783Y246161D01*
X1743200Y246078D01*
X1743492Y245869D01*
X1743575Y245619D01*
X1743533Y245369D01*
X1743367Y245161D01*
X1742533Y244744D01*
X1742158Y244453D01*
X1741908Y244036D01*
X1741825Y243661D01*
X1743575D01*
G01X1748350Y246661D02*
Y242661D01*
X1755750D01*
G01X1733017Y255000D02*
Y257500D01*
X1734058D01*
X1734392Y257375D01*
X1734600Y257208D01*
X1734683Y256875D01*
X1734600Y256542D01*
X1734350Y256333D01*
X1734058Y256208D01*
X1733017D01*
G01X1734058D02*
X1734683Y255000D01*
G01X1736242Y255292D02*
X1736533Y255083D01*
X1736867Y255000D01*
X1737200Y255083D01*
X1737492Y255333D01*
X1737700Y255708D01*
X1737783Y256083D01*
Y256542D01*
X1737700Y256917D01*
X1737492Y257250D01*
X1737242Y257417D01*
X1736950Y257500D01*
X1736617Y257417D01*
X1736367Y257250D01*
X1736200Y257000D01*
X1736117Y256667D01*
X1736200Y256375D01*
X1736408Y256083D01*
X1736658Y255917D01*
X1736950Y255875D01*
X1737283Y255958D01*
X1737533Y256167D01*
X1737783Y256542D01*
G01X1740050Y255000D02*
Y257500D01*
X1739550Y257000D01*
G01Y255000D02*
X1740550D01*
G01X1742358Y256042D02*
X1742650Y256333D01*
X1742900Y256500D01*
X1743233Y256583D01*
X1743525Y256500D01*
X1743733Y256333D01*
X1743900Y256083D01*
X1743942Y255792D01*
X1743900Y255542D01*
X1743733Y255292D01*
X1743483Y255083D01*
X1743192Y255000D01*
X1742858Y255083D01*
X1742567Y255333D01*
X1742400Y255708D01*
X1742358Y256125D01*
X1742442Y256667D01*
X1742567Y256958D01*
X1742775Y257250D01*
X1743067Y257458D01*
X1743358Y257500D01*
X1743650Y257417D01*
X1743858Y257208D01*
G01X1734317Y241853D02*
X1734067Y241978D01*
X1733775Y242061D01*
X1733442D01*
X1733067Y241936D01*
X1732775Y241728D01*
X1732567Y241478D01*
X1732400Y241061D01*
X1732358Y240686D01*
X1732442Y240311D01*
X1732567Y240061D01*
X1732817Y239811D01*
X1733108Y239644D01*
X1733400Y239561D01*
X1733692D01*
X1733983Y239644D01*
X1734233Y239769D01*
X1734442Y239936D01*
G01X1737000Y239561D02*
Y242061D01*
X1735458Y240269D01*
X1737542D01*
G01X1739600Y239561D02*
X1739892Y239603D01*
X1740225Y239728D01*
X1740433Y239936D01*
X1740517Y240228D01*
X1740433Y240519D01*
X1740183Y240769D01*
X1739808Y240894D01*
X1739392D01*
X1739142Y240978D01*
X1738933Y241186D01*
X1738850Y241478D01*
X1738975Y241769D01*
X1739267Y241978D01*
X1739600Y242061D01*
X1739933Y241978D01*
X1740225Y241769D01*
X1740350Y241478D01*
X1740267Y241186D01*
X1740058Y240978D01*
X1739808Y240894D01*
X1739392D01*
X1739017Y240769D01*
X1738767Y240519D01*
X1738683Y240228D01*
X1738767Y239936D01*
X1738975Y239728D01*
X1739308Y239603D01*
X1739600Y239561D01*
G01X1742617D02*
X1742700Y240103D01*
X1742825Y240561D01*
X1742992Y240978D01*
X1743200Y241436D01*
X1743533Y242061D01*
X1741867D01*
G01X1731800Y271166D02*
Y268666D01*
G01X1730842Y271166D02*
X1732758D01*
G01X1734067Y268666D02*
Y271166D01*
X1735067D01*
X1735400Y271041D01*
X1735650Y270749D01*
X1735733Y270416D01*
X1735650Y270083D01*
X1735442Y269833D01*
X1735067Y269708D01*
X1734067D01*
G01X1738000Y268666D02*
Y271166D01*
X1737500Y270666D01*
G01Y268666D02*
X1738500D01*
G01X1741017D02*
X1741100Y269208D01*
X1741225Y269666D01*
X1741392Y270083D01*
X1741600Y270541D01*
X1741933Y271166D01*
X1740267D01*
G01X1743408Y270749D02*
X1743658Y270999D01*
X1743950Y271124D01*
X1744283Y271166D01*
X1744700Y271083D01*
X1744992Y270874D01*
X1745075Y270624D01*
X1745033Y270374D01*
X1744867Y270166D01*
X1744033Y269749D01*
X1743658Y269458D01*
X1743408Y269041D01*
X1743325Y268666D01*
X1745075D01*
G01X1729556Y382654D02*
Y385154D01*
X1731140D01*
G01X1730556Y383946D02*
X1729556D01*
G01X1732615Y385154D02*
Y382654D01*
X1734281D01*
G01X1737381D02*
X1735715D01*
Y385154D01*
X1737381D01*
G01X1736715Y383946D02*
X1735715D01*
G01X1738731Y382654D02*
Y385154D01*
X1739565D01*
X1739898Y385029D01*
X1740148Y384862D01*
X1740356Y384612D01*
X1740523Y384321D01*
X1740565Y383904D01*
X1740523Y383487D01*
X1740356Y383196D01*
X1740148Y382946D01*
X1739898Y382779D01*
X1739565Y382654D01*
X1738731D01*
G01X1741956Y384737D02*
X1742206Y384987D01*
X1742498Y385112D01*
X1742831Y385154D01*
X1743248Y385071D01*
X1743540Y384862D01*
X1743623Y384612D01*
X1743581Y384362D01*
X1743415Y384154D01*
X1742581Y383737D01*
X1742206Y383446D01*
X1741956Y383029D01*
X1741873Y382654D01*
X1743623D01*
G01X1744931Y383154D02*
X1745181Y382862D01*
X1745515Y382696D01*
X1745890Y382654D01*
X1746223Y382696D01*
X1746556Y382904D01*
X1746765Y383154D01*
X1746806Y383404D01*
X1746723Y383696D01*
X1746431Y383904D01*
X1746140Y383987D01*
X1745765D01*
G01X1746140D02*
X1746390Y384112D01*
X1746598Y384321D01*
X1746681Y384571D01*
X1746598Y384821D01*
X1746390Y385029D01*
X1746015Y385154D01*
X1745640Y385112D01*
X1745265Y384946D01*
G01X1733198Y366054D02*
Y377254D01*
X1741998D01*
Y366054D01*
X1733198D01*
G01X1717957Y495853D02*
Y509853D01*
G01X1720916Y490352D02*
X1720583Y490394D01*
X1720291Y490560D01*
X1720041Y490810D01*
X1719874Y491102D01*
X1719791Y491435D01*
Y491769D01*
X1719874Y492102D01*
X1720041Y492394D01*
X1720291Y492644D01*
X1720583Y492810D01*
X1720916Y492852D01*
X1721249Y492810D01*
X1721541Y492644D01*
X1721791Y492394D01*
X1721958Y492102D01*
X1722041Y491769D01*
Y491435D01*
X1721958Y491102D01*
X1721791Y490810D01*
X1721541Y490560D01*
X1721249Y490394D01*
X1720916Y490352D01*
G01X1721249Y491019D02*
X1721749Y490352D01*
G01X1723224Y492435D02*
X1723474Y492685D01*
X1723766Y492810D01*
X1724099Y492852D01*
X1724516Y492769D01*
X1724808Y492560D01*
X1724891Y492310D01*
X1724849Y492060D01*
X1724683Y491852D01*
X1723849Y491435D01*
X1723474Y491144D01*
X1723224Y490727D01*
X1723141Y490352D01*
X1724891D01*
G01X1727616D02*
Y492852D01*
X1726074Y491060D01*
X1728158D01*
G01X1729508Y490644D02*
X1729799Y490435D01*
X1730133Y490352D01*
X1730466Y490435D01*
X1730758Y490685D01*
X1730966Y491060D01*
X1731049Y491435D01*
Y491894D01*
X1730966Y492269D01*
X1730758Y492602D01*
X1730508Y492769D01*
X1730216Y492852D01*
X1729883Y492769D01*
X1729633Y492602D01*
X1729466Y492352D01*
X1729383Y492019D01*
X1729466Y491727D01*
X1729674Y491435D01*
X1729924Y491269D01*
X1730216Y491227D01*
X1730549Y491310D01*
X1730799Y491519D01*
X1731049Y491894D01*
G01X1732066Y495852D02*
Y509852D01*
G01X1719066Y495852D02*
X1732066D01*
G01X1719066Y509852D02*
Y495852D01*
G01X1751019Y496017D02*
X1748519D01*
Y497058D01*
X1748644Y497392D01*
X1748811Y497600D01*
X1749144Y497683D01*
X1749477Y497600D01*
X1749686Y497350D01*
X1749811Y497058D01*
Y496017D01*
G01Y497058D02*
X1751019Y497683D01*
G01X1750519Y499033D02*
X1750811Y499283D01*
X1750977Y499617D01*
X1751019Y499992D01*
X1750977Y500325D01*
X1750769Y500658D01*
X1750519Y500867D01*
X1750269Y500908D01*
X1749977Y500825D01*
X1749769Y500533D01*
X1749686Y500242D01*
Y499867D01*
G01Y500242D02*
X1749561Y500492D01*
X1749352Y500700D01*
X1749102Y500783D01*
X1748852Y500700D01*
X1748644Y500492D01*
X1748519Y500117D01*
X1748561Y499742D01*
X1748727Y499367D01*
G01X1751019Y503550D02*
X1748519D01*
X1750311Y502008D01*
Y504092D01*
G01X1748936Y505358D02*
X1748686Y505608D01*
X1748561Y505900D01*
X1748519Y506233D01*
X1748602Y506650D01*
X1748811Y506942D01*
X1749061Y507025D01*
X1749311Y506983D01*
X1749519Y506817D01*
X1749936Y505983D01*
X1750227Y505608D01*
X1750644Y505358D01*
X1751019Y505275D01*
Y507025D01*
G01X1746019Y496017D02*
X1743519D01*
Y497058D01*
X1743644Y497392D01*
X1743811Y497600D01*
X1744144Y497683D01*
X1744477Y497600D01*
X1744686Y497350D01*
X1744811Y497058D01*
Y496017D01*
G01Y497058D02*
X1746019Y497683D01*
G01X1745519Y499033D02*
X1745811Y499283D01*
X1745977Y499617D01*
X1746019Y499992D01*
X1745977Y500325D01*
X1745769Y500658D01*
X1745519Y500867D01*
X1745269Y500908D01*
X1744977Y500825D01*
X1744769Y500533D01*
X1744686Y500242D01*
Y499867D01*
G01Y500242D02*
X1744561Y500492D01*
X1744352Y500700D01*
X1744102Y500783D01*
X1743852Y500700D01*
X1743644Y500492D01*
X1743519Y500117D01*
X1743561Y499742D01*
X1743727Y499367D01*
G01X1745519Y502133D02*
X1745811Y502383D01*
X1745977Y502717D01*
X1746019Y503092D01*
X1745977Y503425D01*
X1745769Y503758D01*
X1745519Y503967D01*
X1745269Y504008D01*
X1744977Y503925D01*
X1744769Y503633D01*
X1744686Y503342D01*
Y502967D01*
G01Y503342D02*
X1744561Y503592D01*
X1744352Y503800D01*
X1744102Y503883D01*
X1743852Y503800D01*
X1743644Y503592D01*
X1743519Y503217D01*
X1743561Y502842D01*
X1743727Y502467D01*
G01X1745727Y505442D02*
X1745936Y505733D01*
X1746019Y506067D01*
X1745936Y506400D01*
X1745686Y506692D01*
X1745311Y506900D01*
X1744936Y506983D01*
X1744477D01*
X1744102Y506900D01*
X1743769Y506692D01*
X1743602Y506442D01*
X1743519Y506150D01*
X1743602Y505817D01*
X1743769Y505567D01*
X1744019Y505400D01*
X1744352Y505317D01*
X1744644Y505400D01*
X1744936Y505608D01*
X1745102Y505858D01*
X1745144Y506150D01*
X1745061Y506483D01*
X1744852Y506733D01*
X1744477Y506983D01*
G01X1717977Y520665D02*
Y523165D01*
X1719018D01*
X1719352Y523040D01*
X1719560Y522873D01*
X1719643Y522540D01*
X1719560Y522207D01*
X1719310Y521998D01*
X1719018Y521873D01*
X1717977D01*
G01X1719018D02*
X1719643Y520665D01*
G01X1720993Y521040D02*
X1721243Y520832D01*
X1721535Y520707D01*
X1721910Y520665D01*
X1722285Y520748D01*
X1722577Y520915D01*
X1722785Y521207D01*
X1722827Y521540D01*
X1722743Y521873D01*
X1722535Y522082D01*
X1722243Y522248D01*
X1721952Y522290D01*
X1721660Y522248D01*
X1721285Y522082D01*
X1721410Y523165D01*
X1722535D01*
G01X1725510Y520665D02*
Y523165D01*
X1723968Y521373D01*
X1726052D01*
G01X1727318Y521707D02*
X1727610Y521998D01*
X1727860Y522165D01*
X1728193Y522248D01*
X1728485Y522165D01*
X1728693Y521998D01*
X1728860Y521748D01*
X1728902Y521457D01*
X1728860Y521207D01*
X1728693Y520957D01*
X1728443Y520748D01*
X1728152Y520665D01*
X1727818Y520748D01*
X1727527Y520998D01*
X1727360Y521373D01*
X1727318Y521790D01*
X1727402Y522332D01*
X1727527Y522623D01*
X1727735Y522915D01*
X1728027Y523123D01*
X1728318Y523165D01*
X1728610Y523082D01*
X1728818Y522873D01*
G01X1727160Y511165D02*
Y515165D01*
X1719760D01*
G01X1732066Y509852D02*
X1719066D01*
G01X1761643Y674248D02*
X1766693D01*
Y772948D01*
X1791343D01*
Y588548D01*
X1766693D01*
Y647248D01*
X1761643D01*
Y674248D01*
G01X1745517Y721000D02*
Y723500D01*
X1746558D01*
X1746892Y723375D01*
X1747100Y723208D01*
X1747183Y722875D01*
X1747100Y722542D01*
X1746850Y722333D01*
X1746558Y722208D01*
X1745517D01*
G01X1746558D02*
X1747183Y721000D01*
G01X1748658Y722042D02*
X1748950Y722333D01*
X1749200Y722500D01*
X1749533Y722583D01*
X1749825Y722500D01*
X1750033Y722333D01*
X1750200Y722083D01*
X1750242Y721792D01*
X1750200Y721542D01*
X1750033Y721292D01*
X1749783Y721083D01*
X1749492Y721000D01*
X1749158Y721083D01*
X1748867Y721333D01*
X1748700Y721708D01*
X1748658Y722125D01*
X1748742Y722667D01*
X1748867Y722958D01*
X1749075Y723250D01*
X1749367Y723458D01*
X1749658Y723500D01*
X1749950Y723417D01*
X1750158Y723208D01*
G01X1751633Y721500D02*
X1751883Y721208D01*
X1752217Y721042D01*
X1752592Y721000D01*
X1752925Y721042D01*
X1753258Y721250D01*
X1753467Y721500D01*
X1753508Y721750D01*
X1753425Y722042D01*
X1753133Y722250D01*
X1752842Y722333D01*
X1752467D01*
G01X1752842D02*
X1753092Y722458D01*
X1753300Y722667D01*
X1753383Y722917D01*
X1753300Y723167D01*
X1753092Y723375D01*
X1752717Y723500D01*
X1752342Y723458D01*
X1751967Y723292D01*
G01X1754858Y722042D02*
X1755150Y722333D01*
X1755400Y722500D01*
X1755733Y722583D01*
X1756025Y722500D01*
X1756233Y722333D01*
X1756400Y722083D01*
X1756442Y721792D01*
X1756400Y721542D01*
X1756233Y721292D01*
X1755983Y721083D01*
X1755692Y721000D01*
X1755358Y721083D01*
X1755067Y721333D01*
X1754900Y721708D01*
X1754858Y722125D01*
X1754942Y722667D01*
X1755067Y722958D01*
X1755275Y723250D01*
X1755567Y723458D01*
X1755858Y723500D01*
X1756150Y723417D01*
X1756358Y723208D01*
G01X1765200Y718500D02*
Y722500D01*
X1757800D01*
G01X1756000Y726517D02*
X1753500D01*
Y727558D01*
X1753625Y727892D01*
X1753792Y728100D01*
X1754125Y728183D01*
X1754458Y728100D01*
X1754667Y727850D01*
X1754792Y727558D01*
Y726517D01*
G01Y727558D02*
X1756000Y728183D01*
G01X1754958Y729658D02*
X1754667Y729950D01*
X1754500Y730200D01*
X1754417Y730533D01*
X1754500Y730825D01*
X1754667Y731033D01*
X1754917Y731200D01*
X1755208Y731242D01*
X1755458Y731200D01*
X1755708Y731033D01*
X1755917Y730783D01*
X1756000Y730492D01*
X1755917Y730158D01*
X1755667Y729867D01*
X1755292Y729700D01*
X1754875Y729658D01*
X1754333Y729742D01*
X1754042Y729867D01*
X1753750Y730075D01*
X1753542Y730367D01*
X1753500Y730658D01*
X1753583Y730950D01*
X1753792Y731158D01*
G01X1756000Y734050D02*
X1753500D01*
X1755292Y732508D01*
Y734592D01*
G01X1753500Y736650D02*
X1753583Y736317D01*
X1753792Y736067D01*
X1754042Y735900D01*
X1754375Y735775D01*
X1754750Y735733D01*
X1755125Y735775D01*
X1755458Y735900D01*
X1755708Y736067D01*
X1755917Y736317D01*
X1756000Y736650D01*
X1755917Y736983D01*
X1755708Y737233D01*
X1755458Y737400D01*
X1755125Y737525D01*
X1754750Y737567D01*
X1754375Y737525D01*
X1754042Y737400D01*
X1753792Y737233D01*
X1753583Y736983D01*
X1753500Y736650D01*
G01X1747267Y719292D02*
X1747017Y719417D01*
X1746725Y719500D01*
X1746392D01*
X1746017Y719375D01*
X1745725Y719167D01*
X1745517Y718917D01*
X1745350Y718500D01*
X1745308Y718125D01*
X1745392Y717750D01*
X1745517Y717500D01*
X1745767Y717250D01*
X1746058Y717083D01*
X1746350Y717000D01*
X1746642D01*
X1746933Y717083D01*
X1747183Y717208D01*
X1747392Y717375D01*
G01X1748533Y717500D02*
X1748783Y717208D01*
X1749117Y717042D01*
X1749492Y717000D01*
X1749825Y717042D01*
X1750158Y717250D01*
X1750367Y717500D01*
X1750408Y717750D01*
X1750325Y718042D01*
X1750033Y718250D01*
X1749742Y718333D01*
X1749367D01*
G01X1749742D02*
X1749992Y718458D01*
X1750200Y718667D01*
X1750283Y718917D01*
X1750200Y719167D01*
X1749992Y719375D01*
X1749617Y719500D01*
X1749242Y719458D01*
X1748867Y719292D01*
G01X1751633Y717500D02*
X1751883Y717208D01*
X1752217Y717042D01*
X1752592Y717000D01*
X1752925Y717042D01*
X1753258Y717250D01*
X1753467Y717500D01*
X1753508Y717750D01*
X1753425Y718042D01*
X1753133Y718250D01*
X1752842Y718333D01*
X1752467D01*
G01X1752842D02*
X1753092Y718458D01*
X1753300Y718667D01*
X1753383Y718917D01*
X1753300Y719167D01*
X1753092Y719375D01*
X1752717Y719500D01*
X1752342Y719458D01*
X1751967Y719292D01*
G01X1755650Y717000D02*
Y719500D01*
X1755150Y719000D01*
G01Y717000D02*
X1756150D01*
G01X1750300Y762500D02*
Y760000D01*
G01X1749342Y762500D02*
X1751258D01*
G01X1752567Y760000D02*
Y762500D01*
X1753567D01*
X1753900Y762375D01*
X1754150Y762083D01*
X1754233Y761750D01*
X1754150Y761417D01*
X1753942Y761167D01*
X1753567Y761042D01*
X1752567D01*
G01X1756500Y760000D02*
Y762500D01*
X1756000Y762000D01*
G01Y760000D02*
X1757000D01*
G01X1759600D02*
Y762500D01*
X1759100Y762000D01*
G01Y760000D02*
X1760100D01*
G01X1761908Y762083D02*
X1762158Y762333D01*
X1762450Y762458D01*
X1762783Y762500D01*
X1763200Y762417D01*
X1763492Y762208D01*
X1763575Y761958D01*
X1763533Y761708D01*
X1763367Y761500D01*
X1762533Y761083D01*
X1762158Y760792D01*
X1761908Y760375D01*
X1761825Y760000D01*
X1763575D01*
G01X1733342Y837132D02*
Y839632D01*
X1734926D01*
G01X1734342Y838424D02*
X1733342D01*
G01X1736401Y839632D02*
Y837132D01*
X1738067D01*
G01X1741167D02*
X1739501D01*
Y839632D01*
X1741167D01*
G01X1740501Y838424D02*
X1739501D01*
G01X1742517Y837132D02*
Y839632D01*
X1743351D01*
X1743684Y839507D01*
X1743934Y839340D01*
X1744142Y839090D01*
X1744309Y838799D01*
X1744351Y838382D01*
X1744309Y837965D01*
X1744142Y837674D01*
X1743934Y837424D01*
X1743684Y837257D01*
X1743351Y837132D01*
X1742517D01*
G01X1746534D02*
Y839632D01*
X1746034Y839132D01*
G01Y837132D02*
X1747034D01*
G01X1749634D02*
Y839632D01*
X1749134Y839132D01*
G01Y837132D02*
X1750134D01*
G01X1733198Y818809D02*
Y830009D01*
X1741998D01*
Y818809D01*
X1733198D01*
G01X1765334Y963756D02*
Y967756D01*
X1757934D01*
G01X1728855Y964743D02*
Y967243D01*
X1729896D01*
X1730230Y967118D01*
X1730438Y966951D01*
X1730521Y966618D01*
X1730438Y966285D01*
X1730188Y966076D01*
X1729896Y965951D01*
X1728855D01*
G01X1729896D02*
X1730521Y964743D01*
G01X1733288D02*
Y967243D01*
X1731746Y965451D01*
X1733830D01*
G01X1735180Y965035D02*
X1735471Y964826D01*
X1735805Y964743D01*
X1736138Y964826D01*
X1736430Y965076D01*
X1736638Y965451D01*
X1736721Y965826D01*
Y966285D01*
X1736638Y966660D01*
X1736430Y966993D01*
X1736180Y967160D01*
X1735888Y967243D01*
X1735555Y967160D01*
X1735305Y966993D01*
X1735138Y966743D01*
X1735055Y966410D01*
X1735138Y966118D01*
X1735346Y965826D01*
X1735596Y965660D01*
X1735888Y965618D01*
X1736221Y965701D01*
X1736471Y965910D01*
X1736721Y966285D01*
G01X1739488Y964743D02*
Y967243D01*
X1737946Y965451D01*
X1740030D01*
G01X1751136Y963664D02*
Y967664D01*
X1743736D01*
G01X1744423Y944443D02*
X1744090Y944485D01*
X1743798Y944651D01*
X1743548Y944901D01*
X1743381Y945193D01*
X1743298Y945526D01*
Y945860D01*
X1743381Y946193D01*
X1743548Y946485D01*
X1743798Y946735D01*
X1744090Y946901D01*
X1744423Y946943D01*
X1744756Y946901D01*
X1745048Y946735D01*
X1745298Y946485D01*
X1745465Y946193D01*
X1745548Y945860D01*
Y945526D01*
X1745465Y945193D01*
X1745298Y944901D01*
X1745048Y944651D01*
X1744756Y944485D01*
X1744423Y944443D01*
G01X1744756Y945110D02*
X1745256Y944443D01*
G01X1746731Y946526D02*
X1746981Y946776D01*
X1747273Y946901D01*
X1747606Y946943D01*
X1748023Y946860D01*
X1748315Y946651D01*
X1748398Y946401D01*
X1748356Y946151D01*
X1748190Y945943D01*
X1747356Y945526D01*
X1746981Y945235D01*
X1746731Y944818D01*
X1746648Y944443D01*
X1748398D01*
G01X1750540D02*
X1750623Y944985D01*
X1750748Y945443D01*
X1750915Y945860D01*
X1751123Y946318D01*
X1751456Y946943D01*
X1749790D01*
G01X1752806Y944943D02*
X1753056Y944651D01*
X1753390Y944485D01*
X1753765Y944443D01*
X1754098Y944485D01*
X1754431Y944693D01*
X1754640Y944943D01*
X1754681Y945193D01*
X1754598Y945485D01*
X1754306Y945693D01*
X1754015Y945776D01*
X1753640D01*
G01X1754015D02*
X1754265Y945901D01*
X1754473Y946110D01*
X1754556Y946360D01*
X1754473Y946610D01*
X1754265Y946818D01*
X1753890Y946943D01*
X1753515Y946901D01*
X1753140Y946735D01*
G01X1756073Y948943D02*
Y962943D01*
G01X1743073Y948943D02*
X1756073D01*
G01X1743073Y962943D02*
Y948943D01*
G01X1756073Y962943D02*
X1743073D01*
G01X1758615Y944484D02*
X1758282Y944526D01*
X1757990Y944692D01*
X1757740Y944942D01*
X1757573Y945234D01*
X1757490Y945567D01*
Y945901D01*
X1757573Y946234D01*
X1757740Y946526D01*
X1757990Y946776D01*
X1758282Y946942D01*
X1758615Y946984D01*
X1758948Y946942D01*
X1759240Y946776D01*
X1759490Y946526D01*
X1759657Y946234D01*
X1759740Y945901D01*
Y945567D01*
X1759657Y945234D01*
X1759490Y944942D01*
X1759240Y944692D01*
X1758948Y944526D01*
X1758615Y944484D01*
G01X1758948Y945151D02*
X1759448Y944484D01*
G01X1760923Y946567D02*
X1761173Y946817D01*
X1761465Y946942D01*
X1761798Y946984D01*
X1762215Y946901D01*
X1762507Y946692D01*
X1762590Y946442D01*
X1762548Y946192D01*
X1762382Y945984D01*
X1761548Y945567D01*
X1761173Y945276D01*
X1760923Y944859D01*
X1760840Y944484D01*
X1762590D01*
G01X1763898Y944984D02*
X1764148Y944692D01*
X1764482Y944526D01*
X1764857Y944484D01*
X1765190Y944526D01*
X1765523Y944734D01*
X1765732Y944984D01*
X1765773Y945234D01*
X1765690Y945526D01*
X1765398Y945734D01*
X1765107Y945817D01*
X1764732D01*
G01X1765107D02*
X1765357Y945942D01*
X1765565Y946151D01*
X1765648Y946401D01*
X1765565Y946651D01*
X1765357Y946859D01*
X1764982Y946984D01*
X1764607Y946942D01*
X1764232Y946776D01*
G01X1767832Y944484D02*
X1767915Y945026D01*
X1768040Y945484D01*
X1768207Y945901D01*
X1768415Y946359D01*
X1768748Y946984D01*
X1767082D01*
G01X1757265Y948984D02*
X1770265D01*
G01X1757265Y962984D02*
Y948984D01*
G01X1770265Y962984D02*
X1757265D01*
G01X1740518Y973046D02*
Y975546D01*
X1741559D01*
X1741893Y975421D01*
X1742101Y975254D01*
X1742184Y974921D01*
X1742101Y974588D01*
X1741851Y974379D01*
X1741559Y974254D01*
X1740518D01*
G01X1741559D02*
X1742184Y973046D01*
G01X1744451D02*
Y975546D01*
X1743951Y975046D01*
G01Y973046D02*
X1744951D01*
G01X1746759Y975129D02*
X1747009Y975379D01*
X1747301Y975504D01*
X1747634Y975546D01*
X1748051Y975463D01*
X1748343Y975254D01*
X1748426Y975004D01*
X1748384Y974754D01*
X1748218Y974546D01*
X1747384Y974129D01*
X1747009Y973838D01*
X1746759Y973421D01*
X1746676Y973046D01*
X1748426D01*
G01X1749734Y973421D02*
X1749984Y973213D01*
X1750276Y973088D01*
X1750651Y973046D01*
X1751026Y973129D01*
X1751318Y973296D01*
X1751526Y973588D01*
X1751568Y973921D01*
X1751484Y974254D01*
X1751276Y974463D01*
X1750984Y974629D01*
X1750693Y974671D01*
X1750401Y974629D01*
X1750026Y974463D01*
X1750151Y975546D01*
X1751276D01*
G01X1753751D02*
X1753418Y975463D01*
X1753168Y975254D01*
X1753001Y975004D01*
X1752876Y974671D01*
X1752834Y974296D01*
X1752876Y973921D01*
X1753001Y973588D01*
X1753168Y973338D01*
X1753418Y973129D01*
X1753751Y973046D01*
X1754084Y973129D01*
X1754334Y973338D01*
X1754501Y973588D01*
X1754626Y973921D01*
X1754668Y974296D01*
X1754626Y974671D01*
X1754501Y975004D01*
X1754334Y975254D01*
X1754084Y975463D01*
X1753751Y975546D01*
G01X1770294Y981575D02*
X1762494D01*
G01X1756894Y974575D02*
X1765594D01*
G01X1756894Y981575D02*
Y974575D01*
G01X1763294Y981575D02*
X1756894D01*
G01X1725380Y986606D02*
X1725130Y986731D01*
X1724838Y986814D01*
X1724505D01*
X1724130Y986689D01*
X1723838Y986481D01*
X1723630Y986231D01*
X1723463Y985814D01*
X1723421Y985439D01*
X1723505Y985064D01*
X1723630Y984814D01*
X1723880Y984564D01*
X1724171Y984397D01*
X1724463Y984314D01*
X1724755D01*
X1725046Y984397D01*
X1725296Y984522D01*
X1725505Y984689D01*
G01X1726771Y985356D02*
X1727063Y985647D01*
X1727313Y985814D01*
X1727646Y985897D01*
X1727938Y985814D01*
X1728146Y985647D01*
X1728313Y985397D01*
X1728355Y985106D01*
X1728313Y984856D01*
X1728146Y984606D01*
X1727896Y984397D01*
X1727605Y984314D01*
X1727271Y984397D01*
X1726980Y984647D01*
X1726813Y985022D01*
X1726771Y985439D01*
X1726855Y985981D01*
X1726980Y986272D01*
X1727188Y986564D01*
X1727480Y986772D01*
X1727771Y986814D01*
X1728063Y986731D01*
X1728271Y986522D01*
G01X1729746Y984814D02*
X1729996Y984522D01*
X1730330Y984356D01*
X1730705Y984314D01*
X1731038Y984356D01*
X1731371Y984564D01*
X1731580Y984814D01*
X1731621Y985064D01*
X1731538Y985356D01*
X1731246Y985564D01*
X1730955Y985647D01*
X1730580D01*
G01X1730955D02*
X1731205Y985772D01*
X1731413Y985981D01*
X1731496Y986231D01*
X1731413Y986481D01*
X1731205Y986689D01*
X1730830Y986814D01*
X1730455Y986772D01*
X1730080Y986606D01*
G01X1732971Y986397D02*
X1733221Y986647D01*
X1733513Y986772D01*
X1733846Y986814D01*
X1734263Y986731D01*
X1734555Y986522D01*
X1734638Y986272D01*
X1734596Y986022D01*
X1734430Y985814D01*
X1733596Y985397D01*
X1733221Y985106D01*
X1732971Y984689D01*
X1732888Y984314D01*
X1734638D01*
G01X1725380Y982606D02*
X1725130Y982731D01*
X1724838Y982814D01*
X1724505D01*
X1724130Y982689D01*
X1723838Y982481D01*
X1723630Y982231D01*
X1723463Y981814D01*
X1723421Y981439D01*
X1723505Y981064D01*
X1723630Y980814D01*
X1723880Y980564D01*
X1724171Y980397D01*
X1724463Y980314D01*
X1724755D01*
X1725046Y980397D01*
X1725296Y980522D01*
X1725505Y980689D01*
G01X1726771Y981356D02*
X1727063Y981647D01*
X1727313Y981814D01*
X1727646Y981897D01*
X1727938Y981814D01*
X1728146Y981647D01*
X1728313Y981397D01*
X1728355Y981106D01*
X1728313Y980856D01*
X1728146Y980606D01*
X1727896Y980397D01*
X1727605Y980314D01*
X1727271Y980397D01*
X1726980Y980647D01*
X1726813Y981022D01*
X1726771Y981439D01*
X1726855Y981981D01*
X1726980Y982272D01*
X1727188Y982564D01*
X1727480Y982772D01*
X1727771Y982814D01*
X1728063Y982731D01*
X1728271Y982522D01*
G01X1729746Y980814D02*
X1729996Y980522D01*
X1730330Y980356D01*
X1730705Y980314D01*
X1731038Y980356D01*
X1731371Y980564D01*
X1731580Y980814D01*
X1731621Y981064D01*
X1731538Y981356D01*
X1731246Y981564D01*
X1730955Y981647D01*
X1730580D01*
G01X1730955D02*
X1731205Y981772D01*
X1731413Y981981D01*
X1731496Y982231D01*
X1731413Y982481D01*
X1731205Y982689D01*
X1730830Y982814D01*
X1730455Y982772D01*
X1730080Y982606D01*
G01X1733763Y980314D02*
Y982814D01*
X1733263Y982314D01*
G01Y980314D02*
X1734263D01*
G01X1730207Y949997D02*
X1727707D01*
Y951038D01*
X1727832Y951372D01*
X1727999Y951580D01*
X1728332Y951663D01*
X1728665Y951580D01*
X1728874Y951330D01*
X1728999Y951038D01*
Y949997D01*
G01Y951038D02*
X1730207Y951663D01*
G01X1728124Y953138D02*
X1727874Y953388D01*
X1727749Y953680D01*
X1727707Y954013D01*
X1727790Y954430D01*
X1727999Y954722D01*
X1728249Y954805D01*
X1728499Y954763D01*
X1728707Y954597D01*
X1729124Y953763D01*
X1729415Y953388D01*
X1729832Y953138D01*
X1730207Y953055D01*
Y954805D01*
G01X1729165Y956238D02*
X1728874Y956530D01*
X1728707Y956780D01*
X1728624Y957113D01*
X1728707Y957405D01*
X1728874Y957613D01*
X1729124Y957780D01*
X1729415Y957822D01*
X1729665Y957780D01*
X1729915Y957613D01*
X1730124Y957363D01*
X1730207Y957072D01*
X1730124Y956738D01*
X1729874Y956447D01*
X1729499Y956280D01*
X1729082Y956238D01*
X1728540Y956322D01*
X1728249Y956447D01*
X1727957Y956655D01*
X1727749Y956947D01*
X1727707Y957238D01*
X1727790Y957530D01*
X1727999Y957738D01*
G01X1729165Y959338D02*
X1728874Y959630D01*
X1728707Y959880D01*
X1728624Y960213D01*
X1728707Y960505D01*
X1728874Y960713D01*
X1729124Y960880D01*
X1729415Y960922D01*
X1729665Y960880D01*
X1729915Y960713D01*
X1730124Y960463D01*
X1730207Y960172D01*
X1730124Y959838D01*
X1729874Y959547D01*
X1729499Y959380D01*
X1729082Y959338D01*
X1728540Y959422D01*
X1728249Y959547D01*
X1727957Y959755D01*
X1727749Y960047D01*
X1727707Y960338D01*
X1727790Y960630D01*
X1727999Y960838D01*
G01X1725707Y949997D02*
X1723207D01*
Y951038D01*
X1723332Y951372D01*
X1723499Y951580D01*
X1723832Y951663D01*
X1724165Y951580D01*
X1724374Y951330D01*
X1724499Y951038D01*
Y949997D01*
G01Y951038D02*
X1725707Y951663D01*
G01X1723624Y953138D02*
X1723374Y953388D01*
X1723249Y953680D01*
X1723207Y954013D01*
X1723290Y954430D01*
X1723499Y954722D01*
X1723749Y954805D01*
X1723999Y954763D01*
X1724207Y954597D01*
X1724624Y953763D01*
X1724915Y953388D01*
X1725332Y953138D01*
X1725707Y953055D01*
Y954805D01*
G01X1724665Y956238D02*
X1724374Y956530D01*
X1724207Y956780D01*
X1724124Y957113D01*
X1724207Y957405D01*
X1724374Y957613D01*
X1724624Y957780D01*
X1724915Y957822D01*
X1725165Y957780D01*
X1725415Y957613D01*
X1725624Y957363D01*
X1725707Y957072D01*
X1725624Y956738D01*
X1725374Y956447D01*
X1724999Y956280D01*
X1724582Y956238D01*
X1724040Y956322D01*
X1723749Y956447D01*
X1723457Y956655D01*
X1723249Y956947D01*
X1723207Y957238D01*
X1723290Y957530D01*
X1723499Y957738D01*
G01X1725332Y959213D02*
X1725540Y959463D01*
X1725665Y959755D01*
X1725707Y960130D01*
X1725624Y960505D01*
X1725457Y960797D01*
X1725165Y961005D01*
X1724832Y961047D01*
X1724499Y960963D01*
X1724290Y960755D01*
X1724124Y960463D01*
X1724082Y960172D01*
X1724124Y959880D01*
X1724290Y959505D01*
X1723207Y959630D01*
Y960755D01*
G01X1741464Y1021501D02*
Y1024001D01*
X1742505D01*
X1742839Y1023876D01*
X1743047Y1023709D01*
X1743130Y1023376D01*
X1743047Y1023043D01*
X1742797Y1022834D01*
X1742505Y1022709D01*
X1741464D01*
G01X1742505D02*
X1743130Y1021501D01*
G01X1745397D02*
Y1024001D01*
X1744897Y1023501D01*
G01Y1021501D02*
X1745897D01*
G01X1747705Y1023584D02*
X1747955Y1023834D01*
X1748247Y1023959D01*
X1748580Y1024001D01*
X1748997Y1023918D01*
X1749289Y1023709D01*
X1749372Y1023459D01*
X1749330Y1023209D01*
X1749164Y1023001D01*
X1748330Y1022584D01*
X1747955Y1022293D01*
X1747705Y1021876D01*
X1747622Y1021501D01*
X1749372D01*
G01X1750680Y1021876D02*
X1750930Y1021668D01*
X1751222Y1021543D01*
X1751597Y1021501D01*
X1751972Y1021584D01*
X1752264Y1021751D01*
X1752472Y1022043D01*
X1752514Y1022376D01*
X1752430Y1022709D01*
X1752222Y1022918D01*
X1751930Y1023084D01*
X1751639Y1023126D01*
X1751347Y1023084D01*
X1750972Y1022918D01*
X1751097Y1024001D01*
X1752222D01*
G01X1754697Y1021501D02*
Y1024001D01*
X1754197Y1023501D01*
G01Y1021501D02*
X1755197D01*
G01X1764197Y1005001D02*
Y1009001D01*
X1756797D01*
G01X1741462Y1025567D02*
Y1028067D01*
X1742503D01*
X1742837Y1027942D01*
X1743045Y1027775D01*
X1743128Y1027442D01*
X1743045Y1027109D01*
X1742795Y1026900D01*
X1742503Y1026775D01*
X1741462D01*
G01X1742503D02*
X1743128Y1025567D01*
G01X1745395D02*
Y1028067D01*
X1744895Y1027567D01*
G01Y1025567D02*
X1745895D01*
G01X1747703Y1027650D02*
X1747953Y1027900D01*
X1748245Y1028025D01*
X1748578Y1028067D01*
X1748995Y1027984D01*
X1749287Y1027775D01*
X1749370Y1027525D01*
X1749328Y1027275D01*
X1749162Y1027067D01*
X1748328Y1026650D01*
X1747953Y1026359D01*
X1747703Y1025942D01*
X1747620Y1025567D01*
X1749370D01*
G01X1750678Y1025942D02*
X1750928Y1025734D01*
X1751220Y1025609D01*
X1751595Y1025567D01*
X1751970Y1025650D01*
X1752262Y1025817D01*
X1752470Y1026109D01*
X1752512Y1026442D01*
X1752428Y1026775D01*
X1752220Y1026984D01*
X1751928Y1027150D01*
X1751637Y1027192D01*
X1751345Y1027150D01*
X1750970Y1026984D01*
X1751095Y1028067D01*
X1752220D01*
G01X1753778Y1026067D02*
X1754028Y1025775D01*
X1754362Y1025609D01*
X1754737Y1025567D01*
X1755070Y1025609D01*
X1755403Y1025817D01*
X1755612Y1026067D01*
X1755653Y1026317D01*
X1755570Y1026609D01*
X1755278Y1026817D01*
X1754987Y1026900D01*
X1754612D01*
G01X1754987D02*
X1755237Y1027025D01*
X1755445Y1027234D01*
X1755528Y1027484D01*
X1755445Y1027734D01*
X1755237Y1027942D01*
X1754862Y1028067D01*
X1754487Y1028025D01*
X1754112Y1027859D01*
G01X1756795Y1013067D02*
Y1009067D01*
X1764195D01*
G01X1725967Y1030300D02*
Y1032800D01*
X1727008D01*
X1727342Y1032675D01*
X1727550Y1032508D01*
X1727633Y1032175D01*
X1727550Y1031842D01*
X1727300Y1031633D01*
X1727008Y1031508D01*
X1725967D01*
G01X1727008D02*
X1727633Y1030300D01*
G01X1729900D02*
Y1032800D01*
X1729400Y1032300D01*
G01Y1030300D02*
X1730400D01*
G01X1732208Y1032383D02*
X1732458Y1032633D01*
X1732750Y1032758D01*
X1733083Y1032800D01*
X1733500Y1032717D01*
X1733792Y1032508D01*
X1733875Y1032258D01*
X1733833Y1032008D01*
X1733667Y1031800D01*
X1732833Y1031383D01*
X1732458Y1031092D01*
X1732208Y1030675D01*
X1732125Y1030300D01*
X1733875D01*
G01X1735183Y1030675D02*
X1735433Y1030467D01*
X1735725Y1030342D01*
X1736100Y1030300D01*
X1736475Y1030383D01*
X1736767Y1030550D01*
X1736975Y1030842D01*
X1737017Y1031175D01*
X1736933Y1031508D01*
X1736725Y1031717D01*
X1736433Y1031883D01*
X1736142Y1031925D01*
X1735850Y1031883D01*
X1735475Y1031717D01*
X1735600Y1032800D01*
X1736725D01*
G01X1738283Y1030675D02*
X1738533Y1030467D01*
X1738825Y1030342D01*
X1739200Y1030300D01*
X1739575Y1030383D01*
X1739867Y1030550D01*
X1740075Y1030842D01*
X1740117Y1031175D01*
X1740033Y1031508D01*
X1739825Y1031717D01*
X1739533Y1031883D01*
X1739242Y1031925D01*
X1738950Y1031883D01*
X1738575Y1031717D01*
X1738700Y1032800D01*
X1739825D01*
G01X1749363Y1013325D02*
Y1017325D01*
X1741963D01*
G01X1732582Y992845D02*
Y995345D01*
X1733623D01*
X1733957Y995220D01*
X1734165Y995053D01*
X1734248Y994720D01*
X1734165Y994387D01*
X1733915Y994178D01*
X1733623Y994053D01*
X1732582D01*
G01X1733623D02*
X1734248Y992845D01*
G01X1736515D02*
Y995345D01*
X1736015Y994845D01*
G01Y992845D02*
X1737015D01*
G01X1738823Y994928D02*
X1739073Y995178D01*
X1739365Y995303D01*
X1739698Y995345D01*
X1740115Y995262D01*
X1740407Y995053D01*
X1740490Y994803D01*
X1740448Y994553D01*
X1740282Y994345D01*
X1739448Y993928D01*
X1739073Y993637D01*
X1738823Y993220D01*
X1738740Y992845D01*
X1740490D01*
G01X1741798Y993220D02*
X1742048Y993012D01*
X1742340Y992887D01*
X1742715Y992845D01*
X1743090Y992928D01*
X1743382Y993095D01*
X1743590Y993387D01*
X1743632Y993720D01*
X1743548Y994053D01*
X1743340Y994262D01*
X1743048Y994428D01*
X1742757Y994470D01*
X1742465Y994428D01*
X1742090Y994262D01*
X1742215Y995345D01*
X1743340D01*
G01X1745732Y992845D02*
X1745815Y993387D01*
X1745940Y993845D01*
X1746107Y994262D01*
X1746315Y994720D01*
X1746648Y995345D01*
X1744982D01*
G01X1748063Y995725D02*
Y999725D01*
X1740663D01*
G01X1736000Y1014467D02*
X1733500D01*
Y1015508D01*
X1733625Y1015842D01*
X1733792Y1016050D01*
X1734125Y1016133D01*
X1734458Y1016050D01*
X1734667Y1015800D01*
X1734792Y1015508D01*
Y1014467D01*
G01Y1015508D02*
X1736000Y1016133D01*
G01Y1018400D02*
X1733500D01*
X1734000Y1017900D01*
G01X1736000D02*
Y1018900D01*
G01X1733917Y1020708D02*
X1733667Y1020958D01*
X1733542Y1021250D01*
X1733500Y1021583D01*
X1733583Y1022000D01*
X1733792Y1022292D01*
X1734042Y1022375D01*
X1734292Y1022333D01*
X1734500Y1022167D01*
X1734917Y1021333D01*
X1735208Y1020958D01*
X1735625Y1020708D01*
X1736000Y1020625D01*
Y1022375D01*
G01X1734958Y1023808D02*
X1734667Y1024100D01*
X1734500Y1024350D01*
X1734417Y1024683D01*
X1734500Y1024975D01*
X1734667Y1025183D01*
X1734917Y1025350D01*
X1735208Y1025392D01*
X1735458Y1025350D01*
X1735708Y1025183D01*
X1735917Y1024933D01*
X1736000Y1024642D01*
X1735917Y1024308D01*
X1735667Y1024017D01*
X1735292Y1023850D01*
X1734875Y1023808D01*
X1734333Y1023892D01*
X1734042Y1024017D01*
X1733750Y1024225D01*
X1733542Y1024517D01*
X1733500Y1024808D01*
X1733583Y1025100D01*
X1733792Y1025308D01*
G01X1733500Y1027700D02*
X1733583Y1027367D01*
X1733792Y1027117D01*
X1734042Y1026950D01*
X1734375Y1026825D01*
X1734750Y1026783D01*
X1735125Y1026825D01*
X1735458Y1026950D01*
X1735708Y1027117D01*
X1735917Y1027367D01*
X1736000Y1027700D01*
X1735917Y1028033D01*
X1735708Y1028283D01*
X1735458Y1028450D01*
X1735125Y1028575D01*
X1734750Y1028617D01*
X1734375Y1028575D01*
X1734042Y1028450D01*
X1733792Y1028283D01*
X1733583Y1028033D01*
X1733500Y1027700D01*
G01X1748163Y1005525D02*
X1752163D01*
Y1012925D01*
G01X1740000Y1014467D02*
X1737500D01*
Y1015508D01*
X1737625Y1015842D01*
X1737792Y1016050D01*
X1738125Y1016133D01*
X1738458Y1016050D01*
X1738667Y1015800D01*
X1738792Y1015508D01*
Y1014467D01*
G01Y1015508D02*
X1740000Y1016133D01*
G01Y1018400D02*
X1737500D01*
X1738000Y1017900D01*
G01X1740000D02*
Y1018900D01*
G01X1737917Y1020708D02*
X1737667Y1020958D01*
X1737542Y1021250D01*
X1737500Y1021583D01*
X1737583Y1022000D01*
X1737792Y1022292D01*
X1738042Y1022375D01*
X1738292Y1022333D01*
X1738500Y1022167D01*
X1738917Y1021333D01*
X1739208Y1020958D01*
X1739625Y1020708D01*
X1740000Y1020625D01*
Y1022375D01*
G01X1738958Y1023808D02*
X1738667Y1024100D01*
X1738500Y1024350D01*
X1738417Y1024683D01*
X1738500Y1024975D01*
X1738667Y1025183D01*
X1738917Y1025350D01*
X1739208Y1025392D01*
X1739458Y1025350D01*
X1739708Y1025183D01*
X1739917Y1024933D01*
X1740000Y1024642D01*
X1739917Y1024308D01*
X1739667Y1024017D01*
X1739292Y1023850D01*
X1738875Y1023808D01*
X1738333Y1023892D01*
X1738042Y1024017D01*
X1737750Y1024225D01*
X1737542Y1024517D01*
X1737500Y1024808D01*
X1737583Y1025100D01*
X1737792Y1025308D01*
G01X1740000Y1027700D02*
X1737500D01*
X1738000Y1027200D01*
G01X1740000D02*
Y1028200D01*
G01X1752300Y1005580D02*
X1756300D01*
Y1012980D01*
G01X1757967Y1029500D02*
Y1032000D01*
X1759008D01*
X1759342Y1031875D01*
X1759550Y1031708D01*
X1759633Y1031375D01*
X1759550Y1031042D01*
X1759300Y1030833D01*
X1759008Y1030708D01*
X1757967D01*
G01X1759008D02*
X1759633Y1029500D01*
G01X1761900D02*
Y1032000D01*
X1761400Y1031500D01*
G01Y1029500D02*
X1762400D01*
G01X1764208Y1031583D02*
X1764458Y1031833D01*
X1764750Y1031958D01*
X1765083Y1032000D01*
X1765500Y1031917D01*
X1765792Y1031708D01*
X1765875Y1031458D01*
X1765833Y1031208D01*
X1765667Y1031000D01*
X1764833Y1030583D01*
X1764458Y1030292D01*
X1764208Y1029875D01*
X1764125Y1029500D01*
X1765875D01*
G01X1768600D02*
Y1032000D01*
X1767058Y1030208D01*
X1769142D01*
G01X1770408Y1030542D02*
X1770700Y1030833D01*
X1770950Y1031000D01*
X1771283Y1031083D01*
X1771575Y1031000D01*
X1771783Y1030833D01*
X1771950Y1030583D01*
X1771992Y1030292D01*
X1771950Y1030042D01*
X1771783Y1029792D01*
X1771533Y1029583D01*
X1771242Y1029500D01*
X1770908Y1029583D01*
X1770617Y1029833D01*
X1770450Y1030208D01*
X1770408Y1030625D01*
X1770492Y1031167D01*
X1770617Y1031458D01*
X1770825Y1031750D01*
X1771117Y1031958D01*
X1771408Y1032000D01*
X1771700Y1031917D01*
X1771908Y1031708D01*
G01X1757967Y1021500D02*
Y1024000D01*
X1759008D01*
X1759342Y1023875D01*
X1759550Y1023708D01*
X1759633Y1023375D01*
X1759550Y1023042D01*
X1759300Y1022833D01*
X1759008Y1022708D01*
X1757967D01*
G01X1759008D02*
X1759633Y1021500D01*
G01X1761900D02*
Y1024000D01*
X1761400Y1023500D01*
G01Y1021500D02*
X1762400D01*
G01X1764208Y1023583D02*
X1764458Y1023833D01*
X1764750Y1023958D01*
X1765083Y1024000D01*
X1765500Y1023917D01*
X1765792Y1023708D01*
X1765875Y1023458D01*
X1765833Y1023208D01*
X1765667Y1023000D01*
X1764833Y1022583D01*
X1764458Y1022292D01*
X1764208Y1021875D01*
X1764125Y1021500D01*
X1765875D01*
G01X1767183Y1021875D02*
X1767433Y1021667D01*
X1767725Y1021542D01*
X1768100Y1021500D01*
X1768475Y1021583D01*
X1768767Y1021750D01*
X1768975Y1022042D01*
X1769017Y1022375D01*
X1768933Y1022708D01*
X1768725Y1022917D01*
X1768433Y1023083D01*
X1768142Y1023125D01*
X1767850Y1023083D01*
X1767475Y1022917D01*
X1767600Y1024000D01*
X1768725D01*
G01X1770408Y1023583D02*
X1770658Y1023833D01*
X1770950Y1023958D01*
X1771283Y1024000D01*
X1771700Y1023917D01*
X1771992Y1023708D01*
X1772075Y1023458D01*
X1772033Y1023208D01*
X1771867Y1023000D01*
X1771033Y1022583D01*
X1770658Y1022292D01*
X1770408Y1021875D01*
X1770325Y1021500D01*
X1772075D01*
G01X1771655Y1002723D02*
Y1006723D01*
X1764255D01*
G01X1759767Y1027792D02*
X1759517Y1027917D01*
X1759225Y1028000D01*
X1758892D01*
X1758517Y1027875D01*
X1758225Y1027667D01*
X1758017Y1027417D01*
X1757850Y1027000D01*
X1757808Y1026625D01*
X1757892Y1026250D01*
X1758017Y1026000D01*
X1758267Y1025750D01*
X1758558Y1025583D01*
X1758850Y1025500D01*
X1759142D01*
X1759433Y1025583D01*
X1759683Y1025708D01*
X1759892Y1025875D01*
G01X1761158Y1026542D02*
X1761450Y1026833D01*
X1761700Y1027000D01*
X1762033Y1027083D01*
X1762325Y1027000D01*
X1762533Y1026833D01*
X1762700Y1026583D01*
X1762742Y1026292D01*
X1762700Y1026042D01*
X1762533Y1025792D01*
X1762283Y1025583D01*
X1761992Y1025500D01*
X1761658Y1025583D01*
X1761367Y1025833D01*
X1761200Y1026208D01*
X1761158Y1026625D01*
X1761242Y1027167D01*
X1761367Y1027458D01*
X1761575Y1027750D01*
X1761867Y1027958D01*
X1762158Y1028000D01*
X1762450Y1027917D01*
X1762658Y1027708D01*
G01X1764133Y1026000D02*
X1764383Y1025708D01*
X1764717Y1025542D01*
X1765092Y1025500D01*
X1765425Y1025542D01*
X1765758Y1025750D01*
X1765967Y1026000D01*
X1766008Y1026250D01*
X1765925Y1026542D01*
X1765633Y1026750D01*
X1765342Y1026833D01*
X1764967D01*
G01X1765342D02*
X1765592Y1026958D01*
X1765800Y1027167D01*
X1765883Y1027417D01*
X1765800Y1027667D01*
X1765592Y1027875D01*
X1765217Y1028000D01*
X1764842Y1027958D01*
X1764467Y1027792D01*
G01X1768067Y1025500D02*
X1768150Y1026042D01*
X1768275Y1026500D01*
X1768442Y1026917D01*
X1768650Y1027375D01*
X1768983Y1028000D01*
X1767317D01*
G01X1743767Y1076959D02*
X1743517Y1077084D01*
X1743225Y1077167D01*
X1742892D01*
X1742517Y1077042D01*
X1742225Y1076834D01*
X1742017Y1076584D01*
X1741850Y1076167D01*
X1741808Y1075792D01*
X1741892Y1075417D01*
X1742017Y1075167D01*
X1742267Y1074917D01*
X1742558Y1074750D01*
X1742850Y1074667D01*
X1743142D01*
X1743433Y1074750D01*
X1743683Y1074875D01*
X1743892Y1075042D01*
G01X1745950Y1074667D02*
Y1077167D01*
X1745450Y1076667D01*
G01Y1074667D02*
X1746450D01*
G01X1748258Y1075709D02*
X1748550Y1076000D01*
X1748800Y1076167D01*
X1749133Y1076250D01*
X1749425Y1076167D01*
X1749633Y1076000D01*
X1749800Y1075750D01*
X1749842Y1075459D01*
X1749800Y1075209D01*
X1749633Y1074959D01*
X1749383Y1074750D01*
X1749092Y1074667D01*
X1748758Y1074750D01*
X1748467Y1075000D01*
X1748300Y1075375D01*
X1748258Y1075792D01*
X1748342Y1076334D01*
X1748467Y1076625D01*
X1748675Y1076917D01*
X1748967Y1077125D01*
X1749258Y1077167D01*
X1749550Y1077084D01*
X1749758Y1076875D01*
G01X1751442Y1074959D02*
X1751733Y1074750D01*
X1752067Y1074667D01*
X1752400Y1074750D01*
X1752692Y1075000D01*
X1752900Y1075375D01*
X1752983Y1075750D01*
Y1076209D01*
X1752900Y1076584D01*
X1752692Y1076917D01*
X1752442Y1077084D01*
X1752150Y1077167D01*
X1751817Y1077084D01*
X1751567Y1076917D01*
X1751400Y1076667D01*
X1751317Y1076334D01*
X1751400Y1076042D01*
X1751608Y1075750D01*
X1751858Y1075584D01*
X1752150Y1075542D01*
X1752483Y1075625D01*
X1752733Y1075834D01*
X1752983Y1076209D01*
G01X1743767Y1081292D02*
X1743517Y1081417D01*
X1743225Y1081500D01*
X1742892D01*
X1742517Y1081375D01*
X1742225Y1081167D01*
X1742017Y1080917D01*
X1741850Y1080500D01*
X1741808Y1080125D01*
X1741892Y1079750D01*
X1742017Y1079500D01*
X1742267Y1079250D01*
X1742558Y1079083D01*
X1742850Y1079000D01*
X1743142D01*
X1743433Y1079083D01*
X1743683Y1079208D01*
X1743892Y1079375D01*
G01X1745950Y1079000D02*
Y1081500D01*
X1745450Y1081000D01*
G01Y1079000D02*
X1746450D01*
G01X1748258Y1080042D02*
X1748550Y1080333D01*
X1748800Y1080500D01*
X1749133Y1080583D01*
X1749425Y1080500D01*
X1749633Y1080333D01*
X1749800Y1080083D01*
X1749842Y1079792D01*
X1749800Y1079542D01*
X1749633Y1079292D01*
X1749383Y1079083D01*
X1749092Y1079000D01*
X1748758Y1079083D01*
X1748467Y1079333D01*
X1748300Y1079708D01*
X1748258Y1080125D01*
X1748342Y1080667D01*
X1748467Y1080958D01*
X1748675Y1081250D01*
X1748967Y1081458D01*
X1749258Y1081500D01*
X1749550Y1081417D01*
X1749758Y1081208D01*
G01X1752150Y1079000D02*
X1752442Y1079042D01*
X1752775Y1079167D01*
X1752983Y1079375D01*
X1753067Y1079667D01*
X1752983Y1079958D01*
X1752733Y1080208D01*
X1752358Y1080333D01*
X1751942D01*
X1751692Y1080417D01*
X1751483Y1080625D01*
X1751400Y1080917D01*
X1751525Y1081208D01*
X1751817Y1081417D01*
X1752150Y1081500D01*
X1752483Y1081417D01*
X1752775Y1081208D01*
X1752900Y1080917D01*
X1752817Y1080625D01*
X1752608Y1080417D01*
X1752358Y1080333D01*
X1751942D01*
X1751567Y1080208D01*
X1751317Y1079958D01*
X1751233Y1079667D01*
X1751317Y1079375D01*
X1751525Y1079167D01*
X1751858Y1079042D01*
X1752150Y1079000D01*
G01X1761643Y1127004D02*
X1766693D01*
Y1225704D01*
X1791343D01*
Y1041304D01*
X1766693D01*
Y1100004D01*
X1761643D01*
Y1127004D01*
G01X1725155Y1100173D02*
Y1102673D01*
X1726196D01*
X1726530Y1102548D01*
X1726738Y1102381D01*
X1726821Y1102048D01*
X1726738Y1101715D01*
X1726488Y1101506D01*
X1726196Y1101381D01*
X1725155D01*
G01X1726196D02*
X1726821Y1100173D01*
G01X1728171Y1100673D02*
X1728421Y1100381D01*
X1728755Y1100215D01*
X1729130Y1100173D01*
X1729463Y1100215D01*
X1729796Y1100423D01*
X1730005Y1100673D01*
X1730046Y1100923D01*
X1729963Y1101215D01*
X1729671Y1101423D01*
X1729380Y1101506D01*
X1729005D01*
G01X1729380D02*
X1729630Y1101631D01*
X1729838Y1101840D01*
X1729921Y1102090D01*
X1729838Y1102340D01*
X1729630Y1102548D01*
X1729255Y1102673D01*
X1728880Y1102631D01*
X1728505Y1102465D01*
G01X1731271Y1100548D02*
X1731521Y1100340D01*
X1731813Y1100215D01*
X1732188Y1100173D01*
X1732563Y1100256D01*
X1732855Y1100423D01*
X1733063Y1100715D01*
X1733105Y1101048D01*
X1733021Y1101381D01*
X1732813Y1101590D01*
X1732521Y1101756D01*
X1732230Y1101798D01*
X1731938Y1101756D01*
X1731563Y1101590D01*
X1731688Y1102673D01*
X1732813D01*
G01X1734371Y1100673D02*
X1734621Y1100381D01*
X1734955Y1100215D01*
X1735330Y1100173D01*
X1735663Y1100215D01*
X1735996Y1100423D01*
X1736205Y1100673D01*
X1736246Y1100923D01*
X1736163Y1101215D01*
X1735871Y1101423D01*
X1735580Y1101506D01*
X1735205D01*
G01X1735580D02*
X1735830Y1101631D01*
X1736038Y1101840D01*
X1736121Y1102090D01*
X1736038Y1102340D01*
X1735830Y1102548D01*
X1735455Y1102673D01*
X1735080Y1102631D01*
X1734705Y1102465D01*
G01X1735517Y1114500D02*
Y1117000D01*
X1736558D01*
X1736892Y1116875D01*
X1737100Y1116708D01*
X1737183Y1116375D01*
X1737100Y1116042D01*
X1736850Y1115833D01*
X1736558Y1115708D01*
X1735517D01*
G01X1736558D02*
X1737183Y1114500D01*
G01X1738533Y1114875D02*
X1738783Y1114667D01*
X1739075Y1114542D01*
X1739450Y1114500D01*
X1739825Y1114583D01*
X1740117Y1114750D01*
X1740325Y1115042D01*
X1740367Y1115375D01*
X1740283Y1115708D01*
X1740075Y1115917D01*
X1739783Y1116083D01*
X1739492Y1116125D01*
X1739200Y1116083D01*
X1738825Y1115917D01*
X1738950Y1117000D01*
X1740075D01*
G01X1742550Y1114500D02*
X1742842Y1114542D01*
X1743175Y1114667D01*
X1743383Y1114875D01*
X1743467Y1115167D01*
X1743383Y1115458D01*
X1743133Y1115708D01*
X1742758Y1115833D01*
X1742342D01*
X1742092Y1115917D01*
X1741883Y1116125D01*
X1741800Y1116417D01*
X1741925Y1116708D01*
X1742217Y1116917D01*
X1742550Y1117000D01*
X1742883Y1116917D01*
X1743175Y1116708D01*
X1743300Y1116417D01*
X1743217Y1116125D01*
X1743008Y1115917D01*
X1742758Y1115833D01*
X1742342D01*
X1741967Y1115708D01*
X1741717Y1115458D01*
X1741633Y1115167D01*
X1741717Y1114875D01*
X1741925Y1114667D01*
X1742258Y1114542D01*
X1742550Y1114500D01*
G01X1744858Y1115542D02*
X1745150Y1115833D01*
X1745400Y1116000D01*
X1745733Y1116083D01*
X1746025Y1116000D01*
X1746233Y1115833D01*
X1746400Y1115583D01*
X1746442Y1115292D01*
X1746400Y1115042D01*
X1746233Y1114792D01*
X1745983Y1114583D01*
X1745692Y1114500D01*
X1745358Y1114583D01*
X1745067Y1114833D01*
X1744900Y1115208D01*
X1744858Y1115625D01*
X1744942Y1116167D01*
X1745067Y1116458D01*
X1745275Y1116750D01*
X1745567Y1116958D01*
X1745858Y1117000D01*
X1746150Y1116917D01*
X1746358Y1116708D01*
G01X1731295Y1122127D02*
Y1118127D01*
X1738695D01*
G01X1744000Y1126850D02*
X1743958Y1126517D01*
X1743792Y1126225D01*
X1743542Y1125975D01*
X1743250Y1125808D01*
X1742917Y1125725D01*
X1742583D01*
X1742250Y1125808D01*
X1741958Y1125975D01*
X1741708Y1126225D01*
X1741542Y1126517D01*
X1741500Y1126850D01*
X1741542Y1127183D01*
X1741708Y1127475D01*
X1741958Y1127725D01*
X1742250Y1127892D01*
X1742583Y1127975D01*
X1742917D01*
X1743250Y1127892D01*
X1743542Y1127725D01*
X1743792Y1127475D01*
X1743958Y1127183D01*
X1744000Y1126850D01*
G01X1743333Y1127183D02*
X1744000Y1127683D01*
G01X1741917Y1129158D02*
X1741667Y1129408D01*
X1741542Y1129700D01*
X1741500Y1130033D01*
X1741583Y1130450D01*
X1741792Y1130742D01*
X1742042Y1130825D01*
X1742292Y1130783D01*
X1742500Y1130617D01*
X1742917Y1129783D01*
X1743208Y1129408D01*
X1743625Y1129158D01*
X1744000Y1129075D01*
Y1130825D01*
G01X1743708Y1132342D02*
X1743917Y1132633D01*
X1744000Y1132967D01*
X1743917Y1133300D01*
X1743667Y1133592D01*
X1743292Y1133800D01*
X1742917Y1133883D01*
X1742458D01*
X1742083Y1133800D01*
X1741750Y1133592D01*
X1741583Y1133342D01*
X1741500Y1133050D01*
X1741583Y1132717D01*
X1741750Y1132467D01*
X1742000Y1132300D01*
X1742333Y1132217D01*
X1742625Y1132300D01*
X1742917Y1132508D01*
X1743083Y1132758D01*
X1743125Y1133050D01*
X1743042Y1133383D01*
X1742833Y1133633D01*
X1742458Y1133883D01*
G01X1744000Y1136067D02*
X1743458Y1136150D01*
X1743000Y1136275D01*
X1742583Y1136442D01*
X1742125Y1136650D01*
X1741500Y1136983D01*
Y1135317D01*
G01X1726353Y1138685D02*
Y1124685D01*
G01X1739353D02*
Y1138685D01*
G01X1726353Y1124685D02*
X1739353D01*
G01X1725033Y1096000D02*
Y1098500D01*
X1725867D01*
X1726200Y1098375D01*
X1726450Y1098208D01*
X1726658Y1097958D01*
X1726825Y1097667D01*
X1726867Y1097250D01*
X1726825Y1096833D01*
X1726658Y1096542D01*
X1726450Y1096292D01*
X1726200Y1096125D01*
X1725867Y1096000D01*
X1725033D01*
G01X1728342Y1096292D02*
X1728633Y1096083D01*
X1728967Y1096000D01*
X1729300Y1096083D01*
X1729592Y1096333D01*
X1729800Y1096708D01*
X1729883Y1097083D01*
Y1097542D01*
X1729800Y1097917D01*
X1729592Y1098250D01*
X1729342Y1098417D01*
X1729050Y1098500D01*
X1728717Y1098417D01*
X1728467Y1098250D01*
X1728300Y1098000D01*
X1728217Y1097667D01*
X1728300Y1097375D01*
X1728508Y1097083D01*
X1728758Y1096917D01*
X1729050Y1096875D01*
X1729383Y1096958D01*
X1729633Y1097167D01*
X1729883Y1097542D01*
G01X1750367Y1141273D02*
Y1143773D01*
X1751408D01*
X1751742Y1143648D01*
X1751950Y1143481D01*
X1752033Y1143148D01*
X1751950Y1142815D01*
X1751700Y1142606D01*
X1751408Y1142481D01*
X1750367D01*
G01X1751408D02*
X1752033Y1141273D01*
G01X1753383Y1141773D02*
X1753633Y1141481D01*
X1753967Y1141315D01*
X1754342Y1141273D01*
X1754675Y1141315D01*
X1755008Y1141523D01*
X1755217Y1141773D01*
X1755258Y1142023D01*
X1755175Y1142315D01*
X1754883Y1142523D01*
X1754592Y1142606D01*
X1754217D01*
G01X1754592D02*
X1754842Y1142731D01*
X1755050Y1142940D01*
X1755133Y1143190D01*
X1755050Y1143440D01*
X1754842Y1143648D01*
X1754467Y1143773D01*
X1754092Y1143731D01*
X1753717Y1143565D01*
G01X1756608Y1142315D02*
X1756900Y1142606D01*
X1757150Y1142773D01*
X1757483Y1142856D01*
X1757775Y1142773D01*
X1757983Y1142606D01*
X1758150Y1142356D01*
X1758192Y1142065D01*
X1758150Y1141815D01*
X1757983Y1141565D01*
X1757733Y1141356D01*
X1757442Y1141273D01*
X1757108Y1141356D01*
X1756817Y1141606D01*
X1756650Y1141981D01*
X1756608Y1142398D01*
X1756692Y1142940D01*
X1756817Y1143231D01*
X1757025Y1143523D01*
X1757317Y1143731D01*
X1757608Y1143773D01*
X1757900Y1143690D01*
X1758108Y1143481D01*
G01X1760500Y1143773D02*
X1760167Y1143690D01*
X1759917Y1143481D01*
X1759750Y1143231D01*
X1759625Y1142898D01*
X1759583Y1142523D01*
X1759625Y1142148D01*
X1759750Y1141815D01*
X1759917Y1141565D01*
X1760167Y1141356D01*
X1760500Y1141273D01*
X1760833Y1141356D01*
X1761083Y1141565D01*
X1761250Y1141815D01*
X1761375Y1142148D01*
X1761417Y1142523D01*
X1761375Y1142898D01*
X1761250Y1143231D01*
X1761083Y1143481D01*
X1760833Y1143690D01*
X1760500Y1143773D01*
G01X1746150Y1152273D02*
Y1148273D01*
X1753550D01*
G01X1731491Y1147478D02*
Y1143478D01*
X1738891D01*
G01X1739353Y1138685D02*
X1726353D01*
G01X1728350Y1165500D02*
X1728017Y1165542D01*
X1727725Y1165708D01*
X1727475Y1165958D01*
X1727308Y1166250D01*
X1727225Y1166583D01*
Y1166917D01*
X1727308Y1167250D01*
X1727475Y1167542D01*
X1727725Y1167792D01*
X1728017Y1167958D01*
X1728350Y1168000D01*
X1728683Y1167958D01*
X1728975Y1167792D01*
X1729225Y1167542D01*
X1729392Y1167250D01*
X1729475Y1166917D01*
Y1166583D01*
X1729392Y1166250D01*
X1729225Y1165958D01*
X1728975Y1165708D01*
X1728683Y1165542D01*
X1728350Y1165500D01*
G01X1728683Y1166167D02*
X1729183Y1165500D01*
G01X1730658Y1167583D02*
X1730908Y1167833D01*
X1731200Y1167958D01*
X1731533Y1168000D01*
X1731950Y1167917D01*
X1732242Y1167708D01*
X1732325Y1167458D01*
X1732283Y1167208D01*
X1732117Y1167000D01*
X1731283Y1166583D01*
X1730908Y1166292D01*
X1730658Y1165875D01*
X1730575Y1165500D01*
X1732325D01*
G01X1733842Y1165792D02*
X1734133Y1165583D01*
X1734467Y1165500D01*
X1734800Y1165583D01*
X1735092Y1165833D01*
X1735300Y1166208D01*
X1735383Y1166583D01*
Y1167042D01*
X1735300Y1167417D01*
X1735092Y1167750D01*
X1734842Y1167917D01*
X1734550Y1168000D01*
X1734217Y1167917D01*
X1733967Y1167750D01*
X1733800Y1167500D01*
X1733717Y1167167D01*
X1733800Y1166875D01*
X1734008Y1166583D01*
X1734258Y1166417D01*
X1734550Y1166375D01*
X1734883Y1166458D01*
X1735133Y1166667D01*
X1735383Y1167042D01*
G01X1737650Y1165500D02*
X1737942Y1165542D01*
X1738275Y1165667D01*
X1738483Y1165875D01*
X1738567Y1166167D01*
X1738483Y1166458D01*
X1738233Y1166708D01*
X1737858Y1166833D01*
X1737442D01*
X1737192Y1166917D01*
X1736983Y1167125D01*
X1736900Y1167417D01*
X1737025Y1167708D01*
X1737317Y1167917D01*
X1737650Y1168000D01*
X1737983Y1167917D01*
X1738275Y1167708D01*
X1738400Y1167417D01*
X1738317Y1167125D01*
X1738108Y1166917D01*
X1737858Y1166833D01*
X1737442D01*
X1737067Y1166708D01*
X1736817Y1166458D01*
X1736733Y1166167D01*
X1736817Y1165875D01*
X1737025Y1165667D01*
X1737358Y1165542D01*
X1737650Y1165500D01*
G01X1726496Y1163858D02*
Y1149858D01*
G01X1739496Y1163858D02*
X1726496D01*
G01X1739496Y1149858D02*
Y1163858D01*
G01X1726496Y1149858D02*
X1739496D01*
G01X1733350Y1177666D02*
Y1175166D01*
G01X1732392Y1177666D02*
X1734308D01*
G01X1735617Y1175166D02*
Y1177666D01*
X1736617D01*
X1736950Y1177541D01*
X1737200Y1177249D01*
X1737283Y1176916D01*
X1737200Y1176583D01*
X1736992Y1176333D01*
X1736617Y1176208D01*
X1735617D01*
G01X1738633Y1175541D02*
X1738883Y1175333D01*
X1739175Y1175208D01*
X1739550Y1175166D01*
X1739925Y1175249D01*
X1740217Y1175416D01*
X1740425Y1175708D01*
X1740467Y1176041D01*
X1740383Y1176374D01*
X1740175Y1176583D01*
X1739883Y1176749D01*
X1739592Y1176791D01*
X1739300Y1176749D01*
X1738925Y1176583D01*
X1739050Y1177666D01*
X1740175D01*
G01X1741858Y1177249D02*
X1742108Y1177499D01*
X1742400Y1177624D01*
X1742733Y1177666D01*
X1743150Y1177583D01*
X1743442Y1177374D01*
X1743525Y1177124D01*
X1743483Y1176874D01*
X1743317Y1176666D01*
X1742483Y1176249D01*
X1742108Y1175958D01*
X1741858Y1175541D01*
X1741775Y1175166D01*
X1743525D01*
G01X1724117Y1165170D02*
X1721617D01*
Y1166211D01*
X1721742Y1166545D01*
X1721909Y1166753D01*
X1722242Y1166836D01*
X1722575Y1166753D01*
X1722784Y1166503D01*
X1722909Y1166211D01*
Y1165170D01*
G01Y1166211D02*
X1724117Y1166836D01*
G01X1723617Y1168186D02*
X1723909Y1168436D01*
X1724075Y1168770D01*
X1724117Y1169145D01*
X1724075Y1169478D01*
X1723867Y1169811D01*
X1723617Y1170020D01*
X1723367Y1170061D01*
X1723075Y1169978D01*
X1722867Y1169686D01*
X1722784Y1169395D01*
Y1169020D01*
G01Y1169395D02*
X1722659Y1169645D01*
X1722450Y1169853D01*
X1722200Y1169936D01*
X1721950Y1169853D01*
X1721742Y1169645D01*
X1721617Y1169270D01*
X1721659Y1168895D01*
X1721825Y1168520D01*
G01X1722034Y1171411D02*
X1721784Y1171661D01*
X1721659Y1171953D01*
X1721617Y1172286D01*
X1721700Y1172703D01*
X1721909Y1172995D01*
X1722159Y1173078D01*
X1722409Y1173036D01*
X1722617Y1172870D01*
X1723034Y1172036D01*
X1723325Y1171661D01*
X1723742Y1171411D01*
X1724117Y1171328D01*
Y1173078D01*
G01X1721617Y1175303D02*
X1721700Y1174970D01*
X1721909Y1174720D01*
X1722159Y1174553D01*
X1722492Y1174428D01*
X1722867Y1174386D01*
X1723242Y1174428D01*
X1723575Y1174553D01*
X1723825Y1174720D01*
X1724034Y1174970D01*
X1724117Y1175303D01*
X1724034Y1175636D01*
X1723825Y1175886D01*
X1723575Y1176053D01*
X1723242Y1176178D01*
X1722867Y1176220D01*
X1722492Y1176178D01*
X1722159Y1176053D01*
X1721909Y1175886D01*
X1721700Y1175636D01*
X1721617Y1175303D01*
G01X1719117Y1165170D02*
X1716617D01*
Y1166211D01*
X1716742Y1166545D01*
X1716909Y1166753D01*
X1717242Y1166836D01*
X1717575Y1166753D01*
X1717784Y1166503D01*
X1717909Y1166211D01*
Y1165170D01*
G01Y1166211D02*
X1719117Y1166836D01*
G01X1718617Y1168186D02*
X1718909Y1168436D01*
X1719075Y1168770D01*
X1719117Y1169145D01*
X1719075Y1169478D01*
X1718867Y1169811D01*
X1718617Y1170020D01*
X1718367Y1170061D01*
X1718075Y1169978D01*
X1717867Y1169686D01*
X1717784Y1169395D01*
Y1169020D01*
G01Y1169395D02*
X1717659Y1169645D01*
X1717450Y1169853D01*
X1717200Y1169936D01*
X1716950Y1169853D01*
X1716742Y1169645D01*
X1716617Y1169270D01*
X1716659Y1168895D01*
X1716825Y1168520D01*
G01X1717034Y1171411D02*
X1716784Y1171661D01*
X1716659Y1171953D01*
X1716617Y1172286D01*
X1716700Y1172703D01*
X1716909Y1172995D01*
X1717159Y1173078D01*
X1717409Y1173036D01*
X1717617Y1172870D01*
X1718034Y1172036D01*
X1718325Y1171661D01*
X1718742Y1171411D01*
X1719117Y1171328D01*
Y1173078D01*
G01Y1175803D02*
X1716617D01*
X1718409Y1174261D01*
Y1176345D01*
G01X1749017Y1165500D02*
Y1168000D01*
X1750058D01*
X1750392Y1167875D01*
X1750600Y1167708D01*
X1750683Y1167375D01*
X1750600Y1167042D01*
X1750350Y1166833D01*
X1750058Y1166708D01*
X1749017D01*
G01X1750058D02*
X1750683Y1165500D01*
G01X1752033Y1166000D02*
X1752283Y1165708D01*
X1752617Y1165542D01*
X1752992Y1165500D01*
X1753325Y1165542D01*
X1753658Y1165750D01*
X1753867Y1166000D01*
X1753908Y1166250D01*
X1753825Y1166542D01*
X1753533Y1166750D01*
X1753242Y1166833D01*
X1752867D01*
G01X1753242D02*
X1753492Y1166958D01*
X1753700Y1167167D01*
X1753783Y1167417D01*
X1753700Y1167667D01*
X1753492Y1167875D01*
X1753117Y1168000D01*
X1752742Y1167958D01*
X1752367Y1167792D01*
G01X1755258Y1166542D02*
X1755550Y1166833D01*
X1755800Y1167000D01*
X1756133Y1167083D01*
X1756425Y1167000D01*
X1756633Y1166833D01*
X1756800Y1166583D01*
X1756842Y1166292D01*
X1756800Y1166042D01*
X1756633Y1165792D01*
X1756383Y1165583D01*
X1756092Y1165500D01*
X1755758Y1165583D01*
X1755467Y1165833D01*
X1755300Y1166208D01*
X1755258Y1166625D01*
X1755342Y1167167D01*
X1755467Y1167458D01*
X1755675Y1167750D01*
X1755967Y1167958D01*
X1756258Y1168000D01*
X1756550Y1167917D01*
X1756758Y1167708D01*
G01X1759650Y1165500D02*
Y1168000D01*
X1758108Y1166208D01*
X1760192D01*
G01X1752117Y1139465D02*
X1751867Y1139590D01*
X1751575Y1139673D01*
X1751242D01*
X1750867Y1139548D01*
X1750575Y1139340D01*
X1750367Y1139090D01*
X1750200Y1138673D01*
X1750158Y1138298D01*
X1750242Y1137923D01*
X1750367Y1137673D01*
X1750617Y1137423D01*
X1750908Y1137256D01*
X1751200Y1137173D01*
X1751492D01*
X1751783Y1137256D01*
X1752033Y1137381D01*
X1752242Y1137548D01*
G01X1754300Y1137173D02*
Y1139673D01*
X1753800Y1139173D01*
G01Y1137173D02*
X1754800D01*
G01X1757317D02*
X1757400Y1137715D01*
X1757525Y1138173D01*
X1757692Y1138590D01*
X1757900Y1139048D01*
X1758233Y1139673D01*
X1756567D01*
G01X1759708Y1138215D02*
X1760000Y1138506D01*
X1760250Y1138673D01*
X1760583Y1138756D01*
X1760875Y1138673D01*
X1761083Y1138506D01*
X1761250Y1138256D01*
X1761292Y1137965D01*
X1761250Y1137715D01*
X1761083Y1137465D01*
X1760833Y1137256D01*
X1760542Y1137173D01*
X1760208Y1137256D01*
X1759917Y1137506D01*
X1759750Y1137881D01*
X1759708Y1138298D01*
X1759792Y1138840D01*
X1759917Y1139131D01*
X1760125Y1139423D01*
X1760417Y1139631D01*
X1760708Y1139673D01*
X1761000Y1139590D01*
X1761208Y1139381D01*
G01X1733198Y1271565D02*
Y1282765D01*
X1741998D01*
Y1271565D01*
X1733198D01*
G01X1728515Y1285665D02*
Y1288165D01*
X1729556D01*
X1729890Y1288040D01*
X1730098Y1287873D01*
X1730181Y1287540D01*
X1730098Y1287207D01*
X1729848Y1286998D01*
X1729556Y1286873D01*
X1728515D01*
G01X1729556D02*
X1730181Y1285665D01*
G01X1731615Y1288165D02*
Y1285665D01*
X1733281D01*
G01X1736381D02*
X1734715D01*
Y1288165D01*
X1736381D01*
G01X1735715Y1286957D02*
X1734715D01*
G01X1737731Y1285665D02*
Y1288165D01*
X1738565D01*
X1738898Y1288040D01*
X1739148Y1287873D01*
X1739356Y1287623D01*
X1739523Y1287332D01*
X1739565Y1286915D01*
X1739523Y1286498D01*
X1739356Y1286207D01*
X1739148Y1285957D01*
X1738898Y1285790D01*
X1738565Y1285665D01*
X1737731D01*
G01X1740831Y1286165D02*
X1741081Y1285873D01*
X1741415Y1285707D01*
X1741790Y1285665D01*
X1742123Y1285707D01*
X1742456Y1285915D01*
X1742665Y1286165D01*
X1742706Y1286415D01*
X1742623Y1286707D01*
X1742331Y1286915D01*
X1742040Y1286998D01*
X1741665D01*
G01X1742040D02*
X1742290Y1287123D01*
X1742498Y1287332D01*
X1742581Y1287582D01*
X1742498Y1287832D01*
X1742290Y1288040D01*
X1741915Y1288165D01*
X1741540Y1288123D01*
X1741165Y1287957D01*
G01X1743931Y1286040D02*
X1744181Y1285832D01*
X1744473Y1285707D01*
X1744848Y1285665D01*
X1745223Y1285748D01*
X1745515Y1285915D01*
X1745723Y1286207D01*
X1745765Y1286540D01*
X1745681Y1286873D01*
X1745473Y1287082D01*
X1745181Y1287248D01*
X1744890Y1287290D01*
X1744598Y1287248D01*
X1744223Y1287082D01*
X1744348Y1288165D01*
X1745473D01*
G01X1798367Y154661D02*
Y157161D01*
X1799408D01*
X1799742Y157036D01*
X1799950Y156869D01*
X1800033Y156536D01*
X1799950Y156203D01*
X1799700Y155994D01*
X1799408Y155869D01*
X1798367D01*
G01X1799408D02*
X1800033Y154661D01*
G01X1801592Y154953D02*
X1801883Y154744D01*
X1802217Y154661D01*
X1802550Y154744D01*
X1802842Y154994D01*
X1803050Y155369D01*
X1803133Y155744D01*
Y156203D01*
X1803050Y156578D01*
X1802842Y156911D01*
X1802592Y157078D01*
X1802300Y157161D01*
X1801967Y157078D01*
X1801717Y156911D01*
X1801550Y156661D01*
X1801467Y156328D01*
X1801550Y156036D01*
X1801758Y155744D01*
X1802008Y155578D01*
X1802300Y155536D01*
X1802633Y155619D01*
X1802883Y155828D01*
X1803133Y156203D01*
G01X1805400Y154661D02*
Y157161D01*
X1804900Y156661D01*
G01Y154661D02*
X1805900D01*
G01X1807792Y154953D02*
X1808083Y154744D01*
X1808417Y154661D01*
X1808750Y154744D01*
X1809042Y154994D01*
X1809250Y155369D01*
X1809333Y155744D01*
Y156203D01*
X1809250Y156578D01*
X1809042Y156911D01*
X1808792Y157078D01*
X1808500Y157161D01*
X1808167Y157078D01*
X1807917Y156911D01*
X1807750Y156661D01*
X1807667Y156328D01*
X1807750Y156036D01*
X1807958Y155744D01*
X1808208Y155578D01*
X1808500Y155536D01*
X1808833Y155619D01*
X1809083Y155828D01*
X1809333Y156203D01*
G01X1809350Y138178D02*
X1806850D01*
Y139219D01*
X1806975Y139553D01*
X1807142Y139761D01*
X1807475Y139844D01*
X1807808Y139761D01*
X1808017Y139511D01*
X1808142Y139219D01*
Y138178D01*
G01Y139219D02*
X1809350Y139844D01*
G01X1809058Y141403D02*
X1809267Y141694D01*
X1809350Y142028D01*
X1809267Y142361D01*
X1809017Y142653D01*
X1808642Y142861D01*
X1808267Y142944D01*
X1807808D01*
X1807433Y142861D01*
X1807100Y142653D01*
X1806933Y142403D01*
X1806850Y142111D01*
X1806933Y141778D01*
X1807100Y141528D01*
X1807350Y141361D01*
X1807683Y141278D01*
X1807975Y141361D01*
X1808267Y141569D01*
X1808433Y141819D01*
X1808475Y142111D01*
X1808392Y142444D01*
X1808183Y142694D01*
X1807808Y142944D01*
G01X1807267Y144419D02*
X1807017Y144669D01*
X1806892Y144961D01*
X1806850Y145294D01*
X1806933Y145711D01*
X1807142Y146003D01*
X1807392Y146086D01*
X1807642Y146044D01*
X1807850Y145878D01*
X1808267Y145044D01*
X1808558Y144669D01*
X1808975Y144419D01*
X1809350Y144336D01*
Y146086D01*
G01X1806850Y148311D02*
X1806933Y147978D01*
X1807142Y147728D01*
X1807392Y147561D01*
X1807725Y147436D01*
X1808100Y147394D01*
X1808475Y147436D01*
X1808808Y147561D01*
X1809058Y147728D01*
X1809267Y147978D01*
X1809350Y148311D01*
X1809267Y148644D01*
X1809058Y148894D01*
X1808808Y149061D01*
X1808475Y149186D01*
X1808100Y149228D01*
X1807725Y149186D01*
X1807392Y149061D01*
X1807142Y148894D01*
X1806933Y148644D01*
X1806850Y148311D01*
G01Y163961D02*
X1810850D01*
Y171361D01*
G01X1804850Y138178D02*
X1802350D01*
Y139219D01*
X1802475Y139553D01*
X1802642Y139761D01*
X1802975Y139844D01*
X1803308Y139761D01*
X1803517Y139511D01*
X1803642Y139219D01*
Y138178D01*
G01Y139219D02*
X1804850Y139844D01*
G01X1804558Y141403D02*
X1804767Y141694D01*
X1804850Y142028D01*
X1804767Y142361D01*
X1804517Y142653D01*
X1804142Y142861D01*
X1803767Y142944D01*
X1803308D01*
X1802933Y142861D01*
X1802600Y142653D01*
X1802433Y142403D01*
X1802350Y142111D01*
X1802433Y141778D01*
X1802600Y141528D01*
X1802850Y141361D01*
X1803183Y141278D01*
X1803475Y141361D01*
X1803767Y141569D01*
X1803933Y141819D01*
X1803975Y142111D01*
X1803892Y142444D01*
X1803683Y142694D01*
X1803308Y142944D01*
G01X1802767Y144419D02*
X1802517Y144669D01*
X1802392Y144961D01*
X1802350Y145294D01*
X1802433Y145711D01*
X1802642Y146003D01*
X1802892Y146086D01*
X1803142Y146044D01*
X1803350Y145878D01*
X1803767Y145044D01*
X1804058Y144669D01*
X1804475Y144419D01*
X1804850Y144336D01*
Y146086D01*
G01Y148811D02*
X1802350D01*
X1804142Y147269D01*
Y149353D01*
G01X1806350Y171361D02*
X1802350D01*
Y163961D01*
G01X1799200Y151161D02*
X1798867Y151203D01*
X1798575Y151369D01*
X1798325Y151619D01*
X1798158Y151911D01*
X1798075Y152244D01*
Y152578D01*
X1798158Y152911D01*
X1798325Y153203D01*
X1798575Y153453D01*
X1798867Y153619D01*
X1799200Y153661D01*
X1799533Y153619D01*
X1799825Y153453D01*
X1800075Y153203D01*
X1800242Y152911D01*
X1800325Y152578D01*
Y152244D01*
X1800242Y151911D01*
X1800075Y151619D01*
X1799825Y151369D01*
X1799533Y151203D01*
X1799200Y151161D01*
G01X1799533Y151828D02*
X1800033Y151161D01*
G01X1801508Y153244D02*
X1801758Y153494D01*
X1802050Y153619D01*
X1802383Y153661D01*
X1802800Y153578D01*
X1803092Y153369D01*
X1803175Y153119D01*
X1803133Y152869D01*
X1802967Y152661D01*
X1802133Y152244D01*
X1801758Y151953D01*
X1801508Y151536D01*
X1801425Y151161D01*
X1803175D01*
G01X1805400Y153661D02*
X1805067Y153578D01*
X1804817Y153369D01*
X1804650Y153119D01*
X1804525Y152786D01*
X1804483Y152411D01*
X1804525Y152036D01*
X1804650Y151703D01*
X1804817Y151453D01*
X1805067Y151244D01*
X1805400Y151161D01*
X1805733Y151244D01*
X1805983Y151453D01*
X1806150Y151703D01*
X1806275Y152036D01*
X1806317Y152411D01*
X1806275Y152786D01*
X1806150Y153119D01*
X1805983Y153369D01*
X1805733Y153578D01*
X1805400Y153661D01*
G01X1807583Y151536D02*
X1807833Y151328D01*
X1808125Y151203D01*
X1808500Y151161D01*
X1808875Y151244D01*
X1809167Y151411D01*
X1809375Y151703D01*
X1809417Y152036D01*
X1809333Y152369D01*
X1809125Y152578D01*
X1808833Y152744D01*
X1808542Y152786D01*
X1808250Y152744D01*
X1807875Y152578D01*
X1808000Y153661D01*
X1809125D01*
G01X1800117Y161053D02*
X1799867Y161178D01*
X1799575Y161261D01*
X1799242D01*
X1798867Y161136D01*
X1798575Y160928D01*
X1798367Y160678D01*
X1798200Y160261D01*
X1798158Y159886D01*
X1798242Y159511D01*
X1798367Y159261D01*
X1798617Y159011D01*
X1798908Y158844D01*
X1799200Y158761D01*
X1799492D01*
X1799783Y158844D01*
X1800033Y158969D01*
X1800242Y159136D01*
G01X1802800Y158761D02*
Y161261D01*
X1801258Y159469D01*
X1803342D01*
G01X1804692Y159053D02*
X1804983Y158844D01*
X1805317Y158761D01*
X1805650Y158844D01*
X1805942Y159094D01*
X1806150Y159469D01*
X1806233Y159844D01*
Y160303D01*
X1806150Y160678D01*
X1805942Y161011D01*
X1805692Y161178D01*
X1805400Y161261D01*
X1805067Y161178D01*
X1804817Y161011D01*
X1804650Y160761D01*
X1804567Y160428D01*
X1804650Y160136D01*
X1804858Y159844D01*
X1805108Y159678D01*
X1805400Y159636D01*
X1805733Y159719D01*
X1805983Y159928D01*
X1806233Y160303D01*
G01X1808500Y161261D02*
X1808167Y161178D01*
X1807917Y160969D01*
X1807750Y160719D01*
X1807625Y160386D01*
X1807583Y160011D01*
X1807625Y159636D01*
X1807750Y159303D01*
X1807917Y159053D01*
X1808167Y158844D01*
X1808500Y158761D01*
X1808833Y158844D01*
X1809083Y159053D01*
X1809250Y159303D01*
X1809375Y159636D01*
X1809417Y160011D01*
X1809375Y160386D01*
X1809250Y160719D01*
X1809083Y160969D01*
X1808833Y161178D01*
X1808500Y161261D01*
G01X1810550Y189161D02*
Y193161D01*
X1803150D01*
G01X1797650Y183861D02*
Y172461D01*
G01X1811050Y183861D02*
X1797650D01*
G01X1811050Y172461D02*
Y183861D01*
G01X1797650Y172461D02*
X1811050D01*
G01X1799500Y202850D02*
X1799458Y202517D01*
X1799292Y202225D01*
X1799042Y201975D01*
X1798750Y201808D01*
X1798417Y201725D01*
X1798083D01*
X1797750Y201808D01*
X1797458Y201975D01*
X1797208Y202225D01*
X1797042Y202517D01*
X1797000Y202850D01*
X1797042Y203183D01*
X1797208Y203475D01*
X1797458Y203725D01*
X1797750Y203892D01*
X1798083Y203975D01*
X1798417D01*
X1798750Y203892D01*
X1799042Y203725D01*
X1799292Y203475D01*
X1799458Y203183D01*
X1799500Y202850D01*
G01X1798833Y203183D02*
X1799500Y203683D01*
G01X1797417Y205158D02*
X1797167Y205408D01*
X1797042Y205700D01*
X1797000Y206033D01*
X1797083Y206450D01*
X1797292Y206742D01*
X1797542Y206825D01*
X1797792Y206783D01*
X1798000Y206617D01*
X1798417Y205783D01*
X1798708Y205408D01*
X1799125Y205158D01*
X1799500Y205075D01*
Y206825D01*
G01X1797000Y209050D02*
X1797083Y208717D01*
X1797292Y208467D01*
X1797542Y208300D01*
X1797875Y208175D01*
X1798250Y208133D01*
X1798625Y208175D01*
X1798958Y208300D01*
X1799208Y208467D01*
X1799417Y208717D01*
X1799500Y209050D01*
X1799417Y209383D01*
X1799208Y209633D01*
X1798958Y209800D01*
X1798625Y209925D01*
X1798250Y209967D01*
X1797875Y209925D01*
X1797542Y209800D01*
X1797292Y209633D01*
X1797083Y209383D01*
X1797000Y209050D01*
G01X1799000Y211233D02*
X1799292Y211483D01*
X1799458Y211817D01*
X1799500Y212192D01*
X1799458Y212525D01*
X1799250Y212858D01*
X1799000Y213067D01*
X1798750Y213108D01*
X1798458Y213025D01*
X1798250Y212733D01*
X1798167Y212442D01*
Y212067D01*
G01Y212442D02*
X1798042Y212692D01*
X1797833Y212900D01*
X1797583Y212983D01*
X1797333Y212900D01*
X1797125Y212692D01*
X1797000Y212317D01*
X1797042Y211942D01*
X1797208Y211567D01*
G01X1809750Y218961D02*
Y199761D01*
X1820950D01*
Y218961D01*
X1809750D01*
Y218561D01*
G01X1802367Y221661D02*
Y224161D01*
X1803408D01*
X1803742Y224036D01*
X1803950Y223869D01*
X1804033Y223536D01*
X1803950Y223203D01*
X1803700Y222994D01*
X1803408Y222869D01*
X1802367D01*
G01X1803408D02*
X1804033Y221661D01*
G01X1805592Y221953D02*
X1805883Y221744D01*
X1806217Y221661D01*
X1806550Y221744D01*
X1806842Y221994D01*
X1807050Y222369D01*
X1807133Y222744D01*
Y223203D01*
X1807050Y223578D01*
X1806842Y223911D01*
X1806592Y224078D01*
X1806300Y224161D01*
X1805967Y224078D01*
X1805717Y223911D01*
X1805550Y223661D01*
X1805467Y223328D01*
X1805550Y223036D01*
X1805758Y222744D01*
X1806008Y222578D01*
X1806300Y222536D01*
X1806633Y222619D01*
X1806883Y222828D01*
X1807133Y223203D01*
G01X1808608Y223744D02*
X1808858Y223994D01*
X1809150Y224119D01*
X1809483Y224161D01*
X1809900Y224078D01*
X1810192Y223869D01*
X1810275Y223619D01*
X1810233Y223369D01*
X1810067Y223161D01*
X1809233Y222744D01*
X1808858Y222453D01*
X1808608Y222036D01*
X1808525Y221661D01*
X1810275D01*
G01X1811583Y222036D02*
X1811833Y221828D01*
X1812125Y221703D01*
X1812500Y221661D01*
X1812875Y221744D01*
X1813167Y221911D01*
X1813375Y222203D01*
X1813417Y222536D01*
X1813333Y222869D01*
X1813125Y223078D01*
X1812833Y223244D01*
X1812542Y223286D01*
X1812250Y223244D01*
X1811875Y223078D01*
X1812000Y224161D01*
X1813125D01*
G01X1796517Y232500D02*
Y235000D01*
X1797558D01*
X1797892Y234875D01*
X1798100Y234708D01*
X1798183Y234375D01*
X1798100Y234042D01*
X1797850Y233833D01*
X1797558Y233708D01*
X1796517D01*
G01X1797558D02*
X1798183Y232500D01*
G01X1799742Y232792D02*
X1800033Y232583D01*
X1800367Y232500D01*
X1800700Y232583D01*
X1800992Y232833D01*
X1801200Y233208D01*
X1801283Y233583D01*
Y234042D01*
X1801200Y234417D01*
X1800992Y234750D01*
X1800742Y234917D01*
X1800450Y235000D01*
X1800117Y234917D01*
X1799867Y234750D01*
X1799700Y234500D01*
X1799617Y234167D01*
X1799700Y233875D01*
X1799908Y233583D01*
X1800158Y233417D01*
X1800450Y233375D01*
X1800783Y233458D01*
X1801033Y233667D01*
X1801283Y234042D01*
G01X1803550Y232500D02*
Y235000D01*
X1803050Y234500D01*
G01Y232500D02*
X1804050D01*
G01X1806650D02*
Y235000D01*
X1806150Y234500D01*
G01Y232500D02*
X1807150D01*
G01X1810650Y244661D02*
Y236661D01*
X1793050D01*
Y244661D01*
X1810650D01*
G01X1797708Y247767D02*
X1797583Y247517D01*
X1797500Y247225D01*
Y246892D01*
X1797625Y246517D01*
X1797833Y246225D01*
X1798083Y246017D01*
X1798500Y245850D01*
X1798875Y245808D01*
X1799250Y245892D01*
X1799500Y246017D01*
X1799750Y246267D01*
X1799917Y246558D01*
X1800000Y246850D01*
Y247142D01*
X1799917Y247433D01*
X1799792Y247683D01*
X1799625Y247892D01*
G01X1800000Y250450D02*
X1797500D01*
X1799292Y248908D01*
Y250992D01*
G01X1800000Y253050D02*
X1799958Y253342D01*
X1799833Y253675D01*
X1799625Y253883D01*
X1799333Y253967D01*
X1799042Y253883D01*
X1798792Y253633D01*
X1798667Y253258D01*
Y252842D01*
X1798583Y252592D01*
X1798375Y252383D01*
X1798083Y252300D01*
X1797792Y252425D01*
X1797583Y252717D01*
X1797500Y253050D01*
X1797583Y253383D01*
X1797792Y253675D01*
X1798083Y253800D01*
X1798375Y253717D01*
X1798583Y253508D01*
X1798667Y253258D01*
Y252842D01*
X1798792Y252467D01*
X1799042Y252217D01*
X1799333Y252133D01*
X1799625Y252217D01*
X1799833Y252425D01*
X1799958Y252758D01*
X1800000Y253050D01*
G01X1799500Y255233D02*
X1799792Y255483D01*
X1799958Y255817D01*
X1800000Y256192D01*
X1799958Y256525D01*
X1799750Y256858D01*
X1799500Y257067D01*
X1799250Y257108D01*
X1798958Y257025D01*
X1798750Y256733D01*
X1798667Y256442D01*
Y256067D01*
G01Y256442D02*
X1798542Y256692D01*
X1798333Y256900D01*
X1798083Y256983D01*
X1797833Y256900D01*
X1797625Y256692D01*
X1797500Y256317D01*
X1797542Y255942D01*
X1797708Y255567D01*
G01X1801350Y250361D02*
Y255861D01*
G01X1809350Y250361D02*
X1801350D01*
G01X1809350Y255861D02*
Y250361D01*
G01X1812150Y246161D02*
X1814250Y244361D01*
X1812150Y242161D01*
G01X1812050Y238561D02*
X1831250D01*
Y249761D01*
X1812050D01*
Y238561D01*
X1812450D01*
G01X1817350Y218861D02*
X1815550Y216761D01*
X1813350Y218861D01*
G01X1804117Y228053D02*
X1803867Y228178D01*
X1803575Y228261D01*
X1803242D01*
X1802867Y228136D01*
X1802575Y227928D01*
X1802367Y227678D01*
X1802200Y227261D01*
X1802158Y226886D01*
X1802242Y226511D01*
X1802367Y226261D01*
X1802617Y226011D01*
X1802908Y225844D01*
X1803200Y225761D01*
X1803492D01*
X1803783Y225844D01*
X1804033Y225969D01*
X1804242Y226136D01*
G01X1806800Y225761D02*
Y228261D01*
X1805258Y226469D01*
X1807342D01*
G01X1808692Y226053D02*
X1808983Y225844D01*
X1809317Y225761D01*
X1809650Y225844D01*
X1809942Y226094D01*
X1810150Y226469D01*
X1810233Y226844D01*
Y227303D01*
X1810150Y227678D01*
X1809942Y228011D01*
X1809692Y228178D01*
X1809400Y228261D01*
X1809067Y228178D01*
X1808817Y228011D01*
X1808650Y227761D01*
X1808567Y227428D01*
X1808650Y227136D01*
X1808858Y226844D01*
X1809108Y226678D01*
X1809400Y226636D01*
X1809733Y226719D01*
X1809983Y226928D01*
X1810233Y227303D01*
G01X1812500Y225761D02*
Y228261D01*
X1812000Y227761D01*
G01Y225761D02*
X1813000D01*
G01X1812517Y265500D02*
Y268000D01*
X1813558D01*
X1813892Y267875D01*
X1814100Y267708D01*
X1814183Y267375D01*
X1814100Y267042D01*
X1813850Y266833D01*
X1813558Y266708D01*
X1812517D01*
G01X1813558D02*
X1814183Y265500D01*
G01X1815742Y265792D02*
X1816033Y265583D01*
X1816367Y265500D01*
X1816700Y265583D01*
X1816992Y265833D01*
X1817200Y266208D01*
X1817283Y266583D01*
Y267042D01*
X1817200Y267417D01*
X1816992Y267750D01*
X1816742Y267917D01*
X1816450Y268000D01*
X1816117Y267917D01*
X1815867Y267750D01*
X1815700Y267500D01*
X1815617Y267167D01*
X1815700Y266875D01*
X1815908Y266583D01*
X1816158Y266417D01*
X1816450Y266375D01*
X1816783Y266458D01*
X1817033Y266667D01*
X1817283Y267042D01*
G01X1819550Y265500D02*
Y268000D01*
X1819050Y267500D01*
G01Y265500D02*
X1820050D01*
G01X1821733Y266000D02*
X1821983Y265708D01*
X1822317Y265542D01*
X1822692Y265500D01*
X1823025Y265542D01*
X1823358Y265750D01*
X1823567Y266000D01*
X1823608Y266250D01*
X1823525Y266542D01*
X1823233Y266750D01*
X1822942Y266833D01*
X1822567D01*
G01X1822942D02*
X1823192Y266958D01*
X1823400Y267167D01*
X1823483Y267417D01*
X1823400Y267667D01*
X1823192Y267875D01*
X1822817Y268000D01*
X1822442Y267958D01*
X1822067Y267792D01*
G01X1818866Y277190D02*
Y269190D01*
X1801266D01*
Y277190D01*
X1818866D01*
G01X1809350Y267961D02*
Y262461D01*
G01X1801350Y267961D02*
X1809350D01*
G01X1801350Y262461D02*
Y267961D01*
G01X1794208Y271267D02*
X1794083Y271017D01*
X1794000Y270725D01*
Y270392D01*
X1794125Y270017D01*
X1794333Y269725D01*
X1794583Y269517D01*
X1795000Y269350D01*
X1795375Y269308D01*
X1795750Y269392D01*
X1796000Y269517D01*
X1796250Y269767D01*
X1796417Y270058D01*
X1796500Y270350D01*
Y270642D01*
X1796417Y270933D01*
X1796292Y271183D01*
X1796125Y271392D01*
G01X1796500Y273950D02*
X1794000D01*
X1795792Y272408D01*
Y274492D01*
G01X1796500Y276550D02*
X1796458Y276842D01*
X1796333Y277175D01*
X1796125Y277383D01*
X1795833Y277467D01*
X1795542Y277383D01*
X1795292Y277133D01*
X1795167Y276758D01*
Y276342D01*
X1795083Y276092D01*
X1794875Y275883D01*
X1794583Y275800D01*
X1794292Y275925D01*
X1794083Y276217D01*
X1794000Y276550D01*
X1794083Y276883D01*
X1794292Y277175D01*
X1794583Y277300D01*
X1794875Y277217D01*
X1795083Y277008D01*
X1795167Y276758D01*
Y276342D01*
X1795292Y275967D01*
X1795542Y275717D01*
X1795833Y275633D01*
X1796125Y275717D01*
X1796333Y275925D01*
X1796458Y276258D01*
X1796500Y276550D01*
G01X1794417Y278858D02*
X1794167Y279108D01*
X1794042Y279400D01*
X1794000Y279733D01*
X1794083Y280150D01*
X1794292Y280442D01*
X1794542Y280525D01*
X1794792Y280483D01*
X1795000Y280317D01*
X1795417Y279483D01*
X1795708Y279108D01*
X1796125Y278858D01*
X1796500Y278775D01*
Y280525D01*
G01X1766818Y329492D02*
Y331992D01*
G01X1768568D02*
Y329492D01*
G01Y330742D02*
X1766818D01*
G01X1769876Y329492D02*
Y331992D01*
X1770710D01*
X1771043Y331867D01*
X1771293Y331700D01*
X1771501Y331450D01*
X1771668Y331159D01*
X1771710Y330742D01*
X1771668Y330325D01*
X1771501Y330034D01*
X1771293Y329784D01*
X1771043Y329617D01*
X1770710Y329492D01*
X1769876D01*
G01X1772976D02*
Y331992D01*
X1773810D01*
X1774143Y331867D01*
X1774393Y331700D01*
X1774601Y331450D01*
X1774768Y331159D01*
X1774810Y330742D01*
X1774768Y330325D01*
X1774601Y330034D01*
X1774393Y329784D01*
X1774143Y329617D01*
X1773810Y329492D01*
X1772976D01*
G01X1776118Y329825D02*
X1776451Y329617D01*
X1776826Y329492D01*
X1777160D01*
X1777493Y329617D01*
X1777743Y329825D01*
X1777868Y330117D01*
X1777785Y330409D01*
X1777576Y330659D01*
X1777201Y330825D01*
X1776701Y330909D01*
X1776410Y331075D01*
X1776285Y331367D01*
X1776368Y331659D01*
X1776576Y331867D01*
X1776868Y331992D01*
X1777160D01*
X1777451Y331909D01*
X1777701Y331700D01*
G01X1779051Y329492D02*
X1780093Y331992D01*
X1781135Y329492D01*
G01X1780760Y330367D02*
X1779426D01*
G01X1782318Y329825D02*
X1782651Y329617D01*
X1783026Y329492D01*
X1783360D01*
X1783693Y329617D01*
X1783943Y329825D01*
X1784068Y330117D01*
X1783985Y330409D01*
X1783776Y330659D01*
X1783401Y330825D01*
X1782901Y330909D01*
X1782610Y331075D01*
X1782485Y331367D01*
X1782568Y331659D01*
X1782776Y331867D01*
X1783068Y331992D01*
X1783360D01*
X1783651Y331909D01*
X1783901Y331700D01*
G01X1785376Y329992D02*
X1785626Y329700D01*
X1785960Y329534D01*
X1786335Y329492D01*
X1786668Y329534D01*
X1787001Y329742D01*
X1787210Y329992D01*
X1787251Y330242D01*
X1787168Y330534D01*
X1786876Y330742D01*
X1786585Y330825D01*
X1786210D01*
G01X1786585D02*
X1786835Y330950D01*
X1787043Y331159D01*
X1787126Y331409D01*
X1787043Y331659D01*
X1786835Y331867D01*
X1786460Y331992D01*
X1786085Y331950D01*
X1785710Y331784D01*
G01X1789893Y329492D02*
Y331992D01*
X1788351Y330200D01*
X1790435D01*
G01X1807850Y584434D02*
X1805350D01*
Y585475D01*
X1805475Y585809D01*
X1805642Y586017D01*
X1805975Y586100D01*
X1806308Y586017D01*
X1806517Y585767D01*
X1806642Y585475D01*
Y584434D01*
G01Y585475D02*
X1807850Y586100D01*
G01X1806808Y587575D02*
X1806517Y587867D01*
X1806350Y588117D01*
X1806267Y588450D01*
X1806350Y588742D01*
X1806517Y588950D01*
X1806767Y589117D01*
X1807058Y589159D01*
X1807308Y589117D01*
X1807558Y588950D01*
X1807767Y588700D01*
X1807850Y588409D01*
X1807767Y588075D01*
X1807517Y587784D01*
X1807142Y587617D01*
X1806725Y587575D01*
X1806183Y587659D01*
X1805892Y587784D01*
X1805600Y587992D01*
X1805392Y588284D01*
X1805350Y588575D01*
X1805433Y588867D01*
X1805642Y589075D01*
G01X1807850Y591967D02*
X1805350D01*
X1807142Y590425D01*
Y592509D01*
G01X1807850Y595067D02*
X1805350D01*
X1807142Y593525D01*
Y595609D01*
G01X1803350Y584434D02*
X1800850D01*
Y585475D01*
X1800975Y585809D01*
X1801142Y586017D01*
X1801475Y586100D01*
X1801808Y586017D01*
X1802017Y585767D01*
X1802142Y585475D01*
Y584434D01*
G01Y585475D02*
X1803350Y586100D01*
G01X1802308Y587575D02*
X1802017Y587867D01*
X1801850Y588117D01*
X1801767Y588450D01*
X1801850Y588742D01*
X1802017Y588950D01*
X1802267Y589117D01*
X1802558Y589159D01*
X1802808Y589117D01*
X1803058Y588950D01*
X1803267Y588700D01*
X1803350Y588409D01*
X1803267Y588075D01*
X1803017Y587784D01*
X1802642Y587617D01*
X1802225Y587575D01*
X1801683Y587659D01*
X1801392Y587784D01*
X1801100Y587992D01*
X1800892Y588284D01*
X1800850Y588575D01*
X1800933Y588867D01*
X1801142Y589075D01*
G01X1803350Y591967D02*
X1800850D01*
X1802642Y590425D01*
Y592509D01*
G01X1803058Y593859D02*
X1803267Y594150D01*
X1803350Y594484D01*
X1803267Y594817D01*
X1803017Y595109D01*
X1802642Y595317D01*
X1802267Y595400D01*
X1801808D01*
X1801433Y595317D01*
X1801100Y595109D01*
X1800933Y594859D01*
X1800850Y594567D01*
X1800933Y594234D01*
X1801100Y593984D01*
X1801350Y593817D01*
X1801683Y593734D01*
X1801975Y593817D01*
X1802267Y594025D01*
X1802433Y594275D01*
X1802475Y594567D01*
X1802392Y594900D01*
X1802183Y595150D01*
X1801808Y595400D01*
G01X1798215Y597500D02*
X1797882Y597542D01*
X1797590Y597708D01*
X1797340Y597958D01*
X1797173Y598250D01*
X1797090Y598583D01*
Y598917D01*
X1797173Y599250D01*
X1797340Y599542D01*
X1797590Y599792D01*
X1797882Y599958D01*
X1798215Y600000D01*
X1798548Y599958D01*
X1798840Y599792D01*
X1799090Y599542D01*
X1799257Y599250D01*
X1799340Y598917D01*
Y598583D01*
X1799257Y598250D01*
X1799090Y597958D01*
X1798840Y597708D01*
X1798548Y597542D01*
X1798215Y597500D01*
G01X1798548Y598167D02*
X1799048Y597500D01*
G01X1801315D02*
Y600000D01*
X1800815Y599500D01*
G01Y597500D02*
X1801815D01*
G01X1803498Y598000D02*
X1803748Y597708D01*
X1804082Y597542D01*
X1804457Y597500D01*
X1804790Y597542D01*
X1805123Y597750D01*
X1805332Y598000D01*
X1805373Y598250D01*
X1805290Y598542D01*
X1804998Y598750D01*
X1804707Y598833D01*
X1804332D01*
G01X1804707D02*
X1804957Y598958D01*
X1805165Y599167D01*
X1805248Y599417D01*
X1805165Y599667D01*
X1804957Y599875D01*
X1804582Y600000D01*
X1804207Y599958D01*
X1803832Y599792D01*
G01X1806598Y598000D02*
X1806848Y597708D01*
X1807182Y597542D01*
X1807557Y597500D01*
X1807890Y597542D01*
X1808223Y597750D01*
X1808432Y598000D01*
X1808473Y598250D01*
X1808390Y598542D01*
X1808098Y598750D01*
X1807807Y598833D01*
X1807432D01*
G01X1807807D02*
X1808057Y598958D01*
X1808265Y599167D01*
X1808348Y599417D01*
X1808265Y599667D01*
X1808057Y599875D01*
X1807682Y600000D01*
X1807307Y599958D01*
X1806932Y599792D01*
G01X1797382Y602167D02*
Y604667D01*
X1798423D01*
X1798757Y604542D01*
X1798965Y604375D01*
X1799048Y604042D01*
X1798965Y603709D01*
X1798715Y603500D01*
X1798423Y603375D01*
X1797382D01*
G01X1798423D02*
X1799048Y602167D01*
G01X1800523Y603209D02*
X1800815Y603500D01*
X1801065Y603667D01*
X1801398Y603750D01*
X1801690Y603667D01*
X1801898Y603500D01*
X1802065Y603250D01*
X1802107Y602959D01*
X1802065Y602709D01*
X1801898Y602459D01*
X1801648Y602250D01*
X1801357Y602167D01*
X1801023Y602250D01*
X1800732Y602500D01*
X1800565Y602875D01*
X1800523Y603292D01*
X1800607Y603834D01*
X1800732Y604125D01*
X1800940Y604417D01*
X1801232Y604625D01*
X1801523Y604667D01*
X1801815Y604584D01*
X1802023Y604375D01*
G01X1804915Y602167D02*
Y604667D01*
X1803373Y602875D01*
X1805457D01*
G01X1806598Y602667D02*
X1806848Y602375D01*
X1807182Y602209D01*
X1807557Y602167D01*
X1807890Y602209D01*
X1808223Y602417D01*
X1808432Y602667D01*
X1808473Y602917D01*
X1808390Y603209D01*
X1808098Y603417D01*
X1807807Y603500D01*
X1807432D01*
G01X1807807D02*
X1808057Y603625D01*
X1808265Y603834D01*
X1808348Y604084D01*
X1808265Y604334D01*
X1808057Y604542D01*
X1807682Y604667D01*
X1807307Y604625D01*
X1806932Y604459D01*
G01X1810550Y641917D02*
Y645917D01*
X1803150D01*
G01X1806850Y616717D02*
X1810850D01*
Y624117D01*
G01X1806350D02*
X1802350D01*
Y616717D01*
G01X1797650Y636617D02*
Y625217D01*
G01X1811050Y636617D02*
X1797650D01*
G01X1811050Y625217D02*
Y636617D01*
G01X1797650Y625217D02*
X1811050D01*
G01X1800767Y612459D02*
X1800517Y612584D01*
X1800225Y612667D01*
X1799892D01*
X1799517Y612542D01*
X1799225Y612334D01*
X1799017Y612084D01*
X1798850Y611667D01*
X1798808Y611292D01*
X1798892Y610917D01*
X1799017Y610667D01*
X1799267Y610417D01*
X1799558Y610250D01*
X1799850Y610167D01*
X1800142D01*
X1800433Y610250D01*
X1800683Y610375D01*
X1800892Y610542D01*
G01X1802033Y610667D02*
X1802283Y610375D01*
X1802617Y610209D01*
X1802992Y610167D01*
X1803325Y610209D01*
X1803658Y610417D01*
X1803867Y610667D01*
X1803908Y610917D01*
X1803825Y611209D01*
X1803533Y611417D01*
X1803242Y611500D01*
X1802867D01*
G01X1803242D02*
X1803492Y611625D01*
X1803700Y611834D01*
X1803783Y612084D01*
X1803700Y612334D01*
X1803492Y612542D01*
X1803117Y612667D01*
X1802742Y612625D01*
X1802367Y612459D01*
G01X1805133Y610667D02*
X1805383Y610375D01*
X1805717Y610209D01*
X1806092Y610167D01*
X1806425Y610209D01*
X1806758Y610417D01*
X1806967Y610667D01*
X1807008Y610917D01*
X1806925Y611209D01*
X1806633Y611417D01*
X1806342Y611500D01*
X1805967D01*
G01X1806342D02*
X1806592Y611625D01*
X1806800Y611834D01*
X1806883Y612084D01*
X1806800Y612334D01*
X1806592Y612542D01*
X1806217Y612667D01*
X1805842Y612625D01*
X1805467Y612459D01*
G01X1809650Y610167D02*
Y612667D01*
X1808108Y610875D01*
X1810192D01*
G01X1797517Y685000D02*
Y687500D01*
X1798558D01*
X1798892Y687375D01*
X1799100Y687208D01*
X1799183Y686875D01*
X1799100Y686542D01*
X1798850Y686333D01*
X1798558Y686208D01*
X1797517D01*
G01X1798558D02*
X1799183Y685000D01*
G01X1800658Y686042D02*
X1800950Y686333D01*
X1801200Y686500D01*
X1801533Y686583D01*
X1801825Y686500D01*
X1802033Y686333D01*
X1802200Y686083D01*
X1802242Y685792D01*
X1802200Y685542D01*
X1802033Y685292D01*
X1801783Y685083D01*
X1801492Y685000D01*
X1801158Y685083D01*
X1800867Y685333D01*
X1800700Y685708D01*
X1800658Y686125D01*
X1800742Y686667D01*
X1800867Y686958D01*
X1801075Y687250D01*
X1801367Y687458D01*
X1801658Y687500D01*
X1801950Y687417D01*
X1802158Y687208D01*
G01X1803633Y685500D02*
X1803883Y685208D01*
X1804217Y685042D01*
X1804592Y685000D01*
X1804925Y685042D01*
X1805258Y685250D01*
X1805467Y685500D01*
X1805508Y685750D01*
X1805425Y686042D01*
X1805133Y686250D01*
X1804842Y686333D01*
X1804467D01*
G01X1804842D02*
X1805092Y686458D01*
X1805300Y686667D01*
X1805383Y686917D01*
X1805300Y687167D01*
X1805092Y687375D01*
X1804717Y687500D01*
X1804342Y687458D01*
X1803967Y687292D01*
G01X1806733Y685375D02*
X1806983Y685167D01*
X1807275Y685042D01*
X1807650Y685000D01*
X1808025Y685083D01*
X1808317Y685250D01*
X1808525Y685542D01*
X1808567Y685875D01*
X1808483Y686208D01*
X1808275Y686417D01*
X1807983Y686583D01*
X1807692Y686625D01*
X1807400Y686583D01*
X1807025Y686417D01*
X1807150Y687500D01*
X1808275D01*
G01X1810650Y697417D02*
Y689417D01*
X1793050D01*
Y697417D01*
X1810650D01*
G01X1812150Y698917D02*
X1814250Y697117D01*
X1812150Y694917D01*
G01X1812050Y691317D02*
X1831250D01*
Y702517D01*
X1812050D01*
Y691317D01*
X1812450D01*
G01X1801850Y673500D02*
X1801517Y673542D01*
X1801225Y673708D01*
X1800975Y673958D01*
X1800808Y674250D01*
X1800725Y674583D01*
Y674917D01*
X1800808Y675250D01*
X1800975Y675542D01*
X1801225Y675792D01*
X1801517Y675958D01*
X1801850Y676000D01*
X1802183Y675958D01*
X1802475Y675792D01*
X1802725Y675542D01*
X1802892Y675250D01*
X1802975Y674917D01*
Y674583D01*
X1802892Y674250D01*
X1802725Y673958D01*
X1802475Y673708D01*
X1802183Y673542D01*
X1801850Y673500D01*
G01X1802183Y674167D02*
X1802683Y673500D01*
G01X1804950D02*
Y676000D01*
X1804450Y675500D01*
G01Y673500D02*
X1805450D01*
G01X1807133Y674000D02*
X1807383Y673708D01*
X1807717Y673542D01*
X1808092Y673500D01*
X1808425Y673542D01*
X1808758Y673750D01*
X1808967Y674000D01*
X1809008Y674250D01*
X1808925Y674542D01*
X1808633Y674750D01*
X1808342Y674833D01*
X1807967D01*
G01X1808342D02*
X1808592Y674958D01*
X1808800Y675167D01*
X1808883Y675417D01*
X1808800Y675667D01*
X1808592Y675875D01*
X1808217Y676000D01*
X1807842Y675958D01*
X1807467Y675792D01*
G01X1810358Y675583D02*
X1810608Y675833D01*
X1810900Y675958D01*
X1811233Y676000D01*
X1811650Y675917D01*
X1811942Y675708D01*
X1812025Y675458D01*
X1811983Y675208D01*
X1811817Y675000D01*
X1810983Y674583D01*
X1810608Y674292D01*
X1810358Y673875D01*
X1810275Y673500D01*
X1812025D01*
G01X1817350Y671617D02*
X1815550Y669517D01*
X1813350Y671617D01*
G01X1809750Y671717D02*
Y652517D01*
X1820950D01*
Y671717D01*
X1809750D01*
Y671317D01*
G01X1811517Y731500D02*
Y734000D01*
X1812558D01*
X1812892Y733875D01*
X1813100Y733708D01*
X1813183Y733375D01*
X1813100Y733042D01*
X1812850Y732833D01*
X1812558Y732708D01*
X1811517D01*
G01X1812558D02*
X1813183Y731500D01*
G01X1814658Y732542D02*
X1814950Y732833D01*
X1815200Y733000D01*
X1815533Y733083D01*
X1815825Y733000D01*
X1816033Y732833D01*
X1816200Y732583D01*
X1816242Y732292D01*
X1816200Y732042D01*
X1816033Y731792D01*
X1815783Y731583D01*
X1815492Y731500D01*
X1815158Y731583D01*
X1814867Y731833D01*
X1814700Y732208D01*
X1814658Y732625D01*
X1814742Y733167D01*
X1814867Y733458D01*
X1815075Y733750D01*
X1815367Y733958D01*
X1815658Y734000D01*
X1815950Y733917D01*
X1816158Y733708D01*
G01X1817633Y732000D02*
X1817883Y731708D01*
X1818217Y731542D01*
X1818592Y731500D01*
X1818925Y731542D01*
X1819258Y731750D01*
X1819467Y732000D01*
X1819508Y732250D01*
X1819425Y732542D01*
X1819133Y732750D01*
X1818842Y732833D01*
X1818467D01*
G01X1818842D02*
X1819092Y732958D01*
X1819300Y733167D01*
X1819383Y733417D01*
X1819300Y733667D01*
X1819092Y733875D01*
X1818717Y734000D01*
X1818342Y733958D01*
X1817967Y733792D01*
G01X1821567Y731500D02*
X1821650Y732042D01*
X1821775Y732500D01*
X1821942Y732917D01*
X1822150Y733375D01*
X1822483Y734000D01*
X1820817D01*
G01X1821223Y729768D02*
Y721768D01*
X1803623D01*
Y729768D01*
X1821223D01*
G01X1797708Y700767D02*
X1797583Y700517D01*
X1797500Y700225D01*
Y699892D01*
X1797625Y699517D01*
X1797833Y699225D01*
X1798083Y699017D01*
X1798500Y698850D01*
X1798875Y698808D01*
X1799250Y698892D01*
X1799500Y699017D01*
X1799750Y699267D01*
X1799917Y699558D01*
X1800000Y699850D01*
Y700142D01*
X1799917Y700433D01*
X1799792Y700683D01*
X1799625Y700892D01*
G01X1799500Y702033D02*
X1799792Y702283D01*
X1799958Y702617D01*
X1800000Y702992D01*
X1799958Y703325D01*
X1799750Y703658D01*
X1799500Y703867D01*
X1799250Y703908D01*
X1798958Y703825D01*
X1798750Y703533D01*
X1798667Y703242D01*
Y702867D01*
G01Y703242D02*
X1798542Y703492D01*
X1798333Y703700D01*
X1798083Y703783D01*
X1797833Y703700D01*
X1797625Y703492D01*
X1797500Y703117D01*
X1797542Y702742D01*
X1797708Y702367D01*
G01X1797917Y705258D02*
X1797667Y705508D01*
X1797542Y705800D01*
X1797500Y706133D01*
X1797583Y706550D01*
X1797792Y706842D01*
X1798042Y706925D01*
X1798292Y706883D01*
X1798500Y706717D01*
X1798917Y705883D01*
X1799208Y705508D01*
X1799625Y705258D01*
X1800000Y705175D01*
Y706925D01*
G01Y709067D02*
X1799458Y709150D01*
X1799000Y709275D01*
X1798583Y709442D01*
X1798125Y709650D01*
X1797500Y709983D01*
Y708317D01*
G01X1801350Y703117D02*
Y708617D01*
G01X1809350Y703117D02*
X1801350D01*
G01X1809350Y708617D02*
Y703117D01*
G01Y720717D02*
Y715217D01*
G01X1801350Y720717D02*
X1809350D01*
G01X1801350Y715217D02*
Y720717D01*
G01X1794208Y723767D02*
X1794083Y723517D01*
X1794000Y723225D01*
Y722892D01*
X1794125Y722517D01*
X1794333Y722225D01*
X1794583Y722017D01*
X1795000Y721850D01*
X1795375Y721808D01*
X1795750Y721892D01*
X1796000Y722017D01*
X1796250Y722267D01*
X1796417Y722558D01*
X1796500Y722850D01*
Y723142D01*
X1796417Y723433D01*
X1796292Y723683D01*
X1796125Y723892D01*
G01X1796000Y725033D02*
X1796292Y725283D01*
X1796458Y725617D01*
X1796500Y725992D01*
X1796458Y726325D01*
X1796250Y726658D01*
X1796000Y726867D01*
X1795750Y726908D01*
X1795458Y726825D01*
X1795250Y726533D01*
X1795167Y726242D01*
Y725867D01*
G01Y726242D02*
X1795042Y726492D01*
X1794833Y726700D01*
X1794583Y726783D01*
X1794333Y726700D01*
X1794125Y726492D01*
X1794000Y726117D01*
X1794042Y725742D01*
X1794208Y725367D01*
G01X1794417Y728258D02*
X1794167Y728508D01*
X1794042Y728800D01*
X1794000Y729133D01*
X1794083Y729550D01*
X1794292Y729842D01*
X1794542Y729925D01*
X1794792Y729883D01*
X1795000Y729717D01*
X1795417Y728883D01*
X1795708Y728508D01*
X1796125Y728258D01*
X1796500Y728175D01*
Y729925D01*
G01X1795458Y731358D02*
X1795167Y731650D01*
X1795000Y731900D01*
X1794917Y732233D01*
X1795000Y732525D01*
X1795167Y732733D01*
X1795417Y732900D01*
X1795708Y732942D01*
X1795958Y732900D01*
X1796208Y732733D01*
X1796417Y732483D01*
X1796500Y732192D01*
X1796417Y731858D01*
X1796167Y731567D01*
X1795792Y731400D01*
X1795375Y731358D01*
X1794833Y731442D01*
X1794542Y731567D01*
X1794250Y731775D01*
X1794042Y732067D01*
X1794000Y732358D01*
X1794083Y732650D01*
X1794292Y732858D01*
G01X1774275Y775500D02*
Y778000D01*
G01X1776025D02*
Y775500D01*
G01Y776750D02*
X1774275D01*
G01X1777333Y775500D02*
Y778000D01*
X1778167D01*
X1778500Y777875D01*
X1778750Y777708D01*
X1778958Y777458D01*
X1779125Y777167D01*
X1779167Y776750D01*
X1779125Y776333D01*
X1778958Y776042D01*
X1778750Y775792D01*
X1778500Y775625D01*
X1778167Y775500D01*
X1777333D01*
G01X1780433D02*
Y778000D01*
X1781267D01*
X1781600Y777875D01*
X1781850Y777708D01*
X1782058Y777458D01*
X1782225Y777167D01*
X1782267Y776750D01*
X1782225Y776333D01*
X1782058Y776042D01*
X1781850Y775792D01*
X1781600Y775625D01*
X1781267Y775500D01*
X1780433D01*
G01X1783575Y775833D02*
X1783908Y775625D01*
X1784283Y775500D01*
X1784617D01*
X1784950Y775625D01*
X1785200Y775833D01*
X1785325Y776125D01*
X1785242Y776417D01*
X1785033Y776667D01*
X1784658Y776833D01*
X1784158Y776917D01*
X1783867Y777083D01*
X1783742Y777375D01*
X1783825Y777667D01*
X1784033Y777875D01*
X1784325Y778000D01*
X1784617D01*
X1784908Y777917D01*
X1785158Y777708D01*
G01X1786508Y775500D02*
X1787550Y778000D01*
X1788592Y775500D01*
G01X1788217Y776375D02*
X1786883D01*
G01X1789775Y775833D02*
X1790108Y775625D01*
X1790483Y775500D01*
X1790817D01*
X1791150Y775625D01*
X1791400Y775833D01*
X1791525Y776125D01*
X1791442Y776417D01*
X1791233Y776667D01*
X1790858Y776833D01*
X1790358Y776917D01*
X1790067Y777083D01*
X1789942Y777375D01*
X1790025Y777667D01*
X1790233Y777875D01*
X1790525Y778000D01*
X1790817D01*
X1791108Y777917D01*
X1791358Y777708D01*
G01X1792958Y777583D02*
X1793208Y777833D01*
X1793500Y777958D01*
X1793833Y778000D01*
X1794250Y777917D01*
X1794542Y777708D01*
X1794625Y777458D01*
X1794583Y777208D01*
X1794417Y777000D01*
X1793583Y776583D01*
X1793208Y776292D01*
X1792958Y775875D01*
X1792875Y775500D01*
X1794625D01*
G01X1796058Y777583D02*
X1796308Y777833D01*
X1796600Y777958D01*
X1796933Y778000D01*
X1797350Y777917D01*
X1797642Y777708D01*
X1797725Y777458D01*
X1797683Y777208D01*
X1797517Y777000D01*
X1796683Y776583D01*
X1796308Y776292D01*
X1796058Y775875D01*
X1795975Y775500D01*
X1797725D01*
G01X1778837Y936781D02*
X1776337D01*
Y937822D01*
X1776462Y938156D01*
X1776629Y938364D01*
X1776962Y938447D01*
X1777295Y938364D01*
X1777504Y938114D01*
X1777629Y937822D01*
Y936781D01*
G01Y937822D02*
X1778837Y938447D01*
G01X1776754Y939922D02*
X1776504Y940172D01*
X1776379Y940464D01*
X1776337Y940797D01*
X1776420Y941214D01*
X1776629Y941506D01*
X1776879Y941589D01*
X1777129Y941547D01*
X1777337Y941381D01*
X1777754Y940547D01*
X1778045Y940172D01*
X1778462Y939922D01*
X1778837Y939839D01*
Y941589D01*
G01X1777795Y943022D02*
X1777504Y943314D01*
X1777337Y943564D01*
X1777254Y943897D01*
X1777337Y944189D01*
X1777504Y944397D01*
X1777754Y944564D01*
X1778045Y944606D01*
X1778295Y944564D01*
X1778545Y944397D01*
X1778754Y944147D01*
X1778837Y943856D01*
X1778754Y943522D01*
X1778504Y943231D01*
X1778129Y943064D01*
X1777712Y943022D01*
X1777170Y943106D01*
X1776879Y943231D01*
X1776587Y943439D01*
X1776379Y943731D01*
X1776337Y944022D01*
X1776420Y944314D01*
X1776629Y944522D01*
G01X1778545Y946206D02*
X1778754Y946497D01*
X1778837Y946831D01*
X1778754Y947164D01*
X1778504Y947456D01*
X1778129Y947664D01*
X1777754Y947747D01*
X1777295D01*
X1776920Y947664D01*
X1776587Y947456D01*
X1776420Y947206D01*
X1776337Y946914D01*
X1776420Y946581D01*
X1776587Y946331D01*
X1776837Y946164D01*
X1777170Y946081D01*
X1777462Y946164D01*
X1777754Y946372D01*
X1777920Y946622D01*
X1777962Y946914D01*
X1777879Y947247D01*
X1777670Y947497D01*
X1777295Y947747D01*
G01X1774337Y936781D02*
X1771837D01*
Y937822D01*
X1771962Y938156D01*
X1772129Y938364D01*
X1772462Y938447D01*
X1772795Y938364D01*
X1773004Y938114D01*
X1773129Y937822D01*
Y936781D01*
G01Y937822D02*
X1774337Y938447D01*
G01X1772254Y939922D02*
X1772004Y940172D01*
X1771879Y940464D01*
X1771837Y940797D01*
X1771920Y941214D01*
X1772129Y941506D01*
X1772379Y941589D01*
X1772629Y941547D01*
X1772837Y941381D01*
X1773254Y940547D01*
X1773545Y940172D01*
X1773962Y939922D01*
X1774337Y939839D01*
Y941589D01*
G01X1773295Y943022D02*
X1773004Y943314D01*
X1772837Y943564D01*
X1772754Y943897D01*
X1772837Y944189D01*
X1773004Y944397D01*
X1773254Y944564D01*
X1773545Y944606D01*
X1773795Y944564D01*
X1774045Y944397D01*
X1774254Y944147D01*
X1774337Y943856D01*
X1774254Y943522D01*
X1774004Y943231D01*
X1773629Y943064D01*
X1773212Y943022D01*
X1772670Y943106D01*
X1772379Y943231D01*
X1772087Y943439D01*
X1771879Y943731D01*
X1771837Y944022D01*
X1771920Y944314D01*
X1772129Y944522D01*
G01X1774337Y946914D02*
X1774295Y947206D01*
X1774170Y947539D01*
X1773962Y947747D01*
X1773670Y947831D01*
X1773379Y947747D01*
X1773129Y947497D01*
X1773004Y947122D01*
Y946706D01*
X1772920Y946456D01*
X1772712Y946247D01*
X1772420Y946164D01*
X1772129Y946289D01*
X1771920Y946581D01*
X1771837Y946914D01*
X1771920Y947247D01*
X1772129Y947539D01*
X1772420Y947664D01*
X1772712Y947581D01*
X1772920Y947372D01*
X1773004Y947122D01*
Y946706D01*
X1773129Y946331D01*
X1773379Y946081D01*
X1773670Y945997D01*
X1773962Y946081D01*
X1774170Y946289D01*
X1774295Y946622D01*
X1774337Y946914D01*
G01X1800860Y969198D02*
Y971698D01*
X1801901D01*
X1802235Y971573D01*
X1802443Y971406D01*
X1802526Y971073D01*
X1802443Y970740D01*
X1802193Y970531D01*
X1801901Y970406D01*
X1800860D01*
G01X1801901D02*
X1802526Y969198D01*
G01X1803876Y969573D02*
X1804126Y969365D01*
X1804418Y969240D01*
X1804793Y969198D01*
X1805168Y969281D01*
X1805460Y969448D01*
X1805668Y969740D01*
X1805710Y970073D01*
X1805626Y970406D01*
X1805418Y970615D01*
X1805126Y970781D01*
X1804835Y970823D01*
X1804543Y970781D01*
X1804168Y970615D01*
X1804293Y971698D01*
X1805418D01*
G01X1807893D02*
X1807560Y971615D01*
X1807310Y971406D01*
X1807143Y971156D01*
X1807018Y970823D01*
X1806976Y970448D01*
X1807018Y970073D01*
X1807143Y969740D01*
X1807310Y969490D01*
X1807560Y969281D01*
X1807893Y969198D01*
X1808226Y969281D01*
X1808476Y969490D01*
X1808643Y969740D01*
X1808768Y970073D01*
X1808810Y970448D01*
X1808768Y970823D01*
X1808643Y971156D01*
X1808476Y971406D01*
X1808226Y971615D01*
X1807893Y971698D01*
G01X1810993D02*
X1810660Y971615D01*
X1810410Y971406D01*
X1810243Y971156D01*
X1810118Y970823D01*
X1810076Y970448D01*
X1810118Y970073D01*
X1810243Y969740D01*
X1810410Y969490D01*
X1810660Y969281D01*
X1810993Y969198D01*
X1811326Y969281D01*
X1811576Y969490D01*
X1811743Y969740D01*
X1811868Y970073D01*
X1811910Y970448D01*
X1811868Y970823D01*
X1811743Y971156D01*
X1811576Y971406D01*
X1811326Y971615D01*
X1810993Y971698D01*
G01X1808027Y963626D02*
Y967626D01*
X1800627D01*
G01X1787280Y972152D02*
Y974652D01*
X1788321D01*
X1788655Y974527D01*
X1788863Y974360D01*
X1788946Y974027D01*
X1788863Y973694D01*
X1788613Y973485D01*
X1788321Y973360D01*
X1787280D01*
G01X1788321D02*
X1788946Y972152D01*
G01X1791713D02*
Y974652D01*
X1790171Y972860D01*
X1792255D01*
G01X1793605Y972444D02*
X1793896Y972235D01*
X1794230Y972152D01*
X1794563Y972235D01*
X1794855Y972485D01*
X1795063Y972860D01*
X1795146Y973235D01*
Y973694D01*
X1795063Y974069D01*
X1794855Y974402D01*
X1794605Y974569D01*
X1794313Y974652D01*
X1793980Y974569D01*
X1793730Y974402D01*
X1793563Y974152D01*
X1793480Y973819D01*
X1793563Y973527D01*
X1793771Y973235D01*
X1794021Y973069D01*
X1794313Y973027D01*
X1794646Y973110D01*
X1794896Y973319D01*
X1795146Y973694D01*
G01X1796621Y973194D02*
X1796913Y973485D01*
X1797163Y973652D01*
X1797496Y973735D01*
X1797788Y973652D01*
X1797996Y973485D01*
X1798163Y973235D01*
X1798205Y972944D01*
X1798163Y972694D01*
X1797996Y972444D01*
X1797746Y972235D01*
X1797455Y972152D01*
X1797121Y972235D01*
X1796830Y972485D01*
X1796663Y972860D01*
X1796621Y973277D01*
X1796705Y973819D01*
X1796830Y974110D01*
X1797038Y974402D01*
X1797330Y974610D01*
X1797621Y974652D01*
X1797913Y974569D01*
X1798121Y974360D01*
G01X1795838Y966689D02*
Y970689D01*
X1788438D01*
G01X1770729Y964770D02*
Y967270D01*
X1771770D01*
X1772104Y967145D01*
X1772312Y966978D01*
X1772395Y966645D01*
X1772312Y966312D01*
X1772062Y966103D01*
X1771770Y965978D01*
X1770729D01*
G01X1771770D02*
X1772395Y964770D01*
G01X1775162D02*
Y967270D01*
X1773620Y965478D01*
X1775704D01*
G01X1777054Y965062D02*
X1777345Y964853D01*
X1777679Y964770D01*
X1778012Y964853D01*
X1778304Y965103D01*
X1778512Y965478D01*
X1778595Y965853D01*
Y966312D01*
X1778512Y966687D01*
X1778304Y967020D01*
X1778054Y967187D01*
X1777762Y967270D01*
X1777429Y967187D01*
X1777179Y967020D01*
X1777012Y966770D01*
X1776929Y966437D01*
X1777012Y966145D01*
X1777220Y965853D01*
X1777470Y965687D01*
X1777762Y965645D01*
X1778095Y965728D01*
X1778345Y965937D01*
X1778595Y966312D01*
G01X1779945Y965145D02*
X1780195Y964937D01*
X1780487Y964812D01*
X1780862Y964770D01*
X1781237Y964853D01*
X1781529Y965020D01*
X1781737Y965312D01*
X1781779Y965645D01*
X1781695Y965978D01*
X1781487Y966187D01*
X1781195Y966353D01*
X1780904Y966395D01*
X1780612Y966353D01*
X1780237Y966187D01*
X1780362Y967270D01*
X1781487D01*
G01X1787586Y944101D02*
X1787253Y944143D01*
X1786961Y944309D01*
X1786711Y944559D01*
X1786544Y944851D01*
X1786461Y945184D01*
Y945518D01*
X1786544Y945851D01*
X1786711Y946143D01*
X1786961Y946393D01*
X1787253Y946559D01*
X1787586Y946601D01*
X1787919Y946559D01*
X1788211Y946393D01*
X1788461Y946143D01*
X1788628Y945851D01*
X1788711Y945518D01*
Y945184D01*
X1788628Y944851D01*
X1788461Y944559D01*
X1788211Y944309D01*
X1787919Y944143D01*
X1787586Y944101D01*
G01X1787919Y944768D02*
X1788419Y944101D01*
G01X1789894Y946184D02*
X1790144Y946434D01*
X1790436Y946559D01*
X1790769Y946601D01*
X1791186Y946518D01*
X1791478Y946309D01*
X1791561Y946059D01*
X1791519Y945809D01*
X1791353Y945601D01*
X1790519Y945184D01*
X1790144Y944893D01*
X1789894Y944476D01*
X1789811Y944101D01*
X1791561D01*
G01X1793703D02*
X1793786Y944643D01*
X1793911Y945101D01*
X1794078Y945518D01*
X1794286Y945976D01*
X1794619Y946601D01*
X1792953D01*
G01X1797386Y944101D02*
Y946601D01*
X1795844Y944809D01*
X1797928D01*
G01X1798736Y948601D02*
Y962601D01*
G01X1785736Y948601D02*
X1798736D01*
G01X1785736Y962601D02*
Y948601D01*
G01X1798736Y962601D02*
X1785736D01*
G01X1801802Y944360D02*
X1801469Y944402D01*
X1801177Y944568D01*
X1800927Y944818D01*
X1800760Y945110D01*
X1800677Y945443D01*
Y945777D01*
X1800760Y946110D01*
X1800927Y946402D01*
X1801177Y946652D01*
X1801469Y946818D01*
X1801802Y946860D01*
X1802135Y946818D01*
X1802427Y946652D01*
X1802677Y946402D01*
X1802844Y946110D01*
X1802927Y945777D01*
Y945443D01*
X1802844Y945110D01*
X1802677Y944818D01*
X1802427Y944568D01*
X1802135Y944402D01*
X1801802Y944360D01*
G01X1802135Y945027D02*
X1802635Y944360D01*
G01X1804110Y946443D02*
X1804360Y946693D01*
X1804652Y946818D01*
X1804985Y946860D01*
X1805402Y946777D01*
X1805694Y946568D01*
X1805777Y946318D01*
X1805735Y946068D01*
X1805569Y945860D01*
X1804735Y945443D01*
X1804360Y945152D01*
X1804110Y944735D01*
X1804027Y944360D01*
X1805777D01*
G01X1807085Y944860D02*
X1807335Y944568D01*
X1807669Y944402D01*
X1808044Y944360D01*
X1808377Y944402D01*
X1808710Y944610D01*
X1808919Y944860D01*
X1808960Y945110D01*
X1808877Y945402D01*
X1808585Y945610D01*
X1808294Y945693D01*
X1807919D01*
G01X1808294D02*
X1808544Y945818D01*
X1808752Y946027D01*
X1808835Y946277D01*
X1808752Y946527D01*
X1808544Y946735D01*
X1808169Y946860D01*
X1807794Y946818D01*
X1807419Y946652D01*
G01X1811102Y944360D02*
X1811394Y944402D01*
X1811727Y944527D01*
X1811935Y944735D01*
X1812019Y945027D01*
X1811935Y945318D01*
X1811685Y945568D01*
X1811310Y945693D01*
X1810894D01*
X1810644Y945777D01*
X1810435Y945985D01*
X1810352Y946277D01*
X1810477Y946568D01*
X1810769Y946777D01*
X1811102Y946860D01*
X1811435Y946777D01*
X1811727Y946568D01*
X1811852Y946277D01*
X1811769Y945985D01*
X1811560Y945777D01*
X1811310Y945693D01*
X1810894D01*
X1810519Y945568D01*
X1810269Y945318D01*
X1810185Y945027D01*
X1810269Y944735D01*
X1810477Y944527D01*
X1810810Y944402D01*
X1811102Y944360D01*
G01X1812952Y948860D02*
Y962860D01*
G01X1799952Y948860D02*
X1812952D01*
G01X1799952Y962860D02*
Y948860D01*
G01X1812952Y962860D02*
X1799952D01*
G01X1770265Y948984D02*
Y962984D01*
G01X1770294Y974575D02*
X1765094D01*
G01X1770294D02*
Y981575D01*
G01X1788795Y979527D02*
X1788545Y979652D01*
X1788253Y979735D01*
X1787920D01*
X1787545Y979610D01*
X1787253Y979402D01*
X1787045Y979152D01*
X1786878Y978735D01*
X1786836Y978360D01*
X1786920Y977985D01*
X1787045Y977735D01*
X1787295Y977485D01*
X1787586Y977318D01*
X1787878Y977235D01*
X1788170D01*
X1788461Y977318D01*
X1788711Y977443D01*
X1788920Y977610D01*
G01X1790186Y978277D02*
X1790478Y978568D01*
X1790728Y978735D01*
X1791061Y978818D01*
X1791353Y978735D01*
X1791561Y978568D01*
X1791728Y978318D01*
X1791770Y978027D01*
X1791728Y977777D01*
X1791561Y977527D01*
X1791311Y977318D01*
X1791020Y977235D01*
X1790686Y977318D01*
X1790395Y977568D01*
X1790228Y977943D01*
X1790186Y978360D01*
X1790270Y978902D01*
X1790395Y979193D01*
X1790603Y979485D01*
X1790895Y979693D01*
X1791186Y979735D01*
X1791478Y979652D01*
X1791686Y979443D01*
G01X1794578Y977235D02*
Y979735D01*
X1793036Y977943D01*
X1795120D01*
G01X1797178Y979735D02*
X1796845Y979652D01*
X1796595Y979443D01*
X1796428Y979193D01*
X1796303Y978860D01*
X1796261Y978485D01*
X1796303Y978110D01*
X1796428Y977777D01*
X1796595Y977527D01*
X1796845Y977318D01*
X1797178Y977235D01*
X1797511Y977318D01*
X1797761Y977527D01*
X1797928Y977777D01*
X1798053Y978110D01*
X1798095Y978485D01*
X1798053Y978860D01*
X1797928Y979193D01*
X1797761Y979443D01*
X1797511Y979652D01*
X1797178Y979735D01*
G01X1788823Y984554D02*
X1788573Y984679D01*
X1788281Y984762D01*
X1787948D01*
X1787573Y984637D01*
X1787281Y984429D01*
X1787073Y984179D01*
X1786906Y983762D01*
X1786864Y983387D01*
X1786948Y983012D01*
X1787073Y982762D01*
X1787323Y982512D01*
X1787614Y982345D01*
X1787906Y982262D01*
X1788198D01*
X1788489Y982345D01*
X1788739Y982470D01*
X1788948Y982637D01*
G01X1790214Y983304D02*
X1790506Y983595D01*
X1790756Y983762D01*
X1791089Y983845D01*
X1791381Y983762D01*
X1791589Y983595D01*
X1791756Y983345D01*
X1791798Y983054D01*
X1791756Y982804D01*
X1791589Y982554D01*
X1791339Y982345D01*
X1791048Y982262D01*
X1790714Y982345D01*
X1790423Y982595D01*
X1790256Y982970D01*
X1790214Y983387D01*
X1790298Y983929D01*
X1790423Y984220D01*
X1790631Y984512D01*
X1790923Y984720D01*
X1791214Y984762D01*
X1791506Y984679D01*
X1791714Y984470D01*
G01X1793189Y982762D02*
X1793439Y982470D01*
X1793773Y982304D01*
X1794148Y982262D01*
X1794481Y982304D01*
X1794814Y982512D01*
X1795023Y982762D01*
X1795064Y983012D01*
X1794981Y983304D01*
X1794689Y983512D01*
X1794398Y983595D01*
X1794023D01*
G01X1794398D02*
X1794648Y983720D01*
X1794856Y983929D01*
X1794939Y984179D01*
X1794856Y984429D01*
X1794648Y984637D01*
X1794273Y984762D01*
X1793898Y984720D01*
X1793523Y984554D01*
G01X1797206Y982262D02*
X1797498Y982304D01*
X1797831Y982429D01*
X1798039Y982637D01*
X1798123Y982929D01*
X1798039Y983220D01*
X1797789Y983470D01*
X1797414Y983595D01*
X1796998D01*
X1796748Y983679D01*
X1796539Y983887D01*
X1796456Y984179D01*
X1796581Y984470D01*
X1796873Y984679D01*
X1797206Y984762D01*
X1797539Y984679D01*
X1797831Y984470D01*
X1797956Y984179D01*
X1797873Y983887D01*
X1797664Y983679D01*
X1797414Y983595D01*
X1796998D01*
X1796623Y983470D01*
X1796373Y983220D01*
X1796289Y982929D01*
X1796373Y982637D01*
X1796581Y982429D01*
X1796914Y982304D01*
X1797206Y982262D01*
G01X1779000Y1024967D02*
X1776500D01*
Y1026008D01*
X1776625Y1026342D01*
X1776792Y1026550D01*
X1777125Y1026633D01*
X1777458Y1026550D01*
X1777667Y1026300D01*
X1777792Y1026008D01*
Y1024967D01*
G01Y1026008D02*
X1779000Y1026633D01*
G01Y1028900D02*
X1776500D01*
X1777000Y1028400D01*
G01X1779000D02*
Y1029400D01*
G01X1776917Y1031208D02*
X1776667Y1031458D01*
X1776542Y1031750D01*
X1776500Y1032083D01*
X1776583Y1032500D01*
X1776792Y1032792D01*
X1777042Y1032875D01*
X1777292Y1032833D01*
X1777500Y1032667D01*
X1777917Y1031833D01*
X1778208Y1031458D01*
X1778625Y1031208D01*
X1779000Y1031125D01*
Y1032875D01*
G01Y1035600D02*
X1776500D01*
X1778292Y1034058D01*
Y1036142D01*
G01X1778500Y1037283D02*
X1778792Y1037533D01*
X1778958Y1037867D01*
X1779000Y1038242D01*
X1778958Y1038575D01*
X1778750Y1038908D01*
X1778500Y1039117D01*
X1778250Y1039158D01*
X1777958Y1039075D01*
X1777750Y1038783D01*
X1777667Y1038492D01*
Y1038117D01*
G01Y1038492D02*
X1777542Y1038742D01*
X1777333Y1038950D01*
X1777083Y1039033D01*
X1776833Y1038950D01*
X1776625Y1038742D01*
X1776500Y1038367D01*
X1776542Y1037992D01*
X1776708Y1037617D01*
G01X1776863Y1023425D02*
X1772863D01*
Y1016025D01*
G01X1772563Y1011725D02*
Y1015725D01*
X1765163D01*
G01X1780967Y1022000D02*
Y1024500D01*
X1782008D01*
X1782342Y1024375D01*
X1782550Y1024208D01*
X1782633Y1023875D01*
X1782550Y1023542D01*
X1782300Y1023333D01*
X1782008Y1023208D01*
X1780967D01*
G01X1782008D02*
X1782633Y1022000D01*
G01X1784900D02*
Y1024500D01*
X1784400Y1024000D01*
G01Y1022000D02*
X1785400D01*
G01X1787208Y1024083D02*
X1787458Y1024333D01*
X1787750Y1024458D01*
X1788083Y1024500D01*
X1788500Y1024417D01*
X1788792Y1024208D01*
X1788875Y1023958D01*
X1788833Y1023708D01*
X1788667Y1023500D01*
X1787833Y1023083D01*
X1787458Y1022792D01*
X1787208Y1022375D01*
X1787125Y1022000D01*
X1788875D01*
G01X1791600D02*
Y1024500D01*
X1790058Y1022708D01*
X1792142D01*
G01X1794200Y1022000D02*
X1794492Y1022042D01*
X1794825Y1022167D01*
X1795033Y1022375D01*
X1795117Y1022667D01*
X1795033Y1022958D01*
X1794783Y1023208D01*
X1794408Y1023333D01*
X1793992D01*
X1793742Y1023417D01*
X1793533Y1023625D01*
X1793450Y1023917D01*
X1793575Y1024208D01*
X1793867Y1024417D01*
X1794200Y1024500D01*
X1794533Y1024417D01*
X1794825Y1024208D01*
X1794950Y1023917D01*
X1794867Y1023625D01*
X1794658Y1023417D01*
X1794408Y1023333D01*
X1793992D01*
X1793617Y1023208D01*
X1793367Y1022958D01*
X1793283Y1022667D01*
X1793367Y1022375D01*
X1793575Y1022167D01*
X1793908Y1022042D01*
X1794200Y1022000D01*
G01X1784322Y1007250D02*
Y1011250D01*
X1776922D01*
G01X1780967Y1026000D02*
Y1028500D01*
X1782008D01*
X1782342Y1028375D01*
X1782550Y1028208D01*
X1782633Y1027875D01*
X1782550Y1027542D01*
X1782300Y1027333D01*
X1782008Y1027208D01*
X1780967D01*
G01X1782008D02*
X1782633Y1026000D01*
G01X1784900D02*
Y1028500D01*
X1784400Y1028000D01*
G01Y1026000D02*
X1785400D01*
G01X1787208Y1028083D02*
X1787458Y1028333D01*
X1787750Y1028458D01*
X1788083Y1028500D01*
X1788500Y1028417D01*
X1788792Y1028208D01*
X1788875Y1027958D01*
X1788833Y1027708D01*
X1788667Y1027500D01*
X1787833Y1027083D01*
X1787458Y1026792D01*
X1787208Y1026375D01*
X1787125Y1026000D01*
X1788875D01*
G01X1791600D02*
Y1028500D01*
X1790058Y1026708D01*
X1792142D01*
G01X1794700Y1026000D02*
Y1028500D01*
X1793158Y1026708D01*
X1795242D01*
G01X1784363Y1015625D02*
Y1019625D01*
X1776963D01*
G01X1794300Y1018166D02*
Y1015666D01*
G01X1793342Y1018166D02*
X1795258D01*
G01X1796567Y1015666D02*
Y1018166D01*
X1797567D01*
X1797900Y1018041D01*
X1798150Y1017749D01*
X1798233Y1017416D01*
X1798150Y1017083D01*
X1797942Y1016833D01*
X1797567Y1016708D01*
X1796567D01*
G01X1799708Y1017749D02*
X1799958Y1017999D01*
X1800250Y1018124D01*
X1800583Y1018166D01*
X1801000Y1018083D01*
X1801292Y1017874D01*
X1801375Y1017624D01*
X1801333Y1017374D01*
X1801167Y1017166D01*
X1800333Y1016749D01*
X1799958Y1016458D01*
X1799708Y1016041D01*
X1799625Y1015666D01*
X1801375D01*
G01X1802683Y1016041D02*
X1802933Y1015833D01*
X1803225Y1015708D01*
X1803600Y1015666D01*
X1803975Y1015749D01*
X1804267Y1015916D01*
X1804475Y1016208D01*
X1804517Y1016541D01*
X1804433Y1016874D01*
X1804225Y1017083D01*
X1803933Y1017249D01*
X1803642Y1017291D01*
X1803350Y1017249D01*
X1802975Y1017083D01*
X1803100Y1018166D01*
X1804225D01*
G01X1806700Y1015666D02*
X1806992Y1015708D01*
X1807325Y1015833D01*
X1807533Y1016041D01*
X1807617Y1016333D01*
X1807533Y1016624D01*
X1807283Y1016874D01*
X1806908Y1016999D01*
X1806492D01*
X1806242Y1017083D01*
X1806033Y1017291D01*
X1805950Y1017583D01*
X1806075Y1017874D01*
X1806367Y1018083D01*
X1806700Y1018166D01*
X1807033Y1018083D01*
X1807325Y1017874D01*
X1807450Y1017583D01*
X1807367Y1017291D01*
X1807158Y1017083D01*
X1806908Y1016999D01*
X1806492D01*
X1806117Y1016874D01*
X1805867Y1016624D01*
X1805783Y1016333D01*
X1805867Y1016041D01*
X1806075Y1015833D01*
X1806408Y1015708D01*
X1806700Y1015666D01*
G01X1790834Y988467D02*
X1788334D01*
Y989508D01*
X1788459Y989842D01*
X1788626Y990050D01*
X1788959Y990133D01*
X1789292Y990050D01*
X1789501Y989800D01*
X1789626Y989508D01*
Y988467D01*
G01Y989508D02*
X1790834Y990133D01*
G01Y992400D02*
X1788334D01*
X1788834Y991900D01*
G01X1790834D02*
Y992900D01*
G01X1788751Y994708D02*
X1788501Y994958D01*
X1788376Y995250D01*
X1788334Y995583D01*
X1788417Y996000D01*
X1788626Y996292D01*
X1788876Y996375D01*
X1789126Y996333D01*
X1789334Y996167D01*
X1789751Y995333D01*
X1790042Y994958D01*
X1790459Y994708D01*
X1790834Y994625D01*
Y996375D01*
G01Y999100D02*
X1788334D01*
X1790126Y997558D01*
Y999642D01*
G01X1790834Y1001617D02*
X1790292Y1001700D01*
X1789834Y1001825D01*
X1789417Y1001992D01*
X1788959Y1002200D01*
X1788334Y1002533D01*
Y1000867D01*
G01X1793367Y1058673D02*
Y1061173D01*
X1794408D01*
X1794742Y1061048D01*
X1794950Y1060881D01*
X1795033Y1060548D01*
X1794950Y1060215D01*
X1794700Y1060006D01*
X1794408Y1059881D01*
X1793367D01*
G01X1794408D02*
X1795033Y1058673D01*
G01X1796383Y1059173D02*
X1796633Y1058881D01*
X1796967Y1058715D01*
X1797342Y1058673D01*
X1797675Y1058715D01*
X1798008Y1058923D01*
X1798217Y1059173D01*
X1798258Y1059423D01*
X1798175Y1059715D01*
X1797883Y1059923D01*
X1797592Y1060006D01*
X1797217D01*
G01X1797592D02*
X1797842Y1060131D01*
X1798050Y1060340D01*
X1798133Y1060590D01*
X1798050Y1060840D01*
X1797842Y1061048D01*
X1797467Y1061173D01*
X1797092Y1061131D01*
X1796717Y1060965D01*
G01X1799608Y1059715D02*
X1799900Y1060006D01*
X1800150Y1060173D01*
X1800483Y1060256D01*
X1800775Y1060173D01*
X1800983Y1060006D01*
X1801150Y1059756D01*
X1801192Y1059465D01*
X1801150Y1059215D01*
X1800983Y1058965D01*
X1800733Y1058756D01*
X1800442Y1058673D01*
X1800108Y1058756D01*
X1799817Y1059006D01*
X1799650Y1059381D01*
X1799608Y1059798D01*
X1799692Y1060340D01*
X1799817Y1060631D01*
X1800025Y1060923D01*
X1800317Y1061131D01*
X1800608Y1061173D01*
X1800900Y1061090D01*
X1801108Y1060881D01*
G01X1803417Y1058673D02*
X1803500Y1059215D01*
X1803625Y1059673D01*
X1803792Y1060090D01*
X1804000Y1060548D01*
X1804333Y1061173D01*
X1802667D01*
G01X1800184Y1041490D02*
X1797684D01*
Y1042531D01*
X1797809Y1042865D01*
X1797976Y1043073D01*
X1798309Y1043156D01*
X1798642Y1043073D01*
X1798851Y1042823D01*
X1798976Y1042531D01*
Y1041490D01*
G01Y1042531D02*
X1800184Y1043156D01*
G01X1799684Y1044506D02*
X1799976Y1044756D01*
X1800142Y1045090D01*
X1800184Y1045465D01*
X1800142Y1045798D01*
X1799934Y1046131D01*
X1799684Y1046340D01*
X1799434Y1046381D01*
X1799142Y1046298D01*
X1798934Y1046006D01*
X1798851Y1045715D01*
Y1045340D01*
G01Y1045715D02*
X1798726Y1045965D01*
X1798517Y1046173D01*
X1798267Y1046256D01*
X1798017Y1046173D01*
X1797809Y1045965D01*
X1797684Y1045590D01*
X1797726Y1045215D01*
X1797892Y1044840D01*
G01X1799142Y1047731D02*
X1798851Y1048023D01*
X1798684Y1048273D01*
X1798601Y1048606D01*
X1798684Y1048898D01*
X1798851Y1049106D01*
X1799101Y1049273D01*
X1799392Y1049315D01*
X1799642Y1049273D01*
X1799892Y1049106D01*
X1800101Y1048856D01*
X1800184Y1048565D01*
X1800101Y1048231D01*
X1799851Y1047940D01*
X1799476Y1047773D01*
X1799059Y1047731D01*
X1798517Y1047815D01*
X1798226Y1047940D01*
X1797934Y1048148D01*
X1797726Y1048440D01*
X1797684Y1048731D01*
X1797767Y1049023D01*
X1797976Y1049231D01*
G01X1800184Y1051623D02*
X1800142Y1051915D01*
X1800017Y1052248D01*
X1799809Y1052456D01*
X1799517Y1052540D01*
X1799226Y1052456D01*
X1798976Y1052206D01*
X1798851Y1051831D01*
Y1051415D01*
X1798767Y1051165D01*
X1798559Y1050956D01*
X1798267Y1050873D01*
X1797976Y1050998D01*
X1797767Y1051290D01*
X1797684Y1051623D01*
X1797767Y1051956D01*
X1797976Y1052248D01*
X1798267Y1052373D01*
X1798559Y1052290D01*
X1798767Y1052081D01*
X1798851Y1051831D01*
Y1051415D01*
X1798976Y1051040D01*
X1799226Y1050790D01*
X1799517Y1050706D01*
X1799809Y1050790D01*
X1800017Y1050998D01*
X1800142Y1051331D01*
X1800184Y1051623D01*
G01X1803250Y1069273D02*
X1807250D01*
Y1076673D01*
G01X1804913Y1041484D02*
X1802413D01*
Y1042525D01*
X1802538Y1042859D01*
X1802705Y1043067D01*
X1803038Y1043150D01*
X1803371Y1043067D01*
X1803580Y1042817D01*
X1803705Y1042525D01*
Y1041484D01*
G01Y1042525D02*
X1804913Y1043150D01*
G01X1804413Y1044500D02*
X1804705Y1044750D01*
X1804871Y1045084D01*
X1804913Y1045459D01*
X1804871Y1045792D01*
X1804663Y1046125D01*
X1804413Y1046334D01*
X1804163Y1046375D01*
X1803871Y1046292D01*
X1803663Y1046000D01*
X1803580Y1045709D01*
Y1045334D01*
G01Y1045709D02*
X1803455Y1045959D01*
X1803246Y1046167D01*
X1802996Y1046250D01*
X1802746Y1046167D01*
X1802538Y1045959D01*
X1802413Y1045584D01*
X1802455Y1045209D01*
X1802621Y1044834D01*
G01X1804913Y1048434D02*
X1804371Y1048517D01*
X1803913Y1048642D01*
X1803496Y1048809D01*
X1803038Y1049017D01*
X1802413Y1049350D01*
Y1047684D01*
G01X1802830Y1050825D02*
X1802580Y1051075D01*
X1802455Y1051367D01*
X1802413Y1051700D01*
X1802496Y1052117D01*
X1802705Y1052409D01*
X1802955Y1052492D01*
X1803205Y1052450D01*
X1803413Y1052284D01*
X1803830Y1051450D01*
X1804121Y1051075D01*
X1804538Y1050825D01*
X1804913Y1050742D01*
Y1052492D01*
G01X1796250Y1041490D02*
X1793750D01*
Y1042531D01*
X1793875Y1042865D01*
X1794042Y1043073D01*
X1794375Y1043156D01*
X1794708Y1043073D01*
X1794917Y1042823D01*
X1795042Y1042531D01*
Y1041490D01*
G01Y1042531D02*
X1796250Y1043156D01*
G01X1795750Y1044506D02*
X1796042Y1044756D01*
X1796208Y1045090D01*
X1796250Y1045465D01*
X1796208Y1045798D01*
X1796000Y1046131D01*
X1795750Y1046340D01*
X1795500Y1046381D01*
X1795208Y1046298D01*
X1795000Y1046006D01*
X1794917Y1045715D01*
Y1045340D01*
G01Y1045715D02*
X1794792Y1045965D01*
X1794583Y1046173D01*
X1794333Y1046256D01*
X1794083Y1046173D01*
X1793875Y1045965D01*
X1793750Y1045590D01*
X1793792Y1045215D01*
X1793958Y1044840D01*
G01X1796250Y1048440D02*
X1795708Y1048523D01*
X1795250Y1048648D01*
X1794833Y1048815D01*
X1794375Y1049023D01*
X1793750Y1049356D01*
Y1047690D01*
G01X1795750Y1050706D02*
X1796042Y1050956D01*
X1796208Y1051290D01*
X1796250Y1051665D01*
X1796208Y1051998D01*
X1796000Y1052331D01*
X1795750Y1052540D01*
X1795500Y1052581D01*
X1795208Y1052498D01*
X1795000Y1052206D01*
X1794917Y1051915D01*
Y1051540D01*
G01Y1051915D02*
X1794792Y1052165D01*
X1794583Y1052373D01*
X1794333Y1052456D01*
X1794083Y1052373D01*
X1793875Y1052165D01*
X1793750Y1051790D01*
X1793792Y1051415D01*
X1793958Y1051040D01*
G01X1802750Y1076673D02*
X1798750D01*
Y1069273D01*
G01X1815350Y1045090D02*
X1812850D01*
Y1046131D01*
X1812975Y1046465D01*
X1813142Y1046673D01*
X1813475Y1046756D01*
X1813808Y1046673D01*
X1814017Y1046423D01*
X1814142Y1046131D01*
Y1045090D01*
G01Y1046131D02*
X1815350Y1046756D01*
G01X1814850Y1048106D02*
X1815142Y1048356D01*
X1815308Y1048690D01*
X1815350Y1049065D01*
X1815308Y1049398D01*
X1815100Y1049731D01*
X1814850Y1049940D01*
X1814600Y1049981D01*
X1814308Y1049898D01*
X1814100Y1049606D01*
X1814017Y1049315D01*
Y1048940D01*
G01Y1049315D02*
X1813892Y1049565D01*
X1813683Y1049773D01*
X1813433Y1049856D01*
X1813183Y1049773D01*
X1812975Y1049565D01*
X1812850Y1049190D01*
X1812892Y1048815D01*
X1813058Y1048440D01*
G01X1815350Y1052040D02*
X1814808Y1052123D01*
X1814350Y1052248D01*
X1813933Y1052415D01*
X1813475Y1052623D01*
X1812850Y1052956D01*
Y1051290D01*
G01X1815350Y1055723D02*
X1812850D01*
X1814642Y1054181D01*
Y1056265D01*
G01X1808017Y1062500D02*
Y1065000D01*
X1809058D01*
X1809392Y1064875D01*
X1809600Y1064708D01*
X1809683Y1064375D01*
X1809600Y1064042D01*
X1809350Y1063833D01*
X1809058Y1063708D01*
X1808017D01*
G01X1809058D02*
X1809683Y1062500D01*
G01X1811033Y1063000D02*
X1811283Y1062708D01*
X1811617Y1062542D01*
X1811992Y1062500D01*
X1812325Y1062542D01*
X1812658Y1062750D01*
X1812867Y1063000D01*
X1812908Y1063250D01*
X1812825Y1063542D01*
X1812533Y1063750D01*
X1812242Y1063833D01*
X1811867D01*
G01X1812242D02*
X1812492Y1063958D01*
X1812700Y1064167D01*
X1812783Y1064417D01*
X1812700Y1064667D01*
X1812492Y1064875D01*
X1812117Y1065000D01*
X1811742Y1064958D01*
X1811367Y1064792D01*
G01X1814967Y1062500D02*
X1815050Y1063042D01*
X1815175Y1063500D01*
X1815342Y1063917D01*
X1815550Y1064375D01*
X1815883Y1065000D01*
X1814217D01*
G01X1817358Y1063542D02*
X1817650Y1063833D01*
X1817900Y1064000D01*
X1818233Y1064083D01*
X1818525Y1064000D01*
X1818733Y1063833D01*
X1818900Y1063583D01*
X1818942Y1063292D01*
X1818900Y1063042D01*
X1818733Y1062792D01*
X1818483Y1062583D01*
X1818192Y1062500D01*
X1817858Y1062583D01*
X1817567Y1062833D01*
X1817400Y1063208D01*
X1817358Y1063625D01*
X1817442Y1064167D01*
X1817567Y1064458D01*
X1817775Y1064750D01*
X1818067Y1064958D01*
X1818358Y1065000D01*
X1818650Y1064917D01*
X1818858Y1064708D01*
G01X1810650Y1045090D02*
X1808150D01*
Y1046131D01*
X1808275Y1046465D01*
X1808442Y1046673D01*
X1808775Y1046756D01*
X1809108Y1046673D01*
X1809317Y1046423D01*
X1809442Y1046131D01*
Y1045090D01*
G01Y1046131D02*
X1810650Y1046756D01*
G01X1810150Y1048106D02*
X1810442Y1048356D01*
X1810608Y1048690D01*
X1810650Y1049065D01*
X1810608Y1049398D01*
X1810400Y1049731D01*
X1810150Y1049940D01*
X1809900Y1049981D01*
X1809608Y1049898D01*
X1809400Y1049606D01*
X1809317Y1049315D01*
Y1048940D01*
G01Y1049315D02*
X1809192Y1049565D01*
X1808983Y1049773D01*
X1808733Y1049856D01*
X1808483Y1049773D01*
X1808275Y1049565D01*
X1808150Y1049190D01*
X1808192Y1048815D01*
X1808358Y1048440D01*
G01X1810650Y1052040D02*
X1810108Y1052123D01*
X1809650Y1052248D01*
X1809233Y1052415D01*
X1808775Y1052623D01*
X1808150Y1052956D01*
Y1051290D01*
G01X1810650Y1055140D02*
X1810108Y1055223D01*
X1809650Y1055348D01*
X1809233Y1055515D01*
X1808775Y1055723D01*
X1808150Y1056056D01*
Y1054390D01*
G01X1795750Y1054673D02*
X1795417Y1054715D01*
X1795125Y1054881D01*
X1794875Y1055131D01*
X1794708Y1055423D01*
X1794625Y1055756D01*
Y1056090D01*
X1794708Y1056423D01*
X1794875Y1056715D01*
X1795125Y1056965D01*
X1795417Y1057131D01*
X1795750Y1057173D01*
X1796083Y1057131D01*
X1796375Y1056965D01*
X1796625Y1056715D01*
X1796792Y1056423D01*
X1796875Y1056090D01*
Y1055756D01*
X1796792Y1055423D01*
X1796625Y1055131D01*
X1796375Y1054881D01*
X1796083Y1054715D01*
X1795750Y1054673D01*
G01X1796083Y1055340D02*
X1796583Y1054673D01*
G01X1798058Y1055715D02*
X1798350Y1056006D01*
X1798600Y1056173D01*
X1798933Y1056256D01*
X1799225Y1056173D01*
X1799433Y1056006D01*
X1799600Y1055756D01*
X1799642Y1055465D01*
X1799600Y1055215D01*
X1799433Y1054965D01*
X1799183Y1054756D01*
X1798892Y1054673D01*
X1798558Y1054756D01*
X1798267Y1055006D01*
X1798100Y1055381D01*
X1798058Y1055798D01*
X1798142Y1056340D01*
X1798267Y1056631D01*
X1798475Y1056923D01*
X1798767Y1057131D01*
X1799058Y1057173D01*
X1799350Y1057090D01*
X1799558Y1056881D01*
G01X1801950Y1054673D02*
Y1057173D01*
X1801450Y1056673D01*
G01Y1054673D02*
X1802450D01*
G01X1797650Y1089373D02*
Y1077973D01*
G01X1811050D02*
Y1089373D01*
G01X1797650Y1077973D02*
X1811050D01*
G01X1808333Y1058173D02*
Y1060673D01*
X1809167D01*
X1809500Y1060548D01*
X1809750Y1060381D01*
X1809958Y1060131D01*
X1810125Y1059840D01*
X1810167Y1059423D01*
X1810125Y1059006D01*
X1809958Y1058715D01*
X1809750Y1058465D01*
X1809500Y1058298D01*
X1809167Y1058173D01*
X1808333D01*
G01X1812350D02*
Y1060673D01*
X1811850Y1060173D01*
G01Y1058173D02*
X1812850D01*
G01X1815450Y1060673D02*
X1815117Y1060590D01*
X1814867Y1060381D01*
X1814700Y1060131D01*
X1814575Y1059798D01*
X1814533Y1059423D01*
X1814575Y1059048D01*
X1814700Y1058715D01*
X1814867Y1058465D01*
X1815117Y1058256D01*
X1815450Y1058173D01*
X1815783Y1058256D01*
X1816033Y1058465D01*
X1816200Y1058715D01*
X1816325Y1059048D01*
X1816367Y1059423D01*
X1816325Y1059798D01*
X1816200Y1060131D01*
X1816033Y1060381D01*
X1815783Y1060590D01*
X1815450Y1060673D01*
G01X1795117Y1065065D02*
X1794867Y1065190D01*
X1794575Y1065273D01*
X1794242D01*
X1793867Y1065148D01*
X1793575Y1064940D01*
X1793367Y1064690D01*
X1793200Y1064273D01*
X1793158Y1063898D01*
X1793242Y1063523D01*
X1793367Y1063273D01*
X1793617Y1063023D01*
X1793908Y1062856D01*
X1794200Y1062773D01*
X1794492D01*
X1794783Y1062856D01*
X1795033Y1062981D01*
X1795242Y1063148D01*
G01X1797300Y1062773D02*
Y1065273D01*
X1796800Y1064773D01*
G01Y1062773D02*
X1797800D01*
G01X1800317D02*
X1800400Y1063315D01*
X1800525Y1063773D01*
X1800692Y1064190D01*
X1800900Y1064648D01*
X1801233Y1065273D01*
X1799567D01*
G01X1803500Y1062773D02*
X1803792Y1062815D01*
X1804125Y1062940D01*
X1804333Y1063148D01*
X1804417Y1063440D01*
X1804333Y1063731D01*
X1804083Y1063981D01*
X1803708Y1064106D01*
X1803292D01*
X1803042Y1064190D01*
X1802833Y1064398D01*
X1802750Y1064690D01*
X1802875Y1064981D01*
X1803167Y1065190D01*
X1803500Y1065273D01*
X1803833Y1065190D01*
X1804125Y1064981D01*
X1804250Y1064690D01*
X1804167Y1064398D01*
X1803958Y1064190D01*
X1803708Y1064106D01*
X1803292D01*
X1802917Y1063981D01*
X1802667Y1063731D01*
X1802583Y1063440D01*
X1802667Y1063148D01*
X1802875Y1062940D01*
X1803208Y1062815D01*
X1803500Y1062773D01*
G01X1810550Y1094673D02*
Y1098673D01*
X1803150D01*
G01X1813117Y1125300D02*
Y1127800D01*
X1814158D01*
X1814492Y1127675D01*
X1814700Y1127508D01*
X1814783Y1127175D01*
X1814700Y1126842D01*
X1814450Y1126633D01*
X1814158Y1126508D01*
X1813117D01*
G01X1814158D02*
X1814783Y1125300D01*
G01X1816133Y1125800D02*
X1816383Y1125508D01*
X1816717Y1125342D01*
X1817092Y1125300D01*
X1817425Y1125342D01*
X1817758Y1125550D01*
X1817967Y1125800D01*
X1818008Y1126050D01*
X1817925Y1126342D01*
X1817633Y1126550D01*
X1817342Y1126633D01*
X1816967D01*
G01X1817342D02*
X1817592Y1126758D01*
X1817800Y1126967D01*
X1817883Y1127217D01*
X1817800Y1127467D01*
X1817592Y1127675D01*
X1817217Y1127800D01*
X1816842Y1127758D01*
X1816467Y1127592D01*
G01X1820067Y1125300D02*
X1820150Y1125842D01*
X1820275Y1126300D01*
X1820442Y1126717D01*
X1820650Y1127175D01*
X1820983Y1127800D01*
X1819317D01*
G01X1822333Y1125675D02*
X1822583Y1125467D01*
X1822875Y1125342D01*
X1823250Y1125300D01*
X1823625Y1125383D01*
X1823917Y1125550D01*
X1824125Y1125842D01*
X1824167Y1126175D01*
X1824083Y1126508D01*
X1823875Y1126717D01*
X1823583Y1126883D01*
X1823292Y1126925D01*
X1823000Y1126883D01*
X1822625Y1126717D01*
X1822750Y1127800D01*
X1823875D01*
G01X1811050Y1089373D02*
X1797650D01*
G01X1797500Y1110400D02*
X1797458Y1110067D01*
X1797292Y1109775D01*
X1797042Y1109525D01*
X1796750Y1109358D01*
X1796417Y1109275D01*
X1796083D01*
X1795750Y1109358D01*
X1795458Y1109525D01*
X1795208Y1109775D01*
X1795042Y1110067D01*
X1795000Y1110400D01*
X1795042Y1110733D01*
X1795208Y1111025D01*
X1795458Y1111275D01*
X1795750Y1111442D01*
X1796083Y1111525D01*
X1796417D01*
X1796750Y1111442D01*
X1797042Y1111275D01*
X1797292Y1111025D01*
X1797458Y1110733D01*
X1797500Y1110400D01*
G01X1796833Y1110733D02*
X1797500Y1111233D01*
G01X1796458Y1112708D02*
X1796167Y1113000D01*
X1796000Y1113250D01*
X1795917Y1113583D01*
X1796000Y1113875D01*
X1796167Y1114083D01*
X1796417Y1114250D01*
X1796708Y1114292D01*
X1796958Y1114250D01*
X1797208Y1114083D01*
X1797417Y1113833D01*
X1797500Y1113542D01*
X1797417Y1113208D01*
X1797167Y1112917D01*
X1796792Y1112750D01*
X1796375Y1112708D01*
X1795833Y1112792D01*
X1795542Y1112917D01*
X1795250Y1113125D01*
X1795042Y1113417D01*
X1795000Y1113708D01*
X1795083Y1114000D01*
X1795292Y1114208D01*
G01X1795000Y1116600D02*
X1795083Y1116267D01*
X1795292Y1116017D01*
X1795542Y1115850D01*
X1795875Y1115725D01*
X1796250Y1115683D01*
X1796625Y1115725D01*
X1796958Y1115850D01*
X1797208Y1116017D01*
X1797417Y1116267D01*
X1797500Y1116600D01*
X1797417Y1116933D01*
X1797208Y1117183D01*
X1796958Y1117350D01*
X1796625Y1117475D01*
X1796250Y1117517D01*
X1795875Y1117475D01*
X1795542Y1117350D01*
X1795292Y1117183D01*
X1795083Y1116933D01*
X1795000Y1116600D01*
G01X1815350Y1124373D02*
X1813550Y1122273D01*
X1811350Y1124373D01*
G01X1807750Y1124473D02*
Y1105273D01*
X1818950D01*
Y1124473D01*
X1807750D01*
Y1124073D01*
G01X1814867Y1131292D02*
X1814617Y1131417D01*
X1814325Y1131500D01*
X1813992D01*
X1813617Y1131375D01*
X1813325Y1131167D01*
X1813117Y1130917D01*
X1812950Y1130500D01*
X1812908Y1130125D01*
X1812992Y1129750D01*
X1813117Y1129500D01*
X1813367Y1129250D01*
X1813658Y1129083D01*
X1813950Y1129000D01*
X1814242D01*
X1814533Y1129083D01*
X1814783Y1129208D01*
X1814992Y1129375D01*
G01X1817050Y1129000D02*
Y1131500D01*
X1816550Y1131000D01*
G01Y1129000D02*
X1817550D01*
G01X1820067D02*
X1820150Y1129542D01*
X1820275Y1130000D01*
X1820442Y1130417D01*
X1820650Y1130875D01*
X1820983Y1131500D01*
X1819317D01*
G01X1822542Y1129292D02*
X1822833Y1129083D01*
X1823167Y1129000D01*
X1823500Y1129083D01*
X1823792Y1129333D01*
X1824000Y1129708D01*
X1824083Y1130083D01*
Y1130542D01*
X1824000Y1130917D01*
X1823792Y1131250D01*
X1823542Y1131417D01*
X1823250Y1131500D01*
X1822917Y1131417D01*
X1822667Y1131250D01*
X1822500Y1131000D01*
X1822417Y1130667D01*
X1822500Y1130375D01*
X1822708Y1130083D01*
X1822958Y1129917D01*
X1823250Y1129875D01*
X1823583Y1129958D01*
X1823833Y1130167D01*
X1824083Y1130542D01*
G01X1796017Y1138000D02*
Y1140500D01*
X1797058D01*
X1797392Y1140375D01*
X1797600Y1140208D01*
X1797683Y1139875D01*
X1797600Y1139542D01*
X1797350Y1139333D01*
X1797058Y1139208D01*
X1796017D01*
G01X1797058D02*
X1797683Y1138000D01*
G01X1799033Y1138500D02*
X1799283Y1138208D01*
X1799617Y1138042D01*
X1799992Y1138000D01*
X1800325Y1138042D01*
X1800658Y1138250D01*
X1800867Y1138500D01*
X1800908Y1138750D01*
X1800825Y1139042D01*
X1800533Y1139250D01*
X1800242Y1139333D01*
X1799867D01*
G01X1800242D02*
X1800492Y1139458D01*
X1800700Y1139667D01*
X1800783Y1139917D01*
X1800700Y1140167D01*
X1800492Y1140375D01*
X1800117Y1140500D01*
X1799742Y1140458D01*
X1799367Y1140292D01*
G01X1802133Y1138375D02*
X1802383Y1138167D01*
X1802675Y1138042D01*
X1803050Y1138000D01*
X1803425Y1138083D01*
X1803717Y1138250D01*
X1803925Y1138542D01*
X1803967Y1138875D01*
X1803883Y1139208D01*
X1803675Y1139417D01*
X1803383Y1139583D01*
X1803092Y1139625D01*
X1802800Y1139583D01*
X1802425Y1139417D01*
X1802550Y1140500D01*
X1803675D01*
G01X1805442Y1138292D02*
X1805733Y1138083D01*
X1806067Y1138000D01*
X1806400Y1138083D01*
X1806692Y1138333D01*
X1806900Y1138708D01*
X1806983Y1139083D01*
Y1139542D01*
X1806900Y1139917D01*
X1806692Y1140250D01*
X1806442Y1140417D01*
X1806150Y1140500D01*
X1805817Y1140417D01*
X1805567Y1140250D01*
X1805400Y1140000D01*
X1805317Y1139667D01*
X1805400Y1139375D01*
X1805608Y1139083D01*
X1805858Y1138917D01*
X1806150Y1138875D01*
X1806483Y1138958D01*
X1806733Y1139167D01*
X1806983Y1139542D01*
G01X1810650Y1150173D02*
Y1142173D01*
X1793050D01*
Y1150173D01*
X1810650D01*
G01X1819043Y1182878D02*
Y1174878D01*
X1801443D01*
Y1182878D01*
X1819043D01*
G01X1797708Y1153767D02*
X1797583Y1153517D01*
X1797500Y1153225D01*
Y1152892D01*
X1797625Y1152517D01*
X1797833Y1152225D01*
X1798083Y1152017D01*
X1798500Y1151850D01*
X1798875Y1151808D01*
X1799250Y1151892D01*
X1799500Y1152017D01*
X1799750Y1152267D01*
X1799917Y1152558D01*
X1800000Y1152850D01*
Y1153142D01*
X1799917Y1153433D01*
X1799792Y1153683D01*
X1799625Y1153892D01*
G01X1800000Y1155950D02*
X1797500D01*
X1798000Y1155450D01*
G01X1800000D02*
Y1156450D01*
G01Y1158967D02*
X1799458Y1159050D01*
X1799000Y1159175D01*
X1798583Y1159342D01*
X1798125Y1159550D01*
X1797500Y1159883D01*
Y1158217D01*
G01X1800000Y1162150D02*
X1797500D01*
X1798000Y1161650D01*
G01X1800000D02*
Y1162650D01*
G01X1801350Y1155873D02*
Y1161373D01*
G01X1809350Y1155873D02*
X1801350D01*
G01X1809350Y1161373D02*
Y1155873D01*
G01Y1173473D02*
Y1167973D01*
G01X1801350Y1173473D02*
X1809350D01*
G01X1801350Y1167973D02*
Y1173473D01*
G01X1812150Y1151673D02*
X1814250Y1149873D01*
X1812150Y1147673D01*
G01X1812050Y1144073D02*
X1831250D01*
Y1155273D01*
X1812050D01*
Y1144073D01*
X1812450D01*
G01X1794208Y1177767D02*
X1794083Y1177517D01*
X1794000Y1177225D01*
Y1176892D01*
X1794125Y1176517D01*
X1794333Y1176225D01*
X1794583Y1176017D01*
X1795000Y1175850D01*
X1795375Y1175808D01*
X1795750Y1175892D01*
X1796000Y1176017D01*
X1796250Y1176267D01*
X1796417Y1176558D01*
X1796500Y1176850D01*
Y1177142D01*
X1796417Y1177433D01*
X1796292Y1177683D01*
X1796125Y1177892D01*
G01X1796500Y1179950D02*
X1794000D01*
X1794500Y1179450D01*
G01X1796500D02*
Y1180450D01*
G01Y1182967D02*
X1795958Y1183050D01*
X1795500Y1183175D01*
X1795083Y1183342D01*
X1794625Y1183550D01*
X1794000Y1183883D01*
Y1182217D01*
G01Y1186150D02*
X1794083Y1185817D01*
X1794292Y1185567D01*
X1794542Y1185400D01*
X1794875Y1185275D01*
X1795250Y1185233D01*
X1795625Y1185275D01*
X1795958Y1185400D01*
X1796208Y1185567D01*
X1796417Y1185817D01*
X1796500Y1186150D01*
X1796417Y1186483D01*
X1796208Y1186733D01*
X1795958Y1186900D01*
X1795625Y1187025D01*
X1795250Y1187067D01*
X1794875Y1187025D01*
X1794542Y1186900D01*
X1794292Y1186733D01*
X1794083Y1186483D01*
X1794000Y1186150D01*
G01X1810517Y1184500D02*
Y1187000D01*
X1811558D01*
X1811892Y1186875D01*
X1812100Y1186708D01*
X1812183Y1186375D01*
X1812100Y1186042D01*
X1811850Y1185833D01*
X1811558Y1185708D01*
X1810517D01*
G01X1811558D02*
X1812183Y1184500D01*
G01X1813533Y1185000D02*
X1813783Y1184708D01*
X1814117Y1184542D01*
X1814492Y1184500D01*
X1814825Y1184542D01*
X1815158Y1184750D01*
X1815367Y1185000D01*
X1815408Y1185250D01*
X1815325Y1185542D01*
X1815033Y1185750D01*
X1814742Y1185833D01*
X1814367D01*
G01X1814742D02*
X1814992Y1185958D01*
X1815200Y1186167D01*
X1815283Y1186417D01*
X1815200Y1186667D01*
X1814992Y1186875D01*
X1814617Y1187000D01*
X1814242Y1186958D01*
X1813867Y1186792D01*
G01X1816758Y1185542D02*
X1817050Y1185833D01*
X1817300Y1186000D01*
X1817633Y1186083D01*
X1817925Y1186000D01*
X1818133Y1185833D01*
X1818300Y1185583D01*
X1818342Y1185292D01*
X1818300Y1185042D01*
X1818133Y1184792D01*
X1817883Y1184583D01*
X1817592Y1184500D01*
X1817258Y1184583D01*
X1816967Y1184833D01*
X1816800Y1185208D01*
X1816758Y1185625D01*
X1816842Y1186167D01*
X1816967Y1186458D01*
X1817175Y1186750D01*
X1817467Y1186958D01*
X1817758Y1187000D01*
X1818050Y1186917D01*
X1818258Y1186708D01*
G01X1819733Y1185000D02*
X1819983Y1184708D01*
X1820317Y1184542D01*
X1820692Y1184500D01*
X1821025Y1184542D01*
X1821358Y1184750D01*
X1821567Y1185000D01*
X1821608Y1185250D01*
X1821525Y1185542D01*
X1821233Y1185750D01*
X1820942Y1185833D01*
X1820567D01*
G01X1820942D02*
X1821192Y1185958D01*
X1821400Y1186167D01*
X1821483Y1186417D01*
X1821400Y1186667D01*
X1821192Y1186875D01*
X1820817Y1187000D01*
X1820442Y1186958D01*
X1820067Y1186792D01*
G01X1766818Y1234004D02*
Y1236504D01*
G01X1768568D02*
Y1234004D01*
G01Y1235254D02*
X1766818D01*
G01X1769876Y1234004D02*
Y1236504D01*
X1770710D01*
X1771043Y1236379D01*
X1771293Y1236212D01*
X1771501Y1235962D01*
X1771668Y1235671D01*
X1771710Y1235254D01*
X1771668Y1234837D01*
X1771501Y1234546D01*
X1771293Y1234296D01*
X1771043Y1234129D01*
X1770710Y1234004D01*
X1769876D01*
G01X1772976D02*
Y1236504D01*
X1773810D01*
X1774143Y1236379D01*
X1774393Y1236212D01*
X1774601Y1235962D01*
X1774768Y1235671D01*
X1774810Y1235254D01*
X1774768Y1234837D01*
X1774601Y1234546D01*
X1774393Y1234296D01*
X1774143Y1234129D01*
X1773810Y1234004D01*
X1772976D01*
G01X1776118Y1234337D02*
X1776451Y1234129D01*
X1776826Y1234004D01*
X1777160D01*
X1777493Y1234129D01*
X1777743Y1234337D01*
X1777868Y1234629D01*
X1777785Y1234921D01*
X1777576Y1235171D01*
X1777201Y1235337D01*
X1776701Y1235421D01*
X1776410Y1235587D01*
X1776285Y1235879D01*
X1776368Y1236171D01*
X1776576Y1236379D01*
X1776868Y1236504D01*
X1777160D01*
X1777451Y1236421D01*
X1777701Y1236212D01*
G01X1779051Y1234004D02*
X1780093Y1236504D01*
X1781135Y1234004D01*
G01X1780760Y1234879D02*
X1779426D01*
G01X1782318Y1234337D02*
X1782651Y1234129D01*
X1783026Y1234004D01*
X1783360D01*
X1783693Y1234129D01*
X1783943Y1234337D01*
X1784068Y1234629D01*
X1783985Y1234921D01*
X1783776Y1235171D01*
X1783401Y1235337D01*
X1782901Y1235421D01*
X1782610Y1235587D01*
X1782485Y1235879D01*
X1782568Y1236171D01*
X1782776Y1236379D01*
X1783068Y1236504D01*
X1783360D01*
X1783651Y1236421D01*
X1783901Y1236212D01*
G01X1786293Y1234004D02*
Y1236504D01*
X1785793Y1236004D01*
G01Y1234004D02*
X1786793D01*
G01X1789393Y1236504D02*
X1789060Y1236421D01*
X1788810Y1236212D01*
X1788643Y1235962D01*
X1788518Y1235629D01*
X1788476Y1235254D01*
X1788518Y1234879D01*
X1788643Y1234546D01*
X1788810Y1234296D01*
X1789060Y1234087D01*
X1789393Y1234004D01*
X1789726Y1234087D01*
X1789976Y1234296D01*
X1790143Y1234546D01*
X1790268Y1234879D01*
X1790310Y1235254D01*
X1790268Y1235629D01*
X1790143Y1235962D01*
X1789976Y1236212D01*
X1789726Y1236421D01*
X1789393Y1236504D01*
G01X1818850Y138678D02*
X1816350D01*
Y139719D01*
X1816475Y140053D01*
X1816642Y140261D01*
X1816975Y140344D01*
X1817308Y140261D01*
X1817517Y140011D01*
X1817642Y139719D01*
Y138678D01*
G01Y139719D02*
X1818850Y140344D01*
G01X1818558Y141903D02*
X1818767Y142194D01*
X1818850Y142528D01*
X1818767Y142861D01*
X1818517Y143153D01*
X1818142Y143361D01*
X1817767Y143444D01*
X1817308D01*
X1816933Y143361D01*
X1816600Y143153D01*
X1816433Y142903D01*
X1816350Y142611D01*
X1816433Y142278D01*
X1816600Y142028D01*
X1816850Y141861D01*
X1817183Y141778D01*
X1817475Y141861D01*
X1817767Y142069D01*
X1817933Y142319D01*
X1817975Y142611D01*
X1817892Y142944D01*
X1817683Y143194D01*
X1817308Y143444D01*
G01X1816767Y144919D02*
X1816517Y145169D01*
X1816392Y145461D01*
X1816350Y145794D01*
X1816433Y146211D01*
X1816642Y146503D01*
X1816892Y146586D01*
X1817142Y146544D01*
X1817350Y146378D01*
X1817767Y145544D01*
X1818058Y145169D01*
X1818475Y144919D01*
X1818850Y144836D01*
Y146586D01*
G01X1816767Y148019D02*
X1816517Y148269D01*
X1816392Y148561D01*
X1816350Y148894D01*
X1816433Y149311D01*
X1816642Y149603D01*
X1816892Y149686D01*
X1817142Y149644D01*
X1817350Y149478D01*
X1817767Y148644D01*
X1818058Y148269D01*
X1818475Y148019D01*
X1818850Y147936D01*
Y149686D01*
G01X1816850Y163961D02*
X1820850D01*
Y171361D01*
G01X1823350Y151078D02*
X1820850D01*
Y152119D01*
X1820975Y152453D01*
X1821142Y152661D01*
X1821475Y152744D01*
X1821808Y152661D01*
X1822017Y152411D01*
X1822142Y152119D01*
Y151078D01*
G01Y152119D02*
X1823350Y152744D01*
G01X1823058Y154303D02*
X1823267Y154594D01*
X1823350Y154928D01*
X1823267Y155261D01*
X1823017Y155553D01*
X1822642Y155761D01*
X1822267Y155844D01*
X1821808D01*
X1821433Y155761D01*
X1821100Y155553D01*
X1820933Y155303D01*
X1820850Y155011D01*
X1820933Y154678D01*
X1821100Y154428D01*
X1821350Y154261D01*
X1821683Y154178D01*
X1821975Y154261D01*
X1822267Y154469D01*
X1822433Y154719D01*
X1822475Y155011D01*
X1822392Y155344D01*
X1822183Y155594D01*
X1821808Y155844D01*
G01X1821267Y157319D02*
X1821017Y157569D01*
X1820892Y157861D01*
X1820850Y158194D01*
X1820933Y158611D01*
X1821142Y158903D01*
X1821392Y158986D01*
X1821642Y158944D01*
X1821850Y158778D01*
X1822267Y157944D01*
X1822558Y157569D01*
X1822975Y157319D01*
X1823350Y157236D01*
Y158986D01*
G01Y161128D02*
X1822808Y161211D01*
X1822350Y161336D01*
X1821933Y161503D01*
X1821475Y161711D01*
X1820850Y162044D01*
Y160378D01*
G01X1818650Y151078D02*
X1816150D01*
Y152119D01*
X1816275Y152453D01*
X1816442Y152661D01*
X1816775Y152744D01*
X1817108Y152661D01*
X1817317Y152411D01*
X1817442Y152119D01*
Y151078D01*
G01Y152119D02*
X1818650Y152744D01*
G01X1818358Y154303D02*
X1818567Y154594D01*
X1818650Y154928D01*
X1818567Y155261D01*
X1818317Y155553D01*
X1817942Y155761D01*
X1817567Y155844D01*
X1817108D01*
X1816733Y155761D01*
X1816400Y155553D01*
X1816233Y155303D01*
X1816150Y155011D01*
X1816233Y154678D01*
X1816400Y154428D01*
X1816650Y154261D01*
X1816983Y154178D01*
X1817275Y154261D01*
X1817567Y154469D01*
X1817733Y154719D01*
X1817775Y155011D01*
X1817692Y155344D01*
X1817483Y155594D01*
X1817108Y155844D01*
G01X1816567Y157319D02*
X1816317Y157569D01*
X1816192Y157861D01*
X1816150Y158194D01*
X1816233Y158611D01*
X1816442Y158903D01*
X1816692Y158986D01*
X1816942Y158944D01*
X1817150Y158778D01*
X1817567Y157944D01*
X1817858Y157569D01*
X1818275Y157319D01*
X1818650Y157236D01*
Y158986D01*
G01X1818358Y160503D02*
X1818567Y160794D01*
X1818650Y161128D01*
X1818567Y161461D01*
X1818317Y161753D01*
X1817942Y161961D01*
X1817567Y162044D01*
X1817108D01*
X1816733Y161961D01*
X1816400Y161753D01*
X1816233Y161503D01*
X1816150Y161211D01*
X1816233Y160878D01*
X1816400Y160628D01*
X1816650Y160461D01*
X1816983Y160378D01*
X1817275Y160461D01*
X1817567Y160669D01*
X1817733Y160919D01*
X1817775Y161211D01*
X1817692Y161544D01*
X1817483Y161794D01*
X1817108Y162044D01*
G01X1846100Y139917D02*
X1843600D01*
Y140958D01*
X1843725Y141292D01*
X1843892Y141500D01*
X1844225Y141583D01*
X1844558Y141500D01*
X1844767Y141250D01*
X1844892Y140958D01*
Y139917D01*
G01Y140958D02*
X1846100Y141583D01*
G01X1845808Y143142D02*
X1846017Y143433D01*
X1846100Y143767D01*
X1846017Y144100D01*
X1845767Y144392D01*
X1845392Y144600D01*
X1845017Y144683D01*
X1844558D01*
X1844183Y144600D01*
X1843850Y144392D01*
X1843683Y144142D01*
X1843600Y143850D01*
X1843683Y143517D01*
X1843850Y143267D01*
X1844100Y143100D01*
X1844433Y143017D01*
X1844725Y143100D01*
X1845017Y143308D01*
X1845183Y143558D01*
X1845225Y143850D01*
X1845142Y144183D01*
X1844933Y144433D01*
X1844558Y144683D01*
G01X1846100Y147450D02*
X1843600D01*
X1845392Y145908D01*
Y147992D01*
G01X1845600Y149133D02*
X1845892Y149383D01*
X1846058Y149717D01*
X1846100Y150092D01*
X1846058Y150425D01*
X1845850Y150758D01*
X1845600Y150967D01*
X1845350Y151008D01*
X1845058Y150925D01*
X1844850Y150633D01*
X1844767Y150342D01*
Y149967D01*
G01Y150342D02*
X1844642Y150592D01*
X1844433Y150800D01*
X1844183Y150883D01*
X1843933Y150800D01*
X1843725Y150592D01*
X1843600Y150217D01*
X1843642Y149842D01*
X1843808Y149467D01*
G01X1843517Y159775D02*
X1847517D01*
Y167175D01*
G01X1842517Y139992D02*
X1840017D01*
Y141033D01*
X1840142Y141367D01*
X1840309Y141575D01*
X1840642Y141658D01*
X1840975Y141575D01*
X1841184Y141325D01*
X1841309Y141033D01*
Y139992D01*
G01Y141033D02*
X1842517Y141658D01*
G01X1842225Y143217D02*
X1842434Y143508D01*
X1842517Y143842D01*
X1842434Y144175D01*
X1842184Y144467D01*
X1841809Y144675D01*
X1841434Y144758D01*
X1840975D01*
X1840600Y144675D01*
X1840267Y144467D01*
X1840100Y144217D01*
X1840017Y143925D01*
X1840100Y143592D01*
X1840267Y143342D01*
X1840517Y143175D01*
X1840850Y143092D01*
X1841142Y143175D01*
X1841434Y143383D01*
X1841600Y143633D01*
X1841642Y143925D01*
X1841559Y144258D01*
X1841350Y144508D01*
X1840975Y144758D01*
G01X1842517Y147525D02*
X1840017D01*
X1841809Y145983D01*
Y148067D01*
G01X1842142Y149208D02*
X1842350Y149458D01*
X1842475Y149750D01*
X1842517Y150125D01*
X1842434Y150500D01*
X1842267Y150792D01*
X1841975Y151000D01*
X1841642Y151042D01*
X1841309Y150958D01*
X1841100Y150750D01*
X1840934Y150458D01*
X1840892Y150167D01*
X1840934Y149875D01*
X1841100Y149500D01*
X1840017Y149625D01*
Y150750D01*
G01X1839017Y159775D02*
X1843017D01*
Y167175D01*
G01X1856934Y147917D02*
X1854434D01*
Y148958D01*
X1854559Y149292D01*
X1854726Y149500D01*
X1855059Y149583D01*
X1855392Y149500D01*
X1855601Y149250D01*
X1855726Y148958D01*
Y147917D01*
G01Y148958D02*
X1856934Y149583D01*
G01X1856642Y151142D02*
X1856851Y151433D01*
X1856934Y151767D01*
X1856851Y152100D01*
X1856601Y152392D01*
X1856226Y152600D01*
X1855851Y152683D01*
X1855392D01*
X1855017Y152600D01*
X1854684Y152392D01*
X1854517Y152142D01*
X1854434Y151850D01*
X1854517Y151517D01*
X1854684Y151267D01*
X1854934Y151100D01*
X1855267Y151017D01*
X1855559Y151100D01*
X1855851Y151308D01*
X1856017Y151558D01*
X1856059Y151850D01*
X1855976Y152183D01*
X1855767Y152433D01*
X1855392Y152683D01*
G01X1856934Y155450D02*
X1854434D01*
X1856226Y153908D01*
Y155992D01*
G01X1856934Y157967D02*
X1856392Y158050D01*
X1855934Y158175D01*
X1855517Y158342D01*
X1855059Y158550D01*
X1854434Y158883D01*
Y157217D01*
G01X1857517Y167175D02*
X1853517D01*
Y159775D01*
G01X1821350Y176361D02*
X1825350D01*
Y183761D01*
G01X1826867Y180661D02*
Y183161D01*
X1827908D01*
X1828242Y183036D01*
X1828450Y182869D01*
X1828533Y182536D01*
X1828450Y182203D01*
X1828200Y181994D01*
X1827908Y181869D01*
X1826867D01*
G01X1827908D02*
X1828533Y180661D01*
G01X1830092Y180953D02*
X1830383Y180744D01*
X1830717Y180661D01*
X1831050Y180744D01*
X1831342Y180994D01*
X1831550Y181369D01*
X1831633Y181744D01*
Y182203D01*
X1831550Y182578D01*
X1831342Y182911D01*
X1831092Y183078D01*
X1830800Y183161D01*
X1830467Y183078D01*
X1830217Y182911D01*
X1830050Y182661D01*
X1829967Y182328D01*
X1830050Y182036D01*
X1830258Y181744D01*
X1830508Y181578D01*
X1830800Y181536D01*
X1831133Y181619D01*
X1831383Y181828D01*
X1831633Y182203D01*
G01X1833108Y182744D02*
X1833358Y182994D01*
X1833650Y183119D01*
X1833983Y183161D01*
X1834400Y183078D01*
X1834692Y182869D01*
X1834775Y182619D01*
X1834733Y182369D01*
X1834567Y182161D01*
X1833733Y181744D01*
X1833358Y181453D01*
X1833108Y181036D01*
X1833025Y180661D01*
X1834775D01*
G01X1837000D02*
X1837292Y180703D01*
X1837625Y180828D01*
X1837833Y181036D01*
X1837917Y181328D01*
X1837833Y181619D01*
X1837583Y181869D01*
X1837208Y181994D01*
X1836792D01*
X1836542Y182078D01*
X1836333Y182286D01*
X1836250Y182578D01*
X1836375Y182869D01*
X1836667Y183078D01*
X1837000Y183161D01*
X1837333Y183078D01*
X1837625Y182869D01*
X1837750Y182578D01*
X1837667Y182286D01*
X1837458Y182078D01*
X1837208Y181994D01*
X1836792D01*
X1836417Y181869D01*
X1836167Y181619D01*
X1836083Y181328D01*
X1836167Y181036D01*
X1836375Y180828D01*
X1836708Y180703D01*
X1837000Y180661D01*
G01X1824150Y196661D02*
Y192661D01*
X1831550D01*
G01X1816650Y176361D02*
X1820650D01*
Y183761D01*
G01X1854269Y206961D02*
Y202961D01*
X1861669D01*
G01X1838500Y192117D02*
X1836000D01*
Y193158D01*
X1836125Y193492D01*
X1836292Y193700D01*
X1836625Y193783D01*
X1836958Y193700D01*
X1837167Y193450D01*
X1837292Y193158D01*
Y192117D01*
G01Y193158D02*
X1838500Y193783D01*
G01X1838208Y195342D02*
X1838417Y195633D01*
X1838500Y195967D01*
X1838417Y196300D01*
X1838167Y196592D01*
X1837792Y196800D01*
X1837417Y196883D01*
X1836958D01*
X1836583Y196800D01*
X1836250Y196592D01*
X1836083Y196342D01*
X1836000Y196050D01*
X1836083Y195717D01*
X1836250Y195467D01*
X1836500Y195300D01*
X1836833Y195217D01*
X1837125Y195300D01*
X1837417Y195508D01*
X1837583Y195758D01*
X1837625Y196050D01*
X1837542Y196383D01*
X1837333Y196633D01*
X1836958Y196883D01*
G01X1838500Y199650D02*
X1836000D01*
X1837792Y198108D01*
Y200192D01*
G01X1838208Y201542D02*
X1838417Y201833D01*
X1838500Y202167D01*
X1838417Y202500D01*
X1838167Y202792D01*
X1837792Y203000D01*
X1837417Y203083D01*
X1836958D01*
X1836583Y203000D01*
X1836250Y202792D01*
X1836083Y202542D01*
X1836000Y202250D01*
X1836083Y201917D01*
X1836250Y201667D01*
X1836500Y201500D01*
X1836833Y201417D01*
X1837125Y201500D01*
X1837417Y201708D01*
X1837583Y201958D01*
X1837625Y202250D01*
X1837542Y202583D01*
X1837333Y202833D01*
X1836958Y203083D01*
G01X1845917Y199375D02*
X1841917D01*
Y191975D01*
G01X1834186Y210961D02*
Y213461D01*
X1835227D01*
X1835561Y213336D01*
X1835769Y213169D01*
X1835852Y212836D01*
X1835769Y212503D01*
X1835519Y212294D01*
X1835227Y212169D01*
X1834186D01*
G01X1835227D02*
X1835852Y210961D01*
G01X1837411Y211253D02*
X1837702Y211044D01*
X1838036Y210961D01*
X1838369Y211044D01*
X1838661Y211294D01*
X1838869Y211669D01*
X1838952Y212044D01*
Y212503D01*
X1838869Y212878D01*
X1838661Y213211D01*
X1838411Y213378D01*
X1838119Y213461D01*
X1837786Y213378D01*
X1837536Y213211D01*
X1837369Y212961D01*
X1837286Y212628D01*
X1837369Y212336D01*
X1837577Y212044D01*
X1837827Y211878D01*
X1838119Y211836D01*
X1838452Y211919D01*
X1838702Y212128D01*
X1838952Y212503D01*
G01X1840302Y211336D02*
X1840552Y211128D01*
X1840844Y211003D01*
X1841219Y210961D01*
X1841594Y211044D01*
X1841886Y211211D01*
X1842094Y211503D01*
X1842136Y211836D01*
X1842052Y212169D01*
X1841844Y212378D01*
X1841552Y212544D01*
X1841261Y212586D01*
X1840969Y212544D01*
X1840594Y212378D01*
X1840719Y213461D01*
X1841844D01*
G01X1844319D02*
X1843986Y213378D01*
X1843736Y213169D01*
X1843569Y212919D01*
X1843444Y212586D01*
X1843402Y212211D01*
X1843444Y211836D01*
X1843569Y211503D01*
X1843736Y211253D01*
X1843986Y211044D01*
X1844319Y210961D01*
X1844652Y211044D01*
X1844902Y211253D01*
X1845069Y211503D01*
X1845194Y211836D01*
X1845236Y212211D01*
X1845194Y212586D01*
X1845069Y212919D01*
X1844902Y213169D01*
X1844652Y213378D01*
X1844319Y213461D01*
G01X1853869Y208461D02*
Y212461D01*
X1846469D01*
G01X1840617Y204000D02*
Y206500D01*
X1841658D01*
X1841992Y206375D01*
X1842200Y206208D01*
X1842283Y205875D01*
X1842200Y205542D01*
X1841950Y205333D01*
X1841658Y205208D01*
X1840617D01*
G01X1841658D02*
X1842283Y204000D01*
G01X1843842Y204292D02*
X1844133Y204083D01*
X1844467Y204000D01*
X1844800Y204083D01*
X1845092Y204333D01*
X1845300Y204708D01*
X1845383Y205083D01*
Y205542D01*
X1845300Y205917D01*
X1845092Y206250D01*
X1844842Y206417D01*
X1844550Y206500D01*
X1844217Y206417D01*
X1843967Y206250D01*
X1843800Y206000D01*
X1843717Y205667D01*
X1843800Y205375D01*
X1844008Y205083D01*
X1844258Y204917D01*
X1844550Y204875D01*
X1844883Y204958D01*
X1845133Y205167D01*
X1845383Y205542D01*
G01X1846733Y204375D02*
X1846983Y204167D01*
X1847275Y204042D01*
X1847650Y204000D01*
X1848025Y204083D01*
X1848317Y204250D01*
X1848525Y204542D01*
X1848567Y204875D01*
X1848483Y205208D01*
X1848275Y205417D01*
X1847983Y205583D01*
X1847692Y205625D01*
X1847400Y205583D01*
X1847025Y205417D01*
X1847150Y206500D01*
X1848275D01*
G01X1850750Y204000D02*
Y206500D01*
X1850250Y206000D01*
G01Y204000D02*
X1851250D01*
G01X1846317Y196075D02*
Y192075D01*
X1853717D01*
G01X1851017Y180667D02*
Y183167D01*
X1852058D01*
X1852392Y183042D01*
X1852600Y182875D01*
X1852683Y182542D01*
X1852600Y182209D01*
X1852350Y182000D01*
X1852058Y181875D01*
X1851017D01*
G01X1852058D02*
X1852683Y180667D01*
G01X1854242Y180959D02*
X1854533Y180750D01*
X1854867Y180667D01*
X1855200Y180750D01*
X1855492Y181000D01*
X1855700Y181375D01*
X1855783Y181750D01*
Y182209D01*
X1855700Y182584D01*
X1855492Y182917D01*
X1855242Y183084D01*
X1854950Y183167D01*
X1854617Y183084D01*
X1854367Y182917D01*
X1854200Y182667D01*
X1854117Y182334D01*
X1854200Y182042D01*
X1854408Y181750D01*
X1854658Y181584D01*
X1854950Y181542D01*
X1855283Y181625D01*
X1855533Y181834D01*
X1855783Y182209D01*
G01X1857133Y181042D02*
X1857383Y180834D01*
X1857675Y180709D01*
X1858050Y180667D01*
X1858425Y180750D01*
X1858717Y180917D01*
X1858925Y181209D01*
X1858967Y181542D01*
X1858883Y181875D01*
X1858675Y182084D01*
X1858383Y182250D01*
X1858092Y182292D01*
X1857800Y182250D01*
X1857425Y182084D01*
X1857550Y183167D01*
X1858675D01*
G01X1860358Y182750D02*
X1860608Y183000D01*
X1860900Y183125D01*
X1861233Y183167D01*
X1861650Y183084D01*
X1861942Y182875D01*
X1862025Y182625D01*
X1861983Y182375D01*
X1861817Y182167D01*
X1860983Y181750D01*
X1860608Y181459D01*
X1860358Y181042D01*
X1860275Y180667D01*
X1862025D01*
G01X1847517Y179175D02*
Y183175D01*
X1840117D01*
G01X1848717Y167875D02*
X1862117D01*
G01X1848717Y179275D02*
Y167875D01*
G01X1862117Y179275D02*
X1848717D01*
G01X1840483Y200500D02*
Y203000D01*
X1841317D01*
X1841650Y202875D01*
X1841900Y202708D01*
X1842108Y202458D01*
X1842275Y202167D01*
X1842317Y201750D01*
X1842275Y201333D01*
X1842108Y201042D01*
X1841900Y200792D01*
X1841650Y200625D01*
X1841317Y200500D01*
X1840483D01*
G01X1843583Y201000D02*
X1843833Y200708D01*
X1844167Y200542D01*
X1844542Y200500D01*
X1844875Y200542D01*
X1845208Y200750D01*
X1845417Y201000D01*
X1845458Y201250D01*
X1845375Y201542D01*
X1845083Y201750D01*
X1844792Y201833D01*
X1844417D01*
G01X1844792D02*
X1845042Y201958D01*
X1845250Y202167D01*
X1845333Y202417D01*
X1845250Y202667D01*
X1845042Y202875D01*
X1844667Y203000D01*
X1844292Y202958D01*
X1843917Y202792D01*
G01X1846683Y200875D02*
X1846933Y200667D01*
X1847225Y200542D01*
X1847600Y200500D01*
X1847975Y200583D01*
X1848267Y200750D01*
X1848475Y201042D01*
X1848517Y201375D01*
X1848433Y201708D01*
X1848225Y201917D01*
X1847933Y202083D01*
X1847642Y202125D01*
X1847350Y202083D01*
X1846975Y201917D01*
X1847100Y203000D01*
X1848225D01*
G01X1856417Y184075D02*
X1840317D01*
G01X1856417Y191075D02*
Y184075D01*
G01X1840317Y191075D02*
X1856417D01*
G01X1840317Y184075D02*
Y191075D01*
G01X1826983Y176500D02*
Y179000D01*
X1827817D01*
X1828150Y178875D01*
X1828400Y178708D01*
X1828608Y178458D01*
X1828775Y178167D01*
X1828817Y177750D01*
X1828775Y177333D01*
X1828608Y177042D01*
X1828400Y176792D01*
X1828150Y176625D01*
X1827817Y176500D01*
X1826983D01*
G01X1830083Y177000D02*
X1830333Y176708D01*
X1830667Y176542D01*
X1831042Y176500D01*
X1831375Y176542D01*
X1831708Y176750D01*
X1831917Y177000D01*
X1831958Y177250D01*
X1831875Y177542D01*
X1831583Y177750D01*
X1831292Y177833D01*
X1830917D01*
G01X1831292D02*
X1831542Y177958D01*
X1831750Y178167D01*
X1831833Y178417D01*
X1831750Y178667D01*
X1831542Y178875D01*
X1831167Y179000D01*
X1830792Y178958D01*
X1830417Y178792D01*
G01X1834600Y176500D02*
Y179000D01*
X1833058Y177208D01*
X1835142D01*
G01X1833350Y184661D02*
X1817250D01*
G01X1833350Y191661D02*
Y184661D01*
G01X1817250Y191661D02*
X1833350D01*
G01X1817250Y184661D02*
Y191661D01*
G01X1834050Y221661D02*
Y225661D01*
X1826650D01*
G01X1857369Y250661D02*
Y258661D01*
X1874969D01*
Y250661D01*
X1857369D01*
G01X1844850Y260000D02*
X1844517Y260042D01*
X1844225Y260208D01*
X1843975Y260458D01*
X1843808Y260750D01*
X1843725Y261083D01*
Y261417D01*
X1843808Y261750D01*
X1843975Y262042D01*
X1844225Y262292D01*
X1844517Y262458D01*
X1844850Y262500D01*
X1845183Y262458D01*
X1845475Y262292D01*
X1845725Y262042D01*
X1845892Y261750D01*
X1845975Y261417D01*
Y261083D01*
X1845892Y260750D01*
X1845725Y260458D01*
X1845475Y260208D01*
X1845183Y260042D01*
X1844850Y260000D01*
G01X1845183Y260667D02*
X1845683Y260000D01*
G01X1847158Y262083D02*
X1847408Y262333D01*
X1847700Y262458D01*
X1848033Y262500D01*
X1848450Y262417D01*
X1848742Y262208D01*
X1848825Y261958D01*
X1848783Y261708D01*
X1848617Y261500D01*
X1847783Y261083D01*
X1847408Y260792D01*
X1847158Y260375D01*
X1847075Y260000D01*
X1848825D01*
G01X1851050D02*
Y262500D01*
X1850550Y262000D01*
G01Y260000D02*
X1851550D01*
G01X1853358Y262083D02*
X1853608Y262333D01*
X1853900Y262458D01*
X1854233Y262500D01*
X1854650Y262417D01*
X1854942Y262208D01*
X1855025Y261958D01*
X1854983Y261708D01*
X1854817Y261500D01*
X1853983Y261083D01*
X1853608Y260792D01*
X1853358Y260375D01*
X1853275Y260000D01*
X1855025D01*
G01X1839469Y237661D02*
X1841569Y235861D01*
X1839469Y233661D01*
G01X1839369Y230061D02*
X1858569D01*
Y241261D01*
X1839369D01*
Y230061D01*
X1839769D01*
G01X1823850Y259000D02*
X1823517Y259042D01*
X1823225Y259208D01*
X1822975Y259458D01*
X1822808Y259750D01*
X1822725Y260083D01*
Y260417D01*
X1822808Y260750D01*
X1822975Y261042D01*
X1823225Y261292D01*
X1823517Y261458D01*
X1823850Y261500D01*
X1824183Y261458D01*
X1824475Y261292D01*
X1824725Y261042D01*
X1824892Y260750D01*
X1824975Y260417D01*
Y260083D01*
X1824892Y259750D01*
X1824725Y259458D01*
X1824475Y259208D01*
X1824183Y259042D01*
X1823850Y259000D01*
G01X1824183Y259667D02*
X1824683Y259000D01*
G01X1826158Y261083D02*
X1826408Y261333D01*
X1826700Y261458D01*
X1827033Y261500D01*
X1827450Y261417D01*
X1827742Y261208D01*
X1827825Y260958D01*
X1827783Y260708D01*
X1827617Y260500D01*
X1826783Y260083D01*
X1826408Y259792D01*
X1826158Y259375D01*
X1826075Y259000D01*
X1827825D01*
G01X1830050Y261500D02*
X1829717Y261417D01*
X1829467Y261208D01*
X1829300Y260958D01*
X1829175Y260625D01*
X1829133Y260250D01*
X1829175Y259875D01*
X1829300Y259542D01*
X1829467Y259292D01*
X1829717Y259083D01*
X1830050Y259000D01*
X1830383Y259083D01*
X1830633Y259292D01*
X1830800Y259542D01*
X1830925Y259875D01*
X1830967Y260250D01*
X1830925Y260625D01*
X1830800Y260958D01*
X1830633Y261208D01*
X1830383Y261417D01*
X1830050Y261500D01*
G01X1832358Y260042D02*
X1832650Y260333D01*
X1832900Y260500D01*
X1833233Y260583D01*
X1833525Y260500D01*
X1833733Y260333D01*
X1833900Y260083D01*
X1833942Y259792D01*
X1833900Y259542D01*
X1833733Y259292D01*
X1833483Y259083D01*
X1833192Y259000D01*
X1832858Y259083D01*
X1832567Y259333D01*
X1832400Y259708D01*
X1832358Y260125D01*
X1832442Y260667D01*
X1832567Y260958D01*
X1832775Y261250D01*
X1833067Y261458D01*
X1833358Y261500D01*
X1833650Y261417D01*
X1833858Y261208D01*
G01X1835936Y217453D02*
X1835686Y217578D01*
X1835394Y217661D01*
X1835061D01*
X1834686Y217536D01*
X1834394Y217328D01*
X1834186Y217078D01*
X1834019Y216661D01*
X1833977Y216286D01*
X1834061Y215911D01*
X1834186Y215661D01*
X1834436Y215411D01*
X1834727Y215244D01*
X1835019Y215161D01*
X1835311D01*
X1835602Y215244D01*
X1835852Y215369D01*
X1836061Y215536D01*
G01X1837202D02*
X1837452Y215328D01*
X1837744Y215203D01*
X1838119Y215161D01*
X1838494Y215244D01*
X1838786Y215411D01*
X1838994Y215703D01*
X1839036Y216036D01*
X1838952Y216369D01*
X1838744Y216578D01*
X1838452Y216744D01*
X1838161Y216786D01*
X1837869Y216744D01*
X1837494Y216578D01*
X1837619Y217661D01*
X1838744D01*
G01X1841219D02*
X1840886Y217578D01*
X1840636Y217369D01*
X1840469Y217119D01*
X1840344Y216786D01*
X1840302Y216411D01*
X1840344Y216036D01*
X1840469Y215703D01*
X1840636Y215453D01*
X1840886Y215244D01*
X1841219Y215161D01*
X1841552Y215244D01*
X1841802Y215453D01*
X1841969Y215703D01*
X1842094Y216036D01*
X1842136Y216411D01*
X1842094Y216786D01*
X1841969Y217119D01*
X1841802Y217369D01*
X1841552Y217578D01*
X1841219Y217661D01*
G01X1844819Y215161D02*
Y217661D01*
X1843277Y215869D01*
X1845361D01*
G01X1860017Y273000D02*
Y275500D01*
X1861058D01*
X1861392Y275375D01*
X1861600Y275208D01*
X1861683Y274875D01*
X1861600Y274542D01*
X1861350Y274333D01*
X1861058Y274208D01*
X1860017D01*
G01X1861058D02*
X1861683Y273000D01*
G01X1863242Y273292D02*
X1863533Y273083D01*
X1863867Y273000D01*
X1864200Y273083D01*
X1864492Y273333D01*
X1864700Y273708D01*
X1864783Y274083D01*
Y274542D01*
X1864700Y274917D01*
X1864492Y275250D01*
X1864242Y275417D01*
X1863950Y275500D01*
X1863617Y275417D01*
X1863367Y275250D01*
X1863200Y275000D01*
X1863117Y274667D01*
X1863200Y274375D01*
X1863408Y274083D01*
X1863658Y273917D01*
X1863950Y273875D01*
X1864283Y273958D01*
X1864533Y274167D01*
X1864783Y274542D01*
G01X1866133Y273500D02*
X1866383Y273208D01*
X1866717Y273042D01*
X1867092Y273000D01*
X1867425Y273042D01*
X1867758Y273250D01*
X1867967Y273500D01*
X1868008Y273750D01*
X1867925Y274042D01*
X1867633Y274250D01*
X1867342Y274333D01*
X1866967D01*
G01X1867342D02*
X1867592Y274458D01*
X1867800Y274667D01*
X1867883Y274917D01*
X1867800Y275167D01*
X1867592Y275375D01*
X1867217Y275500D01*
X1866842Y275458D01*
X1866467Y275292D01*
G01X1869358Y274042D02*
X1869650Y274333D01*
X1869900Y274500D01*
X1870233Y274583D01*
X1870525Y274500D01*
X1870733Y274333D01*
X1870900Y274083D01*
X1870942Y273792D01*
X1870900Y273542D01*
X1870733Y273292D01*
X1870483Y273083D01*
X1870192Y273000D01*
X1869858Y273083D01*
X1869567Y273333D01*
X1869400Y273708D01*
X1869358Y274125D01*
X1869442Y274667D01*
X1869567Y274958D01*
X1869775Y275250D01*
X1870067Y275458D01*
X1870358Y275500D01*
X1870650Y275417D01*
X1870858Y275208D01*
G01X1845936Y266953D02*
X1845686Y267078D01*
X1845394Y267161D01*
X1845061D01*
X1844686Y267036D01*
X1844394Y266828D01*
X1844186Y266578D01*
X1844019Y266161D01*
X1843977Y265786D01*
X1844061Y265411D01*
X1844186Y265161D01*
X1844436Y264911D01*
X1844727Y264744D01*
X1845019Y264661D01*
X1845311D01*
X1845602Y264744D01*
X1845852Y264869D01*
X1846061Y265036D01*
G01X1847202D02*
X1847452Y264828D01*
X1847744Y264703D01*
X1848119Y264661D01*
X1848494Y264744D01*
X1848786Y264911D01*
X1848994Y265203D01*
X1849036Y265536D01*
X1848952Y265869D01*
X1848744Y266078D01*
X1848452Y266244D01*
X1848161Y266286D01*
X1847869Y266244D01*
X1847494Y266078D01*
X1847619Y267161D01*
X1848744D01*
G01X1851219D02*
X1850886Y267078D01*
X1850636Y266869D01*
X1850469Y266619D01*
X1850344Y266286D01*
X1850302Y265911D01*
X1850344Y265536D01*
X1850469Y265203D01*
X1850636Y264953D01*
X1850886Y264744D01*
X1851219Y264661D01*
X1851552Y264744D01*
X1851802Y264953D01*
X1851969Y265203D01*
X1852094Y265536D01*
X1852136Y265911D01*
X1852094Y266286D01*
X1851969Y266619D01*
X1851802Y266869D01*
X1851552Y267078D01*
X1851219Y267161D01*
G01X1854319Y264661D02*
Y267161D01*
X1853819Y266661D01*
G01Y264661D02*
X1854819D01*
G01X1822542Y288767D02*
X1822417Y288517D01*
X1822334Y288225D01*
Y287892D01*
X1822459Y287517D01*
X1822667Y287225D01*
X1822917Y287017D01*
X1823334Y286850D01*
X1823709Y286808D01*
X1824084Y286892D01*
X1824334Y287017D01*
X1824584Y287267D01*
X1824751Y287558D01*
X1824834Y287850D01*
Y288142D01*
X1824751Y288433D01*
X1824626Y288683D01*
X1824459Y288892D01*
G01X1824834Y291450D02*
X1822334D01*
X1824126Y289908D01*
Y291992D01*
G01X1824834Y294050D02*
X1824792Y294342D01*
X1824667Y294675D01*
X1824459Y294883D01*
X1824167Y294967D01*
X1823876Y294883D01*
X1823626Y294633D01*
X1823501Y294258D01*
Y293842D01*
X1823417Y293592D01*
X1823209Y293383D01*
X1822917Y293300D01*
X1822626Y293425D01*
X1822417Y293717D01*
X1822334Y294050D01*
X1822417Y294383D01*
X1822626Y294675D01*
X1822917Y294800D01*
X1823209Y294717D01*
X1823417Y294508D01*
X1823501Y294258D01*
Y293842D01*
X1823626Y293467D01*
X1823876Y293217D01*
X1824167Y293133D01*
X1824459Y293217D01*
X1824667Y293425D01*
X1824792Y293758D01*
X1824834Y294050D01*
G01Y297150D02*
X1824792Y297442D01*
X1824667Y297775D01*
X1824459Y297983D01*
X1824167Y298067D01*
X1823876Y297983D01*
X1823626Y297733D01*
X1823501Y297358D01*
Y296942D01*
X1823417Y296692D01*
X1823209Y296483D01*
X1822917Y296400D01*
X1822626Y296525D01*
X1822417Y296817D01*
X1822334Y297150D01*
X1822417Y297483D01*
X1822626Y297775D01*
X1822917Y297900D01*
X1823209Y297817D01*
X1823417Y297608D01*
X1823501Y297358D01*
Y296942D01*
X1823626Y296567D01*
X1823876Y296317D01*
X1824167Y296233D01*
X1824459Y296317D01*
X1824667Y296525D01*
X1824792Y296858D01*
X1824834Y297150D01*
G01X1818708Y288767D02*
X1818583Y288517D01*
X1818500Y288225D01*
Y287892D01*
X1818625Y287517D01*
X1818833Y287225D01*
X1819083Y287017D01*
X1819500Y286850D01*
X1819875Y286808D01*
X1820250Y286892D01*
X1820500Y287017D01*
X1820750Y287267D01*
X1820917Y287558D01*
X1821000Y287850D01*
Y288142D01*
X1820917Y288433D01*
X1820792Y288683D01*
X1820625Y288892D01*
G01X1821000Y291450D02*
X1818500D01*
X1820292Y289908D01*
Y291992D01*
G01X1821000Y294050D02*
X1820958Y294342D01*
X1820833Y294675D01*
X1820625Y294883D01*
X1820333Y294967D01*
X1820042Y294883D01*
X1819792Y294633D01*
X1819667Y294258D01*
Y293842D01*
X1819583Y293592D01*
X1819375Y293383D01*
X1819083Y293300D01*
X1818792Y293425D01*
X1818583Y293717D01*
X1818500Y294050D01*
X1818583Y294383D01*
X1818792Y294675D01*
X1819083Y294800D01*
X1819375Y294717D01*
X1819583Y294508D01*
X1819667Y294258D01*
Y293842D01*
X1819792Y293467D01*
X1820042Y293217D01*
X1820333Y293133D01*
X1820625Y293217D01*
X1820833Y293425D01*
X1820958Y293758D01*
X1821000Y294050D01*
G01X1819958Y296358D02*
X1819667Y296650D01*
X1819500Y296900D01*
X1819417Y297233D01*
X1819500Y297525D01*
X1819667Y297733D01*
X1819917Y297900D01*
X1820208Y297942D01*
X1820458Y297900D01*
X1820708Y297733D01*
X1820917Y297483D01*
X1821000Y297192D01*
X1820917Y296858D01*
X1820667Y296567D01*
X1820292Y296400D01*
X1819875Y296358D01*
X1819333Y296442D01*
X1819042Y296567D01*
X1818750Y296775D01*
X1818542Y297067D01*
X1818500Y297358D01*
X1818583Y297650D01*
X1818792Y297858D01*
G01X1861767Y267792D02*
X1861517Y267917D01*
X1861225Y268000D01*
X1860892D01*
X1860517Y267875D01*
X1860225Y267667D01*
X1860017Y267417D01*
X1859850Y267000D01*
X1859808Y266625D01*
X1859892Y266250D01*
X1860017Y266000D01*
X1860267Y265750D01*
X1860558Y265583D01*
X1860850Y265500D01*
X1861142D01*
X1861433Y265583D01*
X1861683Y265708D01*
X1861892Y265875D01*
G01X1864450Y265500D02*
Y268000D01*
X1862908Y266208D01*
X1864992D01*
G01X1866342Y265792D02*
X1866633Y265583D01*
X1866967Y265500D01*
X1867300Y265583D01*
X1867592Y265833D01*
X1867800Y266208D01*
X1867883Y266583D01*
Y267042D01*
X1867800Y267417D01*
X1867592Y267750D01*
X1867342Y267917D01*
X1867050Y268000D01*
X1866717Y267917D01*
X1866467Y267750D01*
X1866300Y267500D01*
X1866217Y267167D01*
X1866300Y266875D01*
X1866508Y266583D01*
X1866758Y266417D01*
X1867050Y266375D01*
X1867383Y266458D01*
X1867633Y266667D01*
X1867883Y267042D01*
G01X1869358Y266542D02*
X1869650Y266833D01*
X1869900Y267000D01*
X1870233Y267083D01*
X1870525Y267000D01*
X1870733Y266833D01*
X1870900Y266583D01*
X1870942Y266292D01*
X1870900Y266042D01*
X1870733Y265792D01*
X1870483Y265583D01*
X1870192Y265500D01*
X1869858Y265583D01*
X1869567Y265833D01*
X1869400Y266208D01*
X1869358Y266625D01*
X1869442Y267167D01*
X1869567Y267458D01*
X1869775Y267750D01*
X1870067Y267958D01*
X1870358Y268000D01*
X1870650Y267917D01*
X1870858Y267708D01*
G01X1861436Y271453D02*
X1861186Y271578D01*
X1860894Y271661D01*
X1860561D01*
X1860186Y271536D01*
X1859894Y271328D01*
X1859686Y271078D01*
X1859519Y270661D01*
X1859477Y270286D01*
X1859561Y269911D01*
X1859686Y269661D01*
X1859936Y269411D01*
X1860227Y269244D01*
X1860519Y269161D01*
X1860811D01*
X1861102Y269244D01*
X1861352Y269369D01*
X1861561Y269536D01*
G01X1864119Y269161D02*
Y271661D01*
X1862577Y269869D01*
X1864661D01*
G01X1866011Y269453D02*
X1866302Y269244D01*
X1866636Y269161D01*
X1866969Y269244D01*
X1867261Y269494D01*
X1867469Y269869D01*
X1867552Y270244D01*
Y270703D01*
X1867469Y271078D01*
X1867261Y271411D01*
X1867011Y271578D01*
X1866719Y271661D01*
X1866386Y271578D01*
X1866136Y271411D01*
X1865969Y271161D01*
X1865886Y270828D01*
X1865969Y270536D01*
X1866177Y270244D01*
X1866427Y270078D01*
X1866719Y270036D01*
X1867052Y270119D01*
X1867302Y270328D01*
X1867552Y270703D01*
G01X1868902Y269536D02*
X1869152Y269328D01*
X1869444Y269203D01*
X1869819Y269161D01*
X1870194Y269244D01*
X1870486Y269411D01*
X1870694Y269703D01*
X1870736Y270036D01*
X1870652Y270369D01*
X1870444Y270578D01*
X1870152Y270744D01*
X1869861Y270786D01*
X1869569Y270744D01*
X1869194Y270578D01*
X1869319Y271661D01*
X1870444D01*
G01X1814708Y288767D02*
X1814583Y288517D01*
X1814500Y288225D01*
Y287892D01*
X1814625Y287517D01*
X1814833Y287225D01*
X1815083Y287017D01*
X1815500Y286850D01*
X1815875Y286808D01*
X1816250Y286892D01*
X1816500Y287017D01*
X1816750Y287267D01*
X1816917Y287558D01*
X1817000Y287850D01*
Y288142D01*
X1816917Y288433D01*
X1816792Y288683D01*
X1816625Y288892D01*
G01X1817000Y291450D02*
X1814500D01*
X1816292Y289908D01*
Y291992D01*
G01X1817000Y294050D02*
X1816958Y294342D01*
X1816833Y294675D01*
X1816625Y294883D01*
X1816333Y294967D01*
X1816042Y294883D01*
X1815792Y294633D01*
X1815667Y294258D01*
Y293842D01*
X1815583Y293592D01*
X1815375Y293383D01*
X1815083Y293300D01*
X1814792Y293425D01*
X1814583Y293717D01*
X1814500Y294050D01*
X1814583Y294383D01*
X1814792Y294675D01*
X1815083Y294800D01*
X1815375Y294717D01*
X1815583Y294508D01*
X1815667Y294258D01*
Y293842D01*
X1815792Y293467D01*
X1816042Y293217D01*
X1816333Y293133D01*
X1816625Y293217D01*
X1816833Y293425D01*
X1816958Y293758D01*
X1817000Y294050D01*
G01X1816708Y296442D02*
X1816917Y296733D01*
X1817000Y297067D01*
X1816917Y297400D01*
X1816667Y297692D01*
X1816292Y297900D01*
X1815917Y297983D01*
X1815458D01*
X1815083Y297900D01*
X1814750Y297692D01*
X1814583Y297442D01*
X1814500Y297150D01*
X1814583Y296817D01*
X1814750Y296567D01*
X1815000Y296400D01*
X1815333Y296317D01*
X1815625Y296400D01*
X1815917Y296608D01*
X1816083Y296858D01*
X1816125Y297150D01*
X1816042Y297483D01*
X1815833Y297733D01*
X1815458Y297983D01*
G01X1853769Y382654D02*
Y385154D01*
X1855353D01*
G01X1854769Y383946D02*
X1853769D01*
G01X1856828Y385154D02*
Y382654D01*
X1858494D01*
G01X1861594D02*
X1859928D01*
Y385154D01*
X1861594D01*
G01X1860928Y383946D02*
X1859928D01*
G01X1862944Y382654D02*
Y385154D01*
X1863778D01*
X1864111Y385029D01*
X1864361Y384862D01*
X1864569Y384612D01*
X1864736Y384321D01*
X1864778Y383904D01*
X1864736Y383487D01*
X1864569Y383196D01*
X1864361Y382946D01*
X1864111Y382779D01*
X1863778Y382654D01*
X1862944D01*
G01X1866169Y384737D02*
X1866419Y384987D01*
X1866711Y385112D01*
X1867044Y385154D01*
X1867461Y385071D01*
X1867753Y384862D01*
X1867836Y384612D01*
X1867794Y384362D01*
X1867628Y384154D01*
X1866794Y383737D01*
X1866419Y383446D01*
X1866169Y383029D01*
X1866086Y382654D01*
X1867836D01*
G01X1870561D02*
Y385154D01*
X1869019Y383362D01*
X1871103D01*
G01X1857411Y366054D02*
Y377254D01*
X1866211D01*
Y366054D01*
X1857411D01*
G01X1829642Y490980D02*
X1829309Y491022D01*
X1829017Y491188D01*
X1828767Y491438D01*
X1828600Y491730D01*
X1828517Y492063D01*
Y492397D01*
X1828600Y492730D01*
X1828767Y493022D01*
X1829017Y493272D01*
X1829309Y493438D01*
X1829642Y493480D01*
X1829975Y493438D01*
X1830267Y493272D01*
X1830517Y493022D01*
X1830684Y492730D01*
X1830767Y492397D01*
Y492063D01*
X1830684Y491730D01*
X1830517Y491438D01*
X1830267Y491188D01*
X1829975Y491022D01*
X1829642Y490980D01*
G01X1829975Y491647D02*
X1830475Y490980D01*
G01X1831950Y493063D02*
X1832200Y493313D01*
X1832492Y493438D01*
X1832825Y493480D01*
X1833242Y493397D01*
X1833534Y493188D01*
X1833617Y492938D01*
X1833575Y492688D01*
X1833409Y492480D01*
X1832575Y492063D01*
X1832200Y491772D01*
X1831950Y491355D01*
X1831867Y490980D01*
X1833617D01*
G01X1835842D02*
X1836134Y491022D01*
X1836467Y491147D01*
X1836675Y491355D01*
X1836759Y491647D01*
X1836675Y491938D01*
X1836425Y492188D01*
X1836050Y492313D01*
X1835634D01*
X1835384Y492397D01*
X1835175Y492605D01*
X1835092Y492897D01*
X1835217Y493188D01*
X1835509Y493397D01*
X1835842Y493480D01*
X1836175Y493397D01*
X1836467Y493188D01*
X1836592Y492897D01*
X1836509Y492605D01*
X1836300Y492397D01*
X1836050Y492313D01*
X1835634D01*
X1835259Y492188D01*
X1835009Y491938D01*
X1834925Y491647D01*
X1835009Y491355D01*
X1835217Y491147D01*
X1835550Y491022D01*
X1835842Y490980D01*
G01X1838150Y492022D02*
X1838442Y492313D01*
X1838692Y492480D01*
X1839025Y492563D01*
X1839317Y492480D01*
X1839525Y492313D01*
X1839692Y492063D01*
X1839734Y491772D01*
X1839692Y491522D01*
X1839525Y491272D01*
X1839275Y491063D01*
X1838984Y490980D01*
X1838650Y491063D01*
X1838359Y491313D01*
X1838192Y491688D01*
X1838150Y492105D01*
X1838234Y492647D01*
X1838359Y492938D01*
X1838567Y493230D01*
X1838859Y493438D01*
X1839150Y493480D01*
X1839442Y493397D01*
X1839650Y493188D01*
G01X1841792Y495980D02*
Y509980D01*
G01X1828792Y495980D02*
X1841792D01*
G01X1828792Y509980D02*
Y495980D01*
G01X1843751Y490979D02*
X1843418Y491021D01*
X1843126Y491187D01*
X1842876Y491437D01*
X1842709Y491729D01*
X1842626Y492062D01*
Y492396D01*
X1842709Y492729D01*
X1842876Y493021D01*
X1843126Y493271D01*
X1843418Y493437D01*
X1843751Y493479D01*
X1844084Y493437D01*
X1844376Y493271D01*
X1844626Y493021D01*
X1844793Y492729D01*
X1844876Y492396D01*
Y492062D01*
X1844793Y491729D01*
X1844626Y491437D01*
X1844376Y491187D01*
X1844084Y491021D01*
X1843751Y490979D01*
G01X1844084Y491646D02*
X1844584Y490979D01*
G01X1846059Y493062D02*
X1846309Y493312D01*
X1846601Y493437D01*
X1846934Y493479D01*
X1847351Y493396D01*
X1847643Y493187D01*
X1847726Y492937D01*
X1847684Y492687D01*
X1847518Y492479D01*
X1846684Y492062D01*
X1846309Y491771D01*
X1846059Y491354D01*
X1845976Y490979D01*
X1847726D01*
G01X1849034Y491354D02*
X1849284Y491146D01*
X1849576Y491021D01*
X1849951Y490979D01*
X1850326Y491062D01*
X1850618Y491229D01*
X1850826Y491521D01*
X1850868Y491854D01*
X1850784Y492187D01*
X1850576Y492396D01*
X1850284Y492562D01*
X1849993Y492604D01*
X1849701Y492562D01*
X1849326Y492396D01*
X1849451Y493479D01*
X1850576D01*
G01X1853051D02*
X1852718Y493396D01*
X1852468Y493187D01*
X1852301Y492937D01*
X1852176Y492604D01*
X1852134Y492229D01*
X1852176Y491854D01*
X1852301Y491521D01*
X1852468Y491271D01*
X1852718Y491062D01*
X1853051Y490979D01*
X1853384Y491062D01*
X1853634Y491271D01*
X1853801Y491521D01*
X1853926Y491854D01*
X1853968Y492229D01*
X1853926Y492604D01*
X1853801Y492937D01*
X1853634Y493187D01*
X1853384Y493396D01*
X1853051Y493479D01*
G01X1855901Y495979D02*
Y509979D01*
G01X1842901Y495979D02*
X1855901D01*
G01X1842901Y509979D02*
Y495979D01*
G01X1841312Y520792D02*
Y523292D01*
X1842353D01*
X1842687Y523167D01*
X1842895Y523000D01*
X1842978Y522667D01*
X1842895Y522334D01*
X1842645Y522125D01*
X1842353Y522000D01*
X1841312D01*
G01X1842353D02*
X1842978Y520792D01*
G01X1844328Y521167D02*
X1844578Y520959D01*
X1844870Y520834D01*
X1845245Y520792D01*
X1845620Y520875D01*
X1845912Y521042D01*
X1846120Y521334D01*
X1846162Y521667D01*
X1846078Y522000D01*
X1845870Y522209D01*
X1845578Y522375D01*
X1845287Y522417D01*
X1844995Y522375D01*
X1844620Y522209D01*
X1844745Y523292D01*
X1845870D01*
G01X1848845Y520792D02*
Y523292D01*
X1847303Y521500D01*
X1849387D01*
G01X1850737Y521084D02*
X1851028Y520875D01*
X1851362Y520792D01*
X1851695Y520875D01*
X1851987Y521125D01*
X1852195Y521500D01*
X1852278Y521875D01*
Y522334D01*
X1852195Y522709D01*
X1851987Y523042D01*
X1851737Y523209D01*
X1851445Y523292D01*
X1851112Y523209D01*
X1850862Y523042D01*
X1850695Y522792D01*
X1850612Y522459D01*
X1850695Y522167D01*
X1850903Y521875D01*
X1851153Y521709D01*
X1851445Y521667D01*
X1851778Y521750D01*
X1852028Y521959D01*
X1852278Y522334D01*
G01X1850995Y511292D02*
Y515292D01*
X1843595D01*
G01X1827175Y520761D02*
Y523261D01*
X1828216D01*
X1828550Y523136D01*
X1828758Y522969D01*
X1828841Y522636D01*
X1828758Y522303D01*
X1828508Y522094D01*
X1828216Y521969D01*
X1827175D01*
G01X1828216D02*
X1828841Y520761D01*
G01X1830191Y521136D02*
X1830441Y520928D01*
X1830733Y520803D01*
X1831108Y520761D01*
X1831483Y520844D01*
X1831775Y521011D01*
X1831983Y521303D01*
X1832025Y521636D01*
X1831941Y521969D01*
X1831733Y522178D01*
X1831441Y522344D01*
X1831150Y522386D01*
X1830858Y522344D01*
X1830483Y522178D01*
X1830608Y523261D01*
X1831733D01*
G01X1834708Y520761D02*
Y523261D01*
X1833166Y521469D01*
X1835250D01*
G01X1837225Y520761D02*
X1837308Y521303D01*
X1837433Y521761D01*
X1837600Y522178D01*
X1837808Y522636D01*
X1838141Y523261D01*
X1836475D01*
G01X1836858Y511261D02*
Y515261D01*
X1829458D01*
G01X1841792Y509980D02*
X1828792D01*
G01X1855901Y509979D02*
X1842901D01*
G01X1849417Y598248D02*
X1846917D01*
Y599289D01*
X1847042Y599623D01*
X1847209Y599831D01*
X1847542Y599914D01*
X1847875Y599831D01*
X1848084Y599581D01*
X1848209Y599289D01*
Y598248D01*
G01Y599289D02*
X1849417Y599914D01*
G01X1848375Y601389D02*
X1848084Y601681D01*
X1847917Y601931D01*
X1847834Y602264D01*
X1847917Y602556D01*
X1848084Y602764D01*
X1848334Y602931D01*
X1848625Y602973D01*
X1848875Y602931D01*
X1849125Y602764D01*
X1849334Y602514D01*
X1849417Y602223D01*
X1849334Y601889D01*
X1849084Y601598D01*
X1848709Y601431D01*
X1848292Y601389D01*
X1847750Y601473D01*
X1847459Y601598D01*
X1847167Y601806D01*
X1846959Y602098D01*
X1846917Y602389D01*
X1847000Y602681D01*
X1847209Y602889D01*
G01X1848375Y604489D02*
X1848084Y604781D01*
X1847917Y605031D01*
X1847834Y605364D01*
X1847917Y605656D01*
X1848084Y605864D01*
X1848334Y606031D01*
X1848625Y606073D01*
X1848875Y606031D01*
X1849125Y605864D01*
X1849334Y605614D01*
X1849417Y605323D01*
X1849334Y604989D01*
X1849084Y604698D01*
X1848709Y604531D01*
X1848292Y604489D01*
X1847750Y604573D01*
X1847459Y604698D01*
X1847167Y604906D01*
X1846959Y605198D01*
X1846917Y605489D01*
X1847000Y605781D01*
X1847209Y605989D01*
G01X1849417Y608298D02*
X1848875Y608381D01*
X1848417Y608506D01*
X1848000Y608673D01*
X1847542Y608881D01*
X1846917Y609214D01*
Y607548D01*
G01X1844917Y598248D02*
X1842417D01*
Y599289D01*
X1842542Y599623D01*
X1842709Y599831D01*
X1843042Y599914D01*
X1843375Y599831D01*
X1843584Y599581D01*
X1843709Y599289D01*
Y598248D01*
G01Y599289D02*
X1844917Y599914D01*
G01X1843875Y601389D02*
X1843584Y601681D01*
X1843417Y601931D01*
X1843334Y602264D01*
X1843417Y602556D01*
X1843584Y602764D01*
X1843834Y602931D01*
X1844125Y602973D01*
X1844375Y602931D01*
X1844625Y602764D01*
X1844834Y602514D01*
X1844917Y602223D01*
X1844834Y601889D01*
X1844584Y601598D01*
X1844209Y601431D01*
X1843792Y601389D01*
X1843250Y601473D01*
X1842959Y601598D01*
X1842667Y601806D01*
X1842459Y602098D01*
X1842417Y602389D01*
X1842500Y602681D01*
X1842709Y602889D01*
G01X1843875Y604489D02*
X1843584Y604781D01*
X1843417Y605031D01*
X1843334Y605364D01*
X1843417Y605656D01*
X1843584Y605864D01*
X1843834Y606031D01*
X1844125Y606073D01*
X1844375Y606031D01*
X1844625Y605864D01*
X1844834Y605614D01*
X1844917Y605323D01*
X1844834Y604989D01*
X1844584Y604698D01*
X1844209Y604531D01*
X1843792Y604489D01*
X1843250Y604573D01*
X1842959Y604698D01*
X1842667Y604906D01*
X1842459Y605198D01*
X1842417Y605489D01*
X1842500Y605781D01*
X1842709Y605989D01*
G01X1844625Y607673D02*
X1844834Y607964D01*
X1844917Y608298D01*
X1844834Y608631D01*
X1844584Y608923D01*
X1844209Y609131D01*
X1843834Y609214D01*
X1843375D01*
X1843000Y609131D01*
X1842667Y608923D01*
X1842500Y608673D01*
X1842417Y608381D01*
X1842500Y608048D01*
X1842667Y607798D01*
X1842917Y607631D01*
X1843250Y607548D01*
X1843542Y607631D01*
X1843834Y607839D01*
X1844000Y608089D01*
X1844042Y608381D01*
X1843959Y608714D01*
X1843750Y608964D01*
X1843375Y609214D01*
G01X1856334Y598917D02*
X1853834D01*
Y599958D01*
X1853959Y600292D01*
X1854126Y600500D01*
X1854459Y600583D01*
X1854792Y600500D01*
X1855001Y600250D01*
X1855126Y599958D01*
Y598917D01*
G01Y599958D02*
X1856334Y600583D01*
G01X1855292Y602058D02*
X1855001Y602350D01*
X1854834Y602600D01*
X1854751Y602933D01*
X1854834Y603225D01*
X1855001Y603433D01*
X1855251Y603600D01*
X1855542Y603642D01*
X1855792Y603600D01*
X1856042Y603433D01*
X1856251Y603183D01*
X1856334Y602892D01*
X1856251Y602558D01*
X1856001Y602267D01*
X1855626Y602100D01*
X1855209Y602058D01*
X1854667Y602142D01*
X1854376Y602267D01*
X1854084Y602475D01*
X1853876Y602767D01*
X1853834Y603058D01*
X1853917Y603350D01*
X1854126Y603558D01*
G01X1856334Y605867D02*
X1855792Y605950D01*
X1855334Y606075D01*
X1854917Y606242D01*
X1854459Y606450D01*
X1853834Y606783D01*
Y605117D01*
G01X1856334Y609050D02*
X1853834D01*
X1854334Y608550D01*
G01X1856334D02*
Y609550D01*
G01X1820834Y603517D02*
X1818334D01*
Y604558D01*
X1818459Y604892D01*
X1818626Y605100D01*
X1818959Y605183D01*
X1819292Y605100D01*
X1819501Y604850D01*
X1819626Y604558D01*
Y603517D01*
G01Y604558D02*
X1820834Y605183D01*
G01X1819792Y606658D02*
X1819501Y606950D01*
X1819334Y607200D01*
X1819251Y607533D01*
X1819334Y607825D01*
X1819501Y608033D01*
X1819751Y608200D01*
X1820042Y608242D01*
X1820292Y608200D01*
X1820542Y608033D01*
X1820751Y607783D01*
X1820834Y607492D01*
X1820751Y607158D01*
X1820501Y606867D01*
X1820126Y606700D01*
X1819709Y606658D01*
X1819167Y606742D01*
X1818876Y606867D01*
X1818584Y607075D01*
X1818376Y607367D01*
X1818334Y607658D01*
X1818417Y607950D01*
X1818626Y608158D01*
G01X1820834Y611050D02*
X1818334D01*
X1820126Y609508D01*
Y611592D01*
G01X1820834Y613567D02*
X1820292Y613650D01*
X1819834Y613775D01*
X1819417Y613942D01*
X1818959Y614150D01*
X1818334Y614483D01*
Y612817D01*
G01X1816850Y616717D02*
X1820850D01*
Y624117D01*
G01X1836350Y616334D02*
X1833850D01*
Y617375D01*
X1833975Y617709D01*
X1834142Y617917D01*
X1834475Y618000D01*
X1834808Y617917D01*
X1835017Y617667D01*
X1835142Y617375D01*
Y616334D01*
G01Y617375D02*
X1836350Y618000D01*
G01X1835308Y619475D02*
X1835017Y619767D01*
X1834850Y620017D01*
X1834767Y620350D01*
X1834850Y620642D01*
X1835017Y620850D01*
X1835267Y621017D01*
X1835558Y621059D01*
X1835808Y621017D01*
X1836058Y620850D01*
X1836267Y620600D01*
X1836350Y620309D01*
X1836267Y619975D01*
X1836017Y619684D01*
X1835642Y619517D01*
X1835225Y619475D01*
X1834683Y619559D01*
X1834392Y619684D01*
X1834100Y619892D01*
X1833892Y620184D01*
X1833850Y620475D01*
X1833933Y620767D01*
X1834142Y620975D01*
G01X1835975Y622450D02*
X1836183Y622700D01*
X1836308Y622992D01*
X1836350Y623367D01*
X1836267Y623742D01*
X1836100Y624034D01*
X1835808Y624242D01*
X1835475Y624284D01*
X1835142Y624200D01*
X1834933Y623992D01*
X1834767Y623700D01*
X1834725Y623409D01*
X1834767Y623117D01*
X1834933Y622742D01*
X1833850Y622867D01*
Y623992D01*
G01Y626467D02*
X1833933Y626134D01*
X1834142Y625884D01*
X1834392Y625717D01*
X1834725Y625592D01*
X1835100Y625550D01*
X1835475Y625592D01*
X1835808Y625717D01*
X1836058Y625884D01*
X1836267Y626134D01*
X1836350Y626467D01*
X1836267Y626800D01*
X1836058Y627050D01*
X1835808Y627217D01*
X1835475Y627342D01*
X1835100Y627384D01*
X1834725Y627342D01*
X1834392Y627217D01*
X1834142Y627050D01*
X1833933Y626800D01*
X1833850Y626467D01*
G01X1821350Y629117D02*
X1825350D01*
Y636517D01*
G01X1826517Y633500D02*
Y636000D01*
X1827558D01*
X1827892Y635875D01*
X1828100Y635708D01*
X1828183Y635375D01*
X1828100Y635042D01*
X1827850Y634833D01*
X1827558Y634708D01*
X1826517D01*
G01X1827558D02*
X1828183Y633500D01*
G01X1829658Y634542D02*
X1829950Y634833D01*
X1830200Y635000D01*
X1830533Y635083D01*
X1830825Y635000D01*
X1831033Y634833D01*
X1831200Y634583D01*
X1831242Y634292D01*
X1831200Y634042D01*
X1831033Y633792D01*
X1830783Y633583D01*
X1830492Y633500D01*
X1830158Y633583D01*
X1829867Y633833D01*
X1829700Y634208D01*
X1829658Y634625D01*
X1829742Y635167D01*
X1829867Y635458D01*
X1830075Y635750D01*
X1830367Y635958D01*
X1830658Y636000D01*
X1830950Y635917D01*
X1831158Y635708D01*
G01X1832633Y633875D02*
X1832883Y633667D01*
X1833175Y633542D01*
X1833550Y633500D01*
X1833925Y633583D01*
X1834217Y633750D01*
X1834425Y634042D01*
X1834467Y634375D01*
X1834383Y634708D01*
X1834175Y634917D01*
X1833883Y635083D01*
X1833592Y635125D01*
X1833300Y635083D01*
X1832925Y634917D01*
X1833050Y636000D01*
X1834175D01*
G01X1835858Y635583D02*
X1836108Y635833D01*
X1836400Y635958D01*
X1836733Y636000D01*
X1837150Y635917D01*
X1837442Y635708D01*
X1837525Y635458D01*
X1837483Y635208D01*
X1837317Y635000D01*
X1836483Y634583D01*
X1836108Y634292D01*
X1835858Y633875D01*
X1835775Y633500D01*
X1837525D01*
G01X1824150Y649417D02*
Y645417D01*
X1831550D01*
G01X1831650Y616334D02*
X1829150D01*
Y617375D01*
X1829275Y617709D01*
X1829442Y617917D01*
X1829775Y618000D01*
X1830108Y617917D01*
X1830317Y617667D01*
X1830442Y617375D01*
Y616334D01*
G01Y617375D02*
X1831650Y618000D01*
G01X1830608Y619475D02*
X1830317Y619767D01*
X1830150Y620017D01*
X1830067Y620350D01*
X1830150Y620642D01*
X1830317Y620850D01*
X1830567Y621017D01*
X1830858Y621059D01*
X1831108Y621017D01*
X1831358Y620850D01*
X1831567Y620600D01*
X1831650Y620309D01*
X1831567Y619975D01*
X1831317Y619684D01*
X1830942Y619517D01*
X1830525Y619475D01*
X1829983Y619559D01*
X1829692Y619684D01*
X1829400Y619892D01*
X1829192Y620184D01*
X1829150Y620475D01*
X1829233Y620767D01*
X1829442Y620975D01*
G01X1831275Y622450D02*
X1831483Y622700D01*
X1831608Y622992D01*
X1831650Y623367D01*
X1831567Y623742D01*
X1831400Y624034D01*
X1831108Y624242D01*
X1830775Y624284D01*
X1830442Y624200D01*
X1830233Y623992D01*
X1830067Y623700D01*
X1830025Y623409D01*
X1830067Y623117D01*
X1830233Y622742D01*
X1829150Y622867D01*
Y623992D01*
G01X1831150Y625550D02*
X1831442Y625800D01*
X1831608Y626134D01*
X1831650Y626509D01*
X1831608Y626842D01*
X1831400Y627175D01*
X1831150Y627384D01*
X1830900Y627425D01*
X1830608Y627342D01*
X1830400Y627050D01*
X1830317Y626759D01*
Y626384D01*
G01Y626759D02*
X1830192Y627009D01*
X1829983Y627217D01*
X1829733Y627300D01*
X1829483Y627217D01*
X1829275Y627009D01*
X1829150Y626634D01*
X1829192Y626259D01*
X1829358Y625884D01*
G01X1816650Y629117D02*
X1820650D01*
Y636517D01*
G01X1843417Y612531D02*
X1847417D01*
Y619931D01*
G01X1838917Y612531D02*
X1842917D01*
Y619931D01*
G01X1857417D02*
X1853417D01*
Y612531D01*
G01X1838000Y645117D02*
X1835500D01*
Y646158D01*
X1835625Y646492D01*
X1835792Y646700D01*
X1836125Y646783D01*
X1836458Y646700D01*
X1836667Y646450D01*
X1836792Y646158D01*
Y645117D01*
G01Y646158D02*
X1838000Y646783D01*
G01X1836958Y648258D02*
X1836667Y648550D01*
X1836500Y648800D01*
X1836417Y649133D01*
X1836500Y649425D01*
X1836667Y649633D01*
X1836917Y649800D01*
X1837208Y649842D01*
X1837458Y649800D01*
X1837708Y649633D01*
X1837917Y649383D01*
X1838000Y649092D01*
X1837917Y648758D01*
X1837667Y648467D01*
X1837292Y648300D01*
X1836875Y648258D01*
X1836333Y648342D01*
X1836042Y648467D01*
X1835750Y648675D01*
X1835542Y648967D01*
X1835500Y649258D01*
X1835583Y649550D01*
X1835792Y649758D01*
G01X1838000Y652067D02*
X1837458Y652150D01*
X1837000Y652275D01*
X1836583Y652442D01*
X1836125Y652650D01*
X1835500Y652983D01*
Y651317D01*
G01X1838000Y655750D02*
X1835500D01*
X1837292Y654208D01*
Y656292D01*
G01X1845917Y652131D02*
X1841917D01*
Y644731D01*
G01X1846317Y648831D02*
Y644831D01*
X1853717D01*
G01X1853517Y633167D02*
Y635667D01*
X1854558D01*
X1854892Y635542D01*
X1855100Y635375D01*
X1855183Y635042D01*
X1855100Y634709D01*
X1854850Y634500D01*
X1854558Y634375D01*
X1853517D01*
G01X1854558D02*
X1855183Y633167D01*
G01X1856658Y634209D02*
X1856950Y634500D01*
X1857200Y634667D01*
X1857533Y634750D01*
X1857825Y634667D01*
X1858033Y634500D01*
X1858200Y634250D01*
X1858242Y633959D01*
X1858200Y633709D01*
X1858033Y633459D01*
X1857783Y633250D01*
X1857492Y633167D01*
X1857158Y633250D01*
X1856867Y633500D01*
X1856700Y633875D01*
X1856658Y634292D01*
X1856742Y634834D01*
X1856867Y635125D01*
X1857075Y635417D01*
X1857367Y635625D01*
X1857658Y635667D01*
X1857950Y635584D01*
X1858158Y635375D01*
G01X1860467Y633167D02*
X1860550Y633709D01*
X1860675Y634167D01*
X1860842Y634584D01*
X1861050Y635042D01*
X1861383Y635667D01*
X1859717D01*
G01X1862858Y634209D02*
X1863150Y634500D01*
X1863400Y634667D01*
X1863733Y634750D01*
X1864025Y634667D01*
X1864233Y634500D01*
X1864400Y634250D01*
X1864442Y633959D01*
X1864400Y633709D01*
X1864233Y633459D01*
X1863983Y633250D01*
X1863692Y633167D01*
X1863358Y633250D01*
X1863067Y633500D01*
X1862900Y633875D01*
X1862858Y634292D01*
X1862942Y634834D01*
X1863067Y635125D01*
X1863275Y635417D01*
X1863567Y635625D01*
X1863858Y635667D01*
X1864150Y635584D01*
X1864358Y635375D01*
G01X1847617Y631931D02*
Y635931D01*
X1840217D01*
G01X1859350Y616000D02*
X1859017Y616042D01*
X1858725Y616208D01*
X1858475Y616458D01*
X1858308Y616750D01*
X1858225Y617083D01*
Y617417D01*
X1858308Y617750D01*
X1858475Y618042D01*
X1858725Y618292D01*
X1859017Y618458D01*
X1859350Y618500D01*
X1859683Y618458D01*
X1859975Y618292D01*
X1860225Y618042D01*
X1860392Y617750D01*
X1860475Y617417D01*
Y617083D01*
X1860392Y616750D01*
X1860225Y616458D01*
X1859975Y616208D01*
X1859683Y616042D01*
X1859350Y616000D01*
G01X1859683Y616667D02*
X1860183Y616000D01*
G01X1862450D02*
Y618500D01*
X1861950Y618000D01*
G01Y616000D02*
X1862950D01*
G01X1864633Y616500D02*
X1864883Y616208D01*
X1865217Y616042D01*
X1865592Y616000D01*
X1865925Y616042D01*
X1866258Y616250D01*
X1866467Y616500D01*
X1866508Y616750D01*
X1866425Y617042D01*
X1866133Y617250D01*
X1865842Y617333D01*
X1865467D01*
G01X1865842D02*
X1866092Y617458D01*
X1866300Y617667D01*
X1866383Y617917D01*
X1866300Y618167D01*
X1866092Y618375D01*
X1865717Y618500D01*
X1865342Y618458D01*
X1864967Y618292D01*
G01X1867942Y616292D02*
X1868233Y616083D01*
X1868567Y616000D01*
X1868900Y616083D01*
X1869192Y616333D01*
X1869400Y616708D01*
X1869483Y617083D01*
Y617542D01*
X1869400Y617917D01*
X1869192Y618250D01*
X1868942Y618417D01*
X1868650Y618500D01*
X1868317Y618417D01*
X1868067Y618250D01*
X1867900Y618000D01*
X1867817Y617667D01*
X1867900Y617375D01*
X1868108Y617083D01*
X1868358Y616917D01*
X1868650Y616875D01*
X1868983Y616958D01*
X1869233Y617167D01*
X1869483Y617542D01*
G01X1848717Y620631D02*
X1862117D01*
G01X1848717Y632031D02*
Y620631D01*
G01X1862117Y632031D02*
X1848717D01*
G01X1856417Y636831D02*
X1840317D01*
G01X1856417Y643831D02*
Y636831D01*
G01X1840317Y643831D02*
X1856417D01*
G01X1840317Y636831D02*
Y643831D01*
G01X1826483Y630000D02*
Y632500D01*
X1827317D01*
X1827650Y632375D01*
X1827900Y632208D01*
X1828108Y631958D01*
X1828275Y631667D01*
X1828317Y631250D01*
X1828275Y630833D01*
X1828108Y630542D01*
X1827900Y630292D01*
X1827650Y630125D01*
X1827317Y630000D01*
X1826483D01*
G01X1829708Y632083D02*
X1829958Y632333D01*
X1830250Y632458D01*
X1830583Y632500D01*
X1831000Y632417D01*
X1831292Y632208D01*
X1831375Y631958D01*
X1831333Y631708D01*
X1831167Y631500D01*
X1830333Y631083D01*
X1829958Y630792D01*
X1829708Y630375D01*
X1829625Y630000D01*
X1831375D01*
G01X1832808Y632083D02*
X1833058Y632333D01*
X1833350Y632458D01*
X1833683Y632500D01*
X1834100Y632417D01*
X1834392Y632208D01*
X1834475Y631958D01*
X1834433Y631708D01*
X1834267Y631500D01*
X1833433Y631083D01*
X1833058Y630792D01*
X1832808Y630375D01*
X1832725Y630000D01*
X1834475D01*
G01X1833350Y637417D02*
X1817250D01*
G01X1833350Y644417D02*
Y637417D01*
G01X1817250Y644417D02*
X1833350D01*
G01X1817250Y637417D02*
Y644417D01*
G01X1834050Y674417D02*
Y678417D01*
X1826650D01*
G01X1857017Y648667D02*
Y651167D01*
X1858058D01*
X1858392Y651042D01*
X1858600Y650875D01*
X1858683Y650542D01*
X1858600Y650209D01*
X1858350Y650000D01*
X1858058Y649875D01*
X1857017D01*
G01X1858058D02*
X1858683Y648667D01*
G01X1860158Y649709D02*
X1860450Y650000D01*
X1860700Y650167D01*
X1861033Y650250D01*
X1861325Y650167D01*
X1861533Y650000D01*
X1861700Y649750D01*
X1861742Y649459D01*
X1861700Y649209D01*
X1861533Y648959D01*
X1861283Y648750D01*
X1860992Y648667D01*
X1860658Y648750D01*
X1860367Y649000D01*
X1860200Y649375D01*
X1860158Y649792D01*
X1860242Y650334D01*
X1860367Y650625D01*
X1860575Y650917D01*
X1860867Y651125D01*
X1861158Y651167D01*
X1861450Y651084D01*
X1861658Y650875D01*
G01X1863258Y649709D02*
X1863550Y650000D01*
X1863800Y650167D01*
X1864133Y650250D01*
X1864425Y650167D01*
X1864633Y650000D01*
X1864800Y649750D01*
X1864842Y649459D01*
X1864800Y649209D01*
X1864633Y648959D01*
X1864383Y648750D01*
X1864092Y648667D01*
X1863758Y648750D01*
X1863467Y649000D01*
X1863300Y649375D01*
X1863258Y649792D01*
X1863342Y650334D01*
X1863467Y650625D01*
X1863675Y650917D01*
X1863967Y651125D01*
X1864258Y651167D01*
X1864550Y651084D01*
X1864758Y650875D01*
G01X1866358Y649709D02*
X1866650Y650000D01*
X1866900Y650167D01*
X1867233Y650250D01*
X1867525Y650167D01*
X1867733Y650000D01*
X1867900Y649750D01*
X1867942Y649459D01*
X1867900Y649209D01*
X1867733Y648959D01*
X1867483Y648750D01*
X1867192Y648667D01*
X1866858Y648750D01*
X1866567Y649000D01*
X1866400Y649375D01*
X1866358Y649792D01*
X1866442Y650334D01*
X1866567Y650625D01*
X1866775Y650917D01*
X1867067Y651125D01*
X1867358Y651167D01*
X1867650Y651084D01*
X1867858Y650875D01*
G01X1854269Y659817D02*
Y655817D01*
X1861669D01*
G01X1834186Y664317D02*
Y666817D01*
X1835227D01*
X1835561Y666692D01*
X1835769Y666525D01*
X1835852Y666192D01*
X1835769Y665859D01*
X1835519Y665650D01*
X1835227Y665525D01*
X1834186D01*
G01X1835227D02*
X1835852Y664317D01*
G01X1837327Y665359D02*
X1837619Y665650D01*
X1837869Y665817D01*
X1838202Y665900D01*
X1838494Y665817D01*
X1838702Y665650D01*
X1838869Y665400D01*
X1838911Y665109D01*
X1838869Y664859D01*
X1838702Y664609D01*
X1838452Y664400D01*
X1838161Y664317D01*
X1837827Y664400D01*
X1837536Y664650D01*
X1837369Y665025D01*
X1837327Y665442D01*
X1837411Y665984D01*
X1837536Y666275D01*
X1837744Y666567D01*
X1838036Y666775D01*
X1838327Y666817D01*
X1838619Y666734D01*
X1838827Y666525D01*
G01X1841136Y664317D02*
X1841219Y664859D01*
X1841344Y665317D01*
X1841511Y665734D01*
X1841719Y666192D01*
X1842052Y666817D01*
X1840386D01*
G01X1843527Y666400D02*
X1843777Y666650D01*
X1844069Y666775D01*
X1844402Y666817D01*
X1844819Y666734D01*
X1845111Y666525D01*
X1845194Y666275D01*
X1845152Y666025D01*
X1844986Y665817D01*
X1844152Y665400D01*
X1843777Y665109D01*
X1843527Y664692D01*
X1843444Y664317D01*
X1845194D01*
G01X1853869Y661317D02*
Y665317D01*
X1846469D01*
G01X1834317Y657500D02*
Y660000D01*
X1835358D01*
X1835692Y659875D01*
X1835900Y659708D01*
X1835983Y659375D01*
X1835900Y659042D01*
X1835650Y658833D01*
X1835358Y658708D01*
X1834317D01*
G01X1835358D02*
X1835983Y657500D01*
G01X1837458Y658542D02*
X1837750Y658833D01*
X1838000Y659000D01*
X1838333Y659083D01*
X1838625Y659000D01*
X1838833Y658833D01*
X1839000Y658583D01*
X1839042Y658292D01*
X1839000Y658042D01*
X1838833Y657792D01*
X1838583Y657583D01*
X1838292Y657500D01*
X1837958Y657583D01*
X1837667Y657833D01*
X1837500Y658208D01*
X1837458Y658625D01*
X1837542Y659167D01*
X1837667Y659458D01*
X1837875Y659750D01*
X1838167Y659958D01*
X1838458Y660000D01*
X1838750Y659917D01*
X1838958Y659708D01*
G01X1841267Y657500D02*
X1841350Y658042D01*
X1841475Y658500D01*
X1841642Y658917D01*
X1841850Y659375D01*
X1842183Y660000D01*
X1840517D01*
G01X1843533Y657875D02*
X1843783Y657667D01*
X1844075Y657542D01*
X1844450Y657500D01*
X1844825Y657583D01*
X1845117Y657750D01*
X1845325Y658042D01*
X1845367Y658375D01*
X1845283Y658708D01*
X1845075Y658917D01*
X1844783Y659083D01*
X1844492Y659125D01*
X1844200Y659083D01*
X1843825Y658917D01*
X1843950Y660000D01*
X1845075D01*
G01X1838983Y653000D02*
Y655500D01*
X1839817D01*
X1840150Y655375D01*
X1840400Y655208D01*
X1840608Y654958D01*
X1840775Y654667D01*
X1840817Y654250D01*
X1840775Y653833D01*
X1840608Y653542D01*
X1840400Y653292D01*
X1840150Y653125D01*
X1839817Y653000D01*
X1838983D01*
G01X1842208Y655083D02*
X1842458Y655333D01*
X1842750Y655458D01*
X1843083Y655500D01*
X1843500Y655417D01*
X1843792Y655208D01*
X1843875Y654958D01*
X1843833Y654708D01*
X1843667Y654500D01*
X1842833Y654083D01*
X1842458Y653792D01*
X1842208Y653375D01*
X1842125Y653000D01*
X1843875D01*
G01X1845183Y653500D02*
X1845433Y653208D01*
X1845767Y653042D01*
X1846142Y653000D01*
X1846475Y653042D01*
X1846808Y653250D01*
X1847017Y653500D01*
X1847058Y653750D01*
X1846975Y654042D01*
X1846683Y654250D01*
X1846392Y654333D01*
X1846017D01*
G01X1846392D02*
X1846642Y654458D01*
X1846850Y654667D01*
X1846933Y654917D01*
X1846850Y655167D01*
X1846642Y655375D01*
X1846267Y655500D01*
X1845892Y655458D01*
X1845517Y655292D01*
G01X1839469Y690417D02*
X1841569Y688617D01*
X1839469Y686417D01*
G01X1839369Y682817D02*
X1858569D01*
Y694017D01*
X1839369D01*
Y682817D01*
X1839769D01*
G01X1835936Y670709D02*
X1835686Y670834D01*
X1835394Y670917D01*
X1835061D01*
X1834686Y670792D01*
X1834394Y670584D01*
X1834186Y670334D01*
X1834019Y669917D01*
X1833977Y669542D01*
X1834061Y669167D01*
X1834186Y668917D01*
X1834436Y668667D01*
X1834727Y668500D01*
X1835019Y668417D01*
X1835311D01*
X1835602Y668500D01*
X1835852Y668625D01*
X1836061Y668792D01*
G01X1837202Y668917D02*
X1837452Y668625D01*
X1837786Y668459D01*
X1838161Y668417D01*
X1838494Y668459D01*
X1838827Y668667D01*
X1839036Y668917D01*
X1839077Y669167D01*
X1838994Y669459D01*
X1838702Y669667D01*
X1838411Y669750D01*
X1838036D01*
G01X1838411D02*
X1838661Y669875D01*
X1838869Y670084D01*
X1838952Y670334D01*
X1838869Y670584D01*
X1838661Y670792D01*
X1838286Y670917D01*
X1837911Y670875D01*
X1837536Y670709D01*
G01X1841719Y668417D02*
Y670917D01*
X1840177Y669125D01*
X1842261D01*
G01X1844319Y668417D02*
X1844611Y668459D01*
X1844944Y668584D01*
X1845152Y668792D01*
X1845236Y669084D01*
X1845152Y669375D01*
X1844902Y669625D01*
X1844527Y669750D01*
X1844111D01*
X1843861Y669834D01*
X1843652Y670042D01*
X1843569Y670334D01*
X1843694Y670625D01*
X1843986Y670834D01*
X1844319Y670917D01*
X1844652Y670834D01*
X1844944Y670625D01*
X1845069Y670334D01*
X1844986Y670042D01*
X1844777Y669834D01*
X1844527Y669750D01*
X1844111D01*
X1843736Y669625D01*
X1843486Y669375D01*
X1843402Y669084D01*
X1843486Y668792D01*
X1843694Y668584D01*
X1844027Y668459D01*
X1844319Y668417D01*
G01X1852478Y672076D02*
X1852228Y672201D01*
X1851936Y672284D01*
X1851603D01*
X1851228Y672159D01*
X1850936Y671951D01*
X1850728Y671701D01*
X1850561Y671284D01*
X1850519Y670909D01*
X1850603Y670534D01*
X1850728Y670284D01*
X1850978Y670034D01*
X1851269Y669867D01*
X1851561Y669784D01*
X1851853D01*
X1852144Y669867D01*
X1852394Y669992D01*
X1852603Y670159D01*
G01X1853744Y670284D02*
X1853994Y669992D01*
X1854328Y669826D01*
X1854703Y669784D01*
X1855036Y669826D01*
X1855369Y670034D01*
X1855578Y670284D01*
X1855619Y670534D01*
X1855536Y670826D01*
X1855244Y671034D01*
X1854953Y671117D01*
X1854578D01*
G01X1854953D02*
X1855203Y671242D01*
X1855411Y671451D01*
X1855494Y671701D01*
X1855411Y671951D01*
X1855203Y672159D01*
X1854828Y672284D01*
X1854453Y672242D01*
X1854078Y672076D01*
G01X1858261Y669784D02*
Y672284D01*
X1856719Y670492D01*
X1858803D01*
G01X1860778Y669784D02*
X1860861Y670326D01*
X1860986Y670784D01*
X1861153Y671201D01*
X1861361Y671659D01*
X1861694Y672284D01*
X1860028D01*
G01X1824367Y712417D02*
Y714917D01*
X1825408D01*
X1825742Y714792D01*
X1825950Y714625D01*
X1826033Y714292D01*
X1825950Y713959D01*
X1825700Y713750D01*
X1825408Y713625D01*
X1824367D01*
G01X1825408D02*
X1826033Y712417D01*
G01X1827508Y713459D02*
X1827800Y713750D01*
X1828050Y713917D01*
X1828383Y714000D01*
X1828675Y713917D01*
X1828883Y713750D01*
X1829050Y713500D01*
X1829092Y713209D01*
X1829050Y712959D01*
X1828883Y712709D01*
X1828633Y712500D01*
X1828342Y712417D01*
X1828008Y712500D01*
X1827717Y712750D01*
X1827550Y713125D01*
X1827508Y713542D01*
X1827592Y714084D01*
X1827717Y714375D01*
X1827925Y714667D01*
X1828217Y714875D01*
X1828508Y714917D01*
X1828800Y714834D01*
X1829008Y714625D01*
G01X1830483Y712792D02*
X1830733Y712584D01*
X1831025Y712459D01*
X1831400Y712417D01*
X1831775Y712500D01*
X1832067Y712667D01*
X1832275Y712959D01*
X1832317Y713292D01*
X1832233Y713625D01*
X1832025Y713834D01*
X1831733Y714000D01*
X1831442Y714042D01*
X1831150Y714000D01*
X1830775Y713834D01*
X1830900Y714917D01*
X1832025D01*
G01X1834500Y712417D02*
Y714917D01*
X1834000Y714417D01*
G01Y712417D02*
X1835000D01*
G01X1856759Y724284D02*
Y726784D01*
X1857800D01*
X1858134Y726659D01*
X1858342Y726492D01*
X1858425Y726159D01*
X1858342Y725826D01*
X1858092Y725617D01*
X1857800Y725492D01*
X1856759D01*
G01X1857800D02*
X1858425Y724284D01*
G01X1859900Y725326D02*
X1860192Y725617D01*
X1860442Y725784D01*
X1860775Y725867D01*
X1861067Y725784D01*
X1861275Y725617D01*
X1861442Y725367D01*
X1861484Y725076D01*
X1861442Y724826D01*
X1861275Y724576D01*
X1861025Y724367D01*
X1860734Y724284D01*
X1860400Y724367D01*
X1860109Y724617D01*
X1859942Y724992D01*
X1859900Y725409D01*
X1859984Y725951D01*
X1860109Y726242D01*
X1860317Y726534D01*
X1860609Y726742D01*
X1860900Y726784D01*
X1861192Y726701D01*
X1861400Y726492D01*
G01X1863000Y725326D02*
X1863292Y725617D01*
X1863542Y725784D01*
X1863875Y725867D01*
X1864167Y725784D01*
X1864375Y725617D01*
X1864542Y725367D01*
X1864584Y725076D01*
X1864542Y724826D01*
X1864375Y724576D01*
X1864125Y724367D01*
X1863834Y724284D01*
X1863500Y724367D01*
X1863209Y724617D01*
X1863042Y724992D01*
X1863000Y725409D01*
X1863084Y725951D01*
X1863209Y726242D01*
X1863417Y726534D01*
X1863709Y726742D01*
X1864000Y726784D01*
X1864292Y726701D01*
X1864500Y726492D01*
G01X1866892Y726784D02*
X1866559Y726701D01*
X1866309Y726492D01*
X1866142Y726242D01*
X1866017Y725909D01*
X1865975Y725534D01*
X1866017Y725159D01*
X1866142Y724826D01*
X1866309Y724576D01*
X1866559Y724367D01*
X1866892Y724284D01*
X1867225Y724367D01*
X1867475Y724576D01*
X1867642Y724826D01*
X1867767Y725159D01*
X1867809Y725534D01*
X1867767Y725909D01*
X1867642Y726242D01*
X1867475Y726492D01*
X1867225Y726701D01*
X1866892Y726784D01*
G01X1853900Y703200D02*
Y711200D01*
X1871500D01*
Y703200D01*
X1853900D01*
G01X1841843Y718709D02*
X1841593Y718834D01*
X1841301Y718917D01*
X1840968D01*
X1840593Y718792D01*
X1840301Y718584D01*
X1840093Y718334D01*
X1839926Y717917D01*
X1839884Y717542D01*
X1839968Y717167D01*
X1840093Y716917D01*
X1840343Y716667D01*
X1840634Y716500D01*
X1840926Y716417D01*
X1841218D01*
X1841509Y716500D01*
X1841759Y716625D01*
X1841968Y716792D01*
G01X1843109Y716917D02*
X1843359Y716625D01*
X1843693Y716459D01*
X1844068Y716417D01*
X1844401Y716459D01*
X1844734Y716667D01*
X1844943Y716917D01*
X1844984Y717167D01*
X1844901Y717459D01*
X1844609Y717667D01*
X1844318Y717750D01*
X1843943D01*
G01X1844318D02*
X1844568Y717875D01*
X1844776Y718084D01*
X1844859Y718334D01*
X1844776Y718584D01*
X1844568Y718792D01*
X1844193Y718917D01*
X1843818Y718875D01*
X1843443Y718709D01*
G01X1847626Y716417D02*
Y718917D01*
X1846084Y717125D01*
X1848168D01*
G01X1850726Y716417D02*
Y718917D01*
X1849184Y717125D01*
X1851268D01*
G01X1823208Y741767D02*
X1823083Y741517D01*
X1823000Y741225D01*
Y740892D01*
X1823125Y740517D01*
X1823333Y740225D01*
X1823583Y740017D01*
X1824000Y739850D01*
X1824375Y739808D01*
X1824750Y739892D01*
X1825000Y740017D01*
X1825250Y740267D01*
X1825417Y740558D01*
X1825500Y740850D01*
Y741142D01*
X1825417Y741433D01*
X1825292Y741683D01*
X1825125Y741892D01*
G01X1825000Y743033D02*
X1825292Y743283D01*
X1825458Y743617D01*
X1825500Y743992D01*
X1825458Y744325D01*
X1825250Y744658D01*
X1825000Y744867D01*
X1824750Y744908D01*
X1824458Y744825D01*
X1824250Y744533D01*
X1824167Y744242D01*
Y743867D01*
G01Y744242D02*
X1824042Y744492D01*
X1823833Y744700D01*
X1823583Y744783D01*
X1823333Y744700D01*
X1823125Y744492D01*
X1823000Y744117D01*
X1823042Y743742D01*
X1823208Y743367D01*
G01X1825000Y746133D02*
X1825292Y746383D01*
X1825458Y746717D01*
X1825500Y747092D01*
X1825458Y747425D01*
X1825250Y747758D01*
X1825000Y747967D01*
X1824750Y748008D01*
X1824458Y747925D01*
X1824250Y747633D01*
X1824167Y747342D01*
Y746967D01*
G01Y747342D02*
X1824042Y747592D01*
X1823833Y747800D01*
X1823583Y747883D01*
X1823333Y747800D01*
X1823125Y747592D01*
X1823000Y747217D01*
X1823042Y746842D01*
X1823208Y746467D01*
G01X1823417Y749358D02*
X1823167Y749608D01*
X1823042Y749900D01*
X1823000Y750233D01*
X1823083Y750650D01*
X1823292Y750942D01*
X1823542Y751025D01*
X1823792Y750983D01*
X1824000Y750817D01*
X1824417Y749983D01*
X1824708Y749608D01*
X1825125Y749358D01*
X1825500Y749275D01*
Y751025D01*
G01X1819208Y741767D02*
X1819083Y741517D01*
X1819000Y741225D01*
Y740892D01*
X1819125Y740517D01*
X1819333Y740225D01*
X1819583Y740017D01*
X1820000Y739850D01*
X1820375Y739808D01*
X1820750Y739892D01*
X1821000Y740017D01*
X1821250Y740267D01*
X1821417Y740558D01*
X1821500Y740850D01*
Y741142D01*
X1821417Y741433D01*
X1821292Y741683D01*
X1821125Y741892D01*
G01X1821000Y743033D02*
X1821292Y743283D01*
X1821458Y743617D01*
X1821500Y743992D01*
X1821458Y744325D01*
X1821250Y744658D01*
X1821000Y744867D01*
X1820750Y744908D01*
X1820458Y744825D01*
X1820250Y744533D01*
X1820167Y744242D01*
Y743867D01*
G01Y744242D02*
X1820042Y744492D01*
X1819833Y744700D01*
X1819583Y744783D01*
X1819333Y744700D01*
X1819125Y744492D01*
X1819000Y744117D01*
X1819042Y743742D01*
X1819208Y743367D01*
G01X1821000Y746133D02*
X1821292Y746383D01*
X1821458Y746717D01*
X1821500Y747092D01*
X1821458Y747425D01*
X1821250Y747758D01*
X1821000Y747967D01*
X1820750Y748008D01*
X1820458Y747925D01*
X1820250Y747633D01*
X1820167Y747342D01*
Y746967D01*
G01Y747342D02*
X1820042Y747592D01*
X1819833Y747800D01*
X1819583Y747883D01*
X1819333Y747800D01*
X1819125Y747592D01*
X1819000Y747217D01*
X1819042Y746842D01*
X1819208Y746467D01*
G01X1819000Y750150D02*
X1819083Y749817D01*
X1819292Y749567D01*
X1819542Y749400D01*
X1819875Y749275D01*
X1820250Y749233D01*
X1820625Y749275D01*
X1820958Y749400D01*
X1821208Y749567D01*
X1821417Y749817D01*
X1821500Y750150D01*
X1821417Y750483D01*
X1821208Y750733D01*
X1820958Y750900D01*
X1820625Y751025D01*
X1820250Y751067D01*
X1819875Y751025D01*
X1819542Y750900D01*
X1819292Y750733D01*
X1819083Y750483D01*
X1819000Y750150D01*
G01X1858267Y718292D02*
X1858017Y718417D01*
X1857725Y718500D01*
X1857392D01*
X1857017Y718375D01*
X1856725Y718167D01*
X1856517Y717917D01*
X1856350Y717500D01*
X1856308Y717125D01*
X1856392Y716750D01*
X1856517Y716500D01*
X1856767Y716250D01*
X1857058Y716083D01*
X1857350Y716000D01*
X1857642D01*
X1857933Y716083D01*
X1858183Y716208D01*
X1858392Y716375D01*
G01X1859533Y716500D02*
X1859783Y716208D01*
X1860117Y716042D01*
X1860492Y716000D01*
X1860825Y716042D01*
X1861158Y716250D01*
X1861367Y716500D01*
X1861408Y716750D01*
X1861325Y717042D01*
X1861033Y717250D01*
X1860742Y717333D01*
X1860367D01*
G01X1860742D02*
X1860992Y717458D01*
X1861200Y717667D01*
X1861283Y717917D01*
X1861200Y718167D01*
X1860992Y718375D01*
X1860617Y718500D01*
X1860242Y718458D01*
X1859867Y718292D01*
G01X1864050Y716000D02*
Y718500D01*
X1862508Y716708D01*
X1864592D01*
G01X1866650Y718500D02*
X1866317Y718417D01*
X1866067Y718208D01*
X1865900Y717958D01*
X1865775Y717625D01*
X1865733Y717250D01*
X1865775Y716875D01*
X1865900Y716542D01*
X1866067Y716292D01*
X1866317Y716083D01*
X1866650Y716000D01*
X1866983Y716083D01*
X1867233Y716292D01*
X1867400Y716542D01*
X1867525Y716875D01*
X1867567Y717250D01*
X1867525Y717625D01*
X1867400Y717958D01*
X1867233Y718208D01*
X1866983Y718417D01*
X1866650Y718500D01*
G01X1840850Y712500D02*
X1840517Y712542D01*
X1840225Y712708D01*
X1839975Y712958D01*
X1839808Y713250D01*
X1839725Y713583D01*
Y713917D01*
X1839808Y714250D01*
X1839975Y714542D01*
X1840225Y714792D01*
X1840517Y714958D01*
X1840850Y715000D01*
X1841183Y714958D01*
X1841475Y714792D01*
X1841725Y714542D01*
X1841892Y714250D01*
X1841975Y713917D01*
Y713583D01*
X1841892Y713250D01*
X1841725Y712958D01*
X1841475Y712708D01*
X1841183Y712542D01*
X1840850Y712500D01*
G01X1841183Y713167D02*
X1841683Y712500D01*
G01X1843950D02*
Y715000D01*
X1843450Y714500D01*
G01Y712500D02*
X1844450D01*
G01X1847550D02*
Y715000D01*
X1846008Y713208D01*
X1848092D01*
G01X1850150Y715000D02*
X1849817Y714917D01*
X1849567Y714708D01*
X1849400Y714458D01*
X1849275Y714125D01*
X1849233Y713750D01*
X1849275Y713375D01*
X1849400Y713042D01*
X1849567Y712792D01*
X1849817Y712583D01*
X1850150Y712500D01*
X1850483Y712583D01*
X1850733Y712792D01*
X1850900Y713042D01*
X1851025Y713375D01*
X1851067Y713750D01*
X1851025Y714125D01*
X1850900Y714458D01*
X1850733Y714708D01*
X1850483Y714917D01*
X1850150Y715000D01*
G01X1824850Y720000D02*
X1824517Y720042D01*
X1824225Y720208D01*
X1823975Y720458D01*
X1823808Y720750D01*
X1823725Y721083D01*
Y721417D01*
X1823808Y721750D01*
X1823975Y722042D01*
X1824225Y722292D01*
X1824517Y722458D01*
X1824850Y722500D01*
X1825183Y722458D01*
X1825475Y722292D01*
X1825725Y722042D01*
X1825892Y721750D01*
X1825975Y721417D01*
Y721083D01*
X1825892Y720750D01*
X1825725Y720458D01*
X1825475Y720208D01*
X1825183Y720042D01*
X1824850Y720000D01*
G01X1825183Y720667D02*
X1825683Y720000D01*
G01X1827950D02*
Y722500D01*
X1827450Y722000D01*
G01Y720000D02*
X1828450D01*
G01X1830133Y720500D02*
X1830383Y720208D01*
X1830717Y720042D01*
X1831092Y720000D01*
X1831425Y720042D01*
X1831758Y720250D01*
X1831967Y720500D01*
X1832008Y720750D01*
X1831925Y721042D01*
X1831633Y721250D01*
X1831342Y721333D01*
X1830967D01*
G01X1831342D02*
X1831592Y721458D01*
X1831800Y721667D01*
X1831883Y721917D01*
X1831800Y722167D01*
X1831592Y722375D01*
X1831217Y722500D01*
X1830842Y722458D01*
X1830467Y722292D01*
G01X1834650Y720000D02*
Y722500D01*
X1833108Y720708D01*
X1835192D01*
G01X1858267Y722292D02*
X1858017Y722417D01*
X1857725Y722500D01*
X1857392D01*
X1857017Y722375D01*
X1856725Y722167D01*
X1856517Y721917D01*
X1856350Y721500D01*
X1856308Y721125D01*
X1856392Y720750D01*
X1856517Y720500D01*
X1856767Y720250D01*
X1857058Y720083D01*
X1857350Y720000D01*
X1857642D01*
X1857933Y720083D01*
X1858183Y720208D01*
X1858392Y720375D01*
G01X1859533Y720500D02*
X1859783Y720208D01*
X1860117Y720042D01*
X1860492Y720000D01*
X1860825Y720042D01*
X1861158Y720250D01*
X1861367Y720500D01*
X1861408Y720750D01*
X1861325Y721042D01*
X1861033Y721250D01*
X1860742Y721333D01*
X1860367D01*
G01X1860742D02*
X1860992Y721458D01*
X1861200Y721667D01*
X1861283Y721917D01*
X1861200Y722167D01*
X1860992Y722375D01*
X1860617Y722500D01*
X1860242Y722458D01*
X1859867Y722292D01*
G01X1862633Y720500D02*
X1862883Y720208D01*
X1863217Y720042D01*
X1863592Y720000D01*
X1863925Y720042D01*
X1864258Y720250D01*
X1864467Y720500D01*
X1864508Y720750D01*
X1864425Y721042D01*
X1864133Y721250D01*
X1863842Y721333D01*
X1863467D01*
G01X1863842D02*
X1864092Y721458D01*
X1864300Y721667D01*
X1864383Y721917D01*
X1864300Y722167D01*
X1864092Y722375D01*
X1863717Y722500D01*
X1863342Y722458D01*
X1862967Y722292D01*
G01X1865942Y720292D02*
X1866233Y720083D01*
X1866567Y720000D01*
X1866900Y720083D01*
X1867192Y720333D01*
X1867400Y720708D01*
X1867483Y721083D01*
Y721542D01*
X1867400Y721917D01*
X1867192Y722250D01*
X1866942Y722417D01*
X1866650Y722500D01*
X1866317Y722417D01*
X1866067Y722250D01*
X1865900Y722000D01*
X1865817Y721667D01*
X1865900Y721375D01*
X1866108Y721083D01*
X1866358Y720917D01*
X1866650Y720875D01*
X1866983Y720958D01*
X1867233Y721167D01*
X1867483Y721542D01*
G01X1815208Y741767D02*
X1815083Y741517D01*
X1815000Y741225D01*
Y740892D01*
X1815125Y740517D01*
X1815333Y740225D01*
X1815583Y740017D01*
X1816000Y739850D01*
X1816375Y739808D01*
X1816750Y739892D01*
X1817000Y740017D01*
X1817250Y740267D01*
X1817417Y740558D01*
X1817500Y740850D01*
Y741142D01*
X1817417Y741433D01*
X1817292Y741683D01*
X1817125Y741892D01*
G01X1817000Y743033D02*
X1817292Y743283D01*
X1817458Y743617D01*
X1817500Y743992D01*
X1817458Y744325D01*
X1817250Y744658D01*
X1817000Y744867D01*
X1816750Y744908D01*
X1816458Y744825D01*
X1816250Y744533D01*
X1816167Y744242D01*
Y743867D01*
G01Y744242D02*
X1816042Y744492D01*
X1815833Y744700D01*
X1815583Y744783D01*
X1815333Y744700D01*
X1815125Y744492D01*
X1815000Y744117D01*
X1815042Y743742D01*
X1815208Y743367D01*
G01X1817000Y746133D02*
X1817292Y746383D01*
X1817458Y746717D01*
X1817500Y747092D01*
X1817458Y747425D01*
X1817250Y747758D01*
X1817000Y747967D01*
X1816750Y748008D01*
X1816458Y747925D01*
X1816250Y747633D01*
X1816167Y747342D01*
Y746967D01*
G01Y747342D02*
X1816042Y747592D01*
X1815833Y747800D01*
X1815583Y747883D01*
X1815333Y747800D01*
X1815125Y747592D01*
X1815000Y747217D01*
X1815042Y746842D01*
X1815208Y746467D01*
G01X1817000Y749233D02*
X1817292Y749483D01*
X1817458Y749817D01*
X1817500Y750192D01*
X1817458Y750525D01*
X1817250Y750858D01*
X1817000Y751067D01*
X1816750Y751108D01*
X1816458Y751025D01*
X1816250Y750733D01*
X1816167Y750442D01*
Y750067D01*
G01Y750442D02*
X1816042Y750692D01*
X1815833Y750900D01*
X1815583Y750983D01*
X1815333Y750900D01*
X1815125Y750692D01*
X1815000Y750317D01*
X1815042Y749942D01*
X1815208Y749567D01*
G01X1826117Y718809D02*
X1825867Y718934D01*
X1825575Y719017D01*
X1825242D01*
X1824867Y718892D01*
X1824575Y718684D01*
X1824367Y718434D01*
X1824200Y718017D01*
X1824158Y717642D01*
X1824242Y717267D01*
X1824367Y717017D01*
X1824617Y716767D01*
X1824908Y716600D01*
X1825200Y716517D01*
X1825492D01*
X1825783Y716600D01*
X1826033Y716725D01*
X1826242Y716892D01*
G01X1827383Y717017D02*
X1827633Y716725D01*
X1827967Y716559D01*
X1828342Y716517D01*
X1828675Y716559D01*
X1829008Y716767D01*
X1829217Y717017D01*
X1829258Y717267D01*
X1829175Y717559D01*
X1828883Y717767D01*
X1828592Y717850D01*
X1828217D01*
G01X1828592D02*
X1828842Y717975D01*
X1829050Y718184D01*
X1829133Y718434D01*
X1829050Y718684D01*
X1828842Y718892D01*
X1828467Y719017D01*
X1828092Y718975D01*
X1827717Y718809D01*
G01X1830483Y717017D02*
X1830733Y716725D01*
X1831067Y716559D01*
X1831442Y716517D01*
X1831775Y716559D01*
X1832108Y716767D01*
X1832317Y717017D01*
X1832358Y717267D01*
X1832275Y717559D01*
X1831983Y717767D01*
X1831692Y717850D01*
X1831317D01*
G01X1831692D02*
X1831942Y717975D01*
X1832150Y718184D01*
X1832233Y718434D01*
X1832150Y718684D01*
X1831942Y718892D01*
X1831567Y719017D01*
X1831192Y718975D01*
X1830817Y718809D01*
G01X1833583Y716892D02*
X1833833Y716684D01*
X1834125Y716559D01*
X1834500Y716517D01*
X1834875Y716600D01*
X1835167Y716767D01*
X1835375Y717059D01*
X1835417Y717392D01*
X1835333Y717725D01*
X1835125Y717934D01*
X1834833Y718100D01*
X1834542Y718142D01*
X1834250Y718100D01*
X1833875Y717934D01*
X1834000Y719017D01*
X1835125D01*
G01X1855828Y837162D02*
Y839662D01*
X1857412D01*
G01X1856828Y838454D02*
X1855828D01*
G01X1858887Y839662D02*
Y837162D01*
X1860553D01*
G01X1863653D02*
X1861987D01*
Y839662D01*
X1863653D01*
G01X1862987Y838454D02*
X1861987D01*
G01X1865003Y837162D02*
Y839662D01*
X1865837D01*
X1866170Y839537D01*
X1866420Y839370D01*
X1866628Y839120D01*
X1866795Y838829D01*
X1866837Y838412D01*
X1866795Y837995D01*
X1866628Y837704D01*
X1866420Y837454D01*
X1866170Y837287D01*
X1865837Y837162D01*
X1865003D01*
G01X1869020D02*
Y839662D01*
X1868520Y839162D01*
G01Y837162D02*
X1869520D01*
G01X1871328Y839245D02*
X1871578Y839495D01*
X1871870Y839620D01*
X1872203Y839662D01*
X1872620Y839579D01*
X1872912Y839370D01*
X1872995Y839120D01*
X1872953Y838870D01*
X1872787Y838662D01*
X1871953Y838245D01*
X1871578Y837954D01*
X1871328Y837537D01*
X1871245Y837162D01*
X1872995D01*
G01X1857411Y818809D02*
Y830009D01*
X1866211D01*
Y818809D01*
X1857411D01*
G01X1849608Y1030287D02*
Y1032787D01*
X1850649D01*
X1850983Y1032662D01*
X1851191Y1032495D01*
X1851274Y1032162D01*
X1851191Y1031829D01*
X1850941Y1031620D01*
X1850649Y1031495D01*
X1849608D01*
G01X1850649D02*
X1851274Y1030287D01*
G01X1852624Y1030787D02*
X1852874Y1030495D01*
X1853208Y1030329D01*
X1853583Y1030287D01*
X1853916Y1030329D01*
X1854249Y1030537D01*
X1854458Y1030787D01*
X1854499Y1031037D01*
X1854416Y1031329D01*
X1854124Y1031537D01*
X1853833Y1031620D01*
X1853458D01*
G01X1853833D02*
X1854083Y1031745D01*
X1854291Y1031954D01*
X1854374Y1032204D01*
X1854291Y1032454D01*
X1854083Y1032662D01*
X1853708Y1032787D01*
X1853333Y1032745D01*
X1852958Y1032579D01*
G01X1855933Y1030579D02*
X1856224Y1030370D01*
X1856558Y1030287D01*
X1856891Y1030370D01*
X1857183Y1030620D01*
X1857391Y1030995D01*
X1857474Y1031370D01*
Y1031829D01*
X1857391Y1032204D01*
X1857183Y1032537D01*
X1856933Y1032704D01*
X1856641Y1032787D01*
X1856308Y1032704D01*
X1856058Y1032537D01*
X1855891Y1032287D01*
X1855808Y1031954D01*
X1855891Y1031662D01*
X1856099Y1031370D01*
X1856349Y1031204D01*
X1856641Y1031162D01*
X1856974Y1031245D01*
X1857224Y1031454D01*
X1857474Y1031829D01*
G01X1859741Y1032787D02*
X1859408Y1032704D01*
X1859158Y1032495D01*
X1858991Y1032245D01*
X1858866Y1031912D01*
X1858824Y1031537D01*
X1858866Y1031162D01*
X1858991Y1030829D01*
X1859158Y1030579D01*
X1859408Y1030370D01*
X1859741Y1030287D01*
X1860074Y1030370D01*
X1860324Y1030579D01*
X1860491Y1030829D01*
X1860616Y1031162D01*
X1860658Y1031537D01*
X1860616Y1031912D01*
X1860491Y1032245D01*
X1860324Y1032495D01*
X1860074Y1032704D01*
X1859741Y1032787D01*
G01X1834933Y1032158D02*
X1832433D01*
Y1033199D01*
X1832558Y1033533D01*
X1832725Y1033741D01*
X1833058Y1033824D01*
X1833391Y1033741D01*
X1833600Y1033491D01*
X1833725Y1033199D01*
Y1032158D01*
G01Y1033199D02*
X1834933Y1033824D01*
G01X1834433Y1035174D02*
X1834725Y1035424D01*
X1834891Y1035758D01*
X1834933Y1036133D01*
X1834891Y1036466D01*
X1834683Y1036799D01*
X1834433Y1037008D01*
X1834183Y1037049D01*
X1833891Y1036966D01*
X1833683Y1036674D01*
X1833600Y1036383D01*
Y1036008D01*
G01Y1036383D02*
X1833475Y1036633D01*
X1833266Y1036841D01*
X1833016Y1036924D01*
X1832766Y1036841D01*
X1832558Y1036633D01*
X1832433Y1036258D01*
X1832475Y1035883D01*
X1832641Y1035508D01*
G01X1834641Y1038483D02*
X1834850Y1038774D01*
X1834933Y1039108D01*
X1834850Y1039441D01*
X1834600Y1039733D01*
X1834225Y1039941D01*
X1833850Y1040024D01*
X1833391D01*
X1833016Y1039941D01*
X1832683Y1039733D01*
X1832516Y1039483D01*
X1832433Y1039191D01*
X1832516Y1038858D01*
X1832683Y1038608D01*
X1832933Y1038441D01*
X1833266Y1038358D01*
X1833558Y1038441D01*
X1833850Y1038649D01*
X1834016Y1038899D01*
X1834058Y1039191D01*
X1833975Y1039524D01*
X1833766Y1039774D01*
X1833391Y1040024D01*
G01X1834933Y1042208D02*
X1834391Y1042291D01*
X1833933Y1042416D01*
X1833516Y1042583D01*
X1833058Y1042791D01*
X1832433Y1043124D01*
Y1041458D01*
G01X1836317Y1030500D02*
Y1033000D01*
X1837358D01*
X1837692Y1032875D01*
X1837900Y1032708D01*
X1837983Y1032375D01*
X1837900Y1032042D01*
X1837650Y1031833D01*
X1837358Y1031708D01*
X1836317D01*
G01X1837358D02*
X1837983Y1030500D01*
G01X1839333Y1031000D02*
X1839583Y1030708D01*
X1839917Y1030542D01*
X1840292Y1030500D01*
X1840625Y1030542D01*
X1840958Y1030750D01*
X1841167Y1031000D01*
X1841208Y1031250D01*
X1841125Y1031542D01*
X1840833Y1031750D01*
X1840542Y1031833D01*
X1840167D01*
G01X1840542D02*
X1840792Y1031958D01*
X1841000Y1032167D01*
X1841083Y1032417D01*
X1841000Y1032667D01*
X1840792Y1032875D01*
X1840417Y1033000D01*
X1840042Y1032958D01*
X1839667Y1032792D01*
G01X1842642Y1030792D02*
X1842933Y1030583D01*
X1843267Y1030500D01*
X1843600Y1030583D01*
X1843892Y1030833D01*
X1844100Y1031208D01*
X1844183Y1031583D01*
Y1032042D01*
X1844100Y1032417D01*
X1843892Y1032750D01*
X1843642Y1032917D01*
X1843350Y1033000D01*
X1843017Y1032917D01*
X1842767Y1032750D01*
X1842600Y1032500D01*
X1842517Y1032167D01*
X1842600Y1031875D01*
X1842808Y1031583D01*
X1843058Y1031417D01*
X1843350Y1031375D01*
X1843683Y1031458D01*
X1843933Y1031667D01*
X1844183Y1032042D01*
G01X1845742Y1030792D02*
X1846033Y1030583D01*
X1846367Y1030500D01*
X1846700Y1030583D01*
X1846992Y1030833D01*
X1847200Y1031208D01*
X1847283Y1031583D01*
Y1032042D01*
X1847200Y1032417D01*
X1846992Y1032750D01*
X1846742Y1032917D01*
X1846450Y1033000D01*
X1846117Y1032917D01*
X1845867Y1032750D01*
X1845700Y1032500D01*
X1845617Y1032167D01*
X1845700Y1031875D01*
X1845908Y1031583D01*
X1846158Y1031417D01*
X1846450Y1031375D01*
X1846783Y1031458D01*
X1847033Y1031667D01*
X1847283Y1032042D01*
G01X1831000Y1023217D02*
X1828500D01*
Y1024258D01*
X1828625Y1024592D01*
X1828792Y1024800D01*
X1829125Y1024883D01*
X1829458Y1024800D01*
X1829667Y1024550D01*
X1829792Y1024258D01*
Y1023217D01*
G01Y1024258D02*
X1831000Y1024883D01*
G01Y1027650D02*
X1828500D01*
X1830292Y1026108D01*
Y1028192D01*
G01X1828500Y1030250D02*
X1828583Y1029917D01*
X1828792Y1029667D01*
X1829042Y1029500D01*
X1829375Y1029375D01*
X1829750Y1029333D01*
X1830125Y1029375D01*
X1830458Y1029500D01*
X1830708Y1029667D01*
X1830917Y1029917D01*
X1831000Y1030250D01*
X1830917Y1030583D01*
X1830708Y1030833D01*
X1830458Y1031000D01*
X1830125Y1031125D01*
X1829750Y1031167D01*
X1829375Y1031125D01*
X1829042Y1031000D01*
X1828792Y1030833D01*
X1828583Y1030583D01*
X1828500Y1030250D01*
G01Y1033350D02*
X1828583Y1033017D01*
X1828792Y1032767D01*
X1829042Y1032600D01*
X1829375Y1032475D01*
X1829750Y1032433D01*
X1830125Y1032475D01*
X1830458Y1032600D01*
X1830708Y1032767D01*
X1830917Y1033017D01*
X1831000Y1033350D01*
X1830917Y1033683D01*
X1830708Y1033933D01*
X1830458Y1034100D01*
X1830125Y1034225D01*
X1829750Y1034267D01*
X1829375Y1034225D01*
X1829042Y1034100D01*
X1828792Y1033933D01*
X1828583Y1033683D01*
X1828500Y1033350D01*
G01X1844483Y1025700D02*
Y1028200D01*
X1845317D01*
X1845650Y1028075D01*
X1845900Y1027908D01*
X1846108Y1027658D01*
X1846275Y1027367D01*
X1846317Y1026950D01*
X1846275Y1026533D01*
X1846108Y1026242D01*
X1845900Y1025992D01*
X1845650Y1025825D01*
X1845317Y1025700D01*
X1844483D01*
G01X1848500D02*
Y1028200D01*
X1848000Y1027700D01*
G01Y1025700D02*
X1849000D01*
G01X1851600D02*
Y1028200D01*
X1851100Y1027700D01*
G01Y1025700D02*
X1852100D01*
G01X1851458Y1036779D02*
X1851208Y1036904D01*
X1850916Y1036987D01*
X1850583D01*
X1850208Y1036862D01*
X1849916Y1036654D01*
X1849708Y1036404D01*
X1849541Y1035987D01*
X1849499Y1035612D01*
X1849583Y1035237D01*
X1849708Y1034987D01*
X1849958Y1034737D01*
X1850249Y1034570D01*
X1850541Y1034487D01*
X1850833D01*
X1851124Y1034570D01*
X1851374Y1034695D01*
X1851583Y1034862D01*
G01X1853641Y1034487D02*
Y1036987D01*
X1853141Y1036487D01*
G01Y1034487D02*
X1854141D01*
G01X1856033Y1034779D02*
X1856324Y1034570D01*
X1856658Y1034487D01*
X1856991Y1034570D01*
X1857283Y1034820D01*
X1857491Y1035195D01*
X1857574Y1035570D01*
Y1036029D01*
X1857491Y1036404D01*
X1857283Y1036737D01*
X1857033Y1036904D01*
X1856741Y1036987D01*
X1856408Y1036904D01*
X1856158Y1036737D01*
X1855991Y1036487D01*
X1855908Y1036154D01*
X1855991Y1035862D01*
X1856199Y1035570D01*
X1856449Y1035404D01*
X1856741Y1035362D01*
X1857074Y1035445D01*
X1857324Y1035654D01*
X1857574Y1036029D01*
G01X1859841Y1034487D02*
Y1036987D01*
X1859341Y1036487D01*
G01Y1034487D02*
X1860341D01*
G01X1813250Y1069273D02*
X1817250D01*
Y1076673D01*
G01X1821350Y1081873D02*
X1825350D01*
Y1089273D01*
G01X1816650Y1081873D02*
X1820650D01*
Y1089273D01*
G01X1850223Y1038294D02*
Y1040794D01*
X1851264D01*
X1851598Y1040669D01*
X1851806Y1040502D01*
X1851889Y1040169D01*
X1851806Y1039836D01*
X1851556Y1039627D01*
X1851264Y1039502D01*
X1850223D01*
G01X1851264D02*
X1851889Y1038294D01*
G01X1853239Y1038794D02*
X1853489Y1038502D01*
X1853823Y1038336D01*
X1854198Y1038294D01*
X1854531Y1038336D01*
X1854864Y1038544D01*
X1855073Y1038794D01*
X1855114Y1039044D01*
X1855031Y1039336D01*
X1854739Y1039544D01*
X1854448Y1039627D01*
X1854073D01*
G01X1854448D02*
X1854698Y1039752D01*
X1854906Y1039961D01*
X1854989Y1040211D01*
X1854906Y1040461D01*
X1854698Y1040669D01*
X1854323Y1040794D01*
X1853948Y1040752D01*
X1853573Y1040586D01*
G01X1856548Y1038586D02*
X1856839Y1038377D01*
X1857173Y1038294D01*
X1857506Y1038377D01*
X1857798Y1038627D01*
X1858006Y1039002D01*
X1858089Y1039377D01*
Y1039836D01*
X1858006Y1040211D01*
X1857798Y1040544D01*
X1857548Y1040711D01*
X1857256Y1040794D01*
X1856923Y1040711D01*
X1856673Y1040544D01*
X1856506Y1040294D01*
X1856423Y1039961D01*
X1856506Y1039669D01*
X1856714Y1039377D01*
X1856964Y1039211D01*
X1857256Y1039169D01*
X1857589Y1039252D01*
X1857839Y1039461D01*
X1858089Y1039836D01*
G01X1860356Y1038294D02*
X1860648Y1038336D01*
X1860981Y1038461D01*
X1861189Y1038669D01*
X1861273Y1038961D01*
X1861189Y1039252D01*
X1860939Y1039502D01*
X1860564Y1039627D01*
X1860148D01*
X1859898Y1039711D01*
X1859689Y1039919D01*
X1859606Y1040211D01*
X1859731Y1040502D01*
X1860023Y1040711D01*
X1860356Y1040794D01*
X1860689Y1040711D01*
X1860981Y1040502D01*
X1861106Y1040211D01*
X1861023Y1039919D01*
X1860814Y1039711D01*
X1860564Y1039627D01*
X1860148D01*
X1859773Y1039502D01*
X1859523Y1039252D01*
X1859439Y1038961D01*
X1859523Y1038669D01*
X1859731Y1038461D01*
X1860064Y1038336D01*
X1860356Y1038294D01*
G01X1860630Y1073800D02*
X1874030D01*
G01X1860630Y1085200D02*
Y1073800D01*
G01X1851973Y1044686D02*
X1851723Y1044811D01*
X1851431Y1044894D01*
X1851098D01*
X1850723Y1044769D01*
X1850431Y1044561D01*
X1850223Y1044311D01*
X1850056Y1043894D01*
X1850014Y1043519D01*
X1850098Y1043144D01*
X1850223Y1042894D01*
X1850473Y1042644D01*
X1850764Y1042477D01*
X1851056Y1042394D01*
X1851348D01*
X1851639Y1042477D01*
X1851889Y1042602D01*
X1852098Y1042769D01*
G01X1854156Y1042394D02*
Y1044894D01*
X1853656Y1044394D01*
G01Y1042394D02*
X1854656D01*
G01X1856548Y1042686D02*
X1856839Y1042477D01*
X1857173Y1042394D01*
X1857506Y1042477D01*
X1857798Y1042727D01*
X1858006Y1043102D01*
X1858089Y1043477D01*
Y1043936D01*
X1858006Y1044311D01*
X1857798Y1044644D01*
X1857548Y1044811D01*
X1857256Y1044894D01*
X1856923Y1044811D01*
X1856673Y1044644D01*
X1856506Y1044394D01*
X1856423Y1044061D01*
X1856506Y1043769D01*
X1856714Y1043477D01*
X1856964Y1043311D01*
X1857256Y1043269D01*
X1857589Y1043352D01*
X1857839Y1043561D01*
X1858089Y1043936D01*
G01X1859564Y1044477D02*
X1859814Y1044727D01*
X1860106Y1044852D01*
X1860439Y1044894D01*
X1860856Y1044811D01*
X1861148Y1044602D01*
X1861231Y1044352D01*
X1861189Y1044102D01*
X1861023Y1043894D01*
X1860189Y1043477D01*
X1859814Y1043186D01*
X1859564Y1042769D01*
X1859481Y1042394D01*
X1861231D01*
G01X1833650Y1126973D02*
Y1130973D01*
X1826250D01*
G01X1824150Y1102173D02*
Y1098173D01*
X1831550D01*
G01X1854391Y1100787D02*
Y1096787D01*
X1861791D01*
G01X1842433Y1105341D02*
X1838433D01*
Y1097941D01*
G01X1860406Y1111294D02*
Y1115294D01*
X1853006D01*
G01X1846296Y1100813D02*
Y1096813D01*
X1853696D01*
G01X1836074Y1086995D02*
X1840074D01*
Y1094395D01*
G01X1834200Y1131220D02*
X1838200D01*
Y1138620D01*
G01X1874030Y1085200D02*
X1860630D01*
G01X1856896Y1088913D02*
X1840796D01*
G01X1856896Y1095913D02*
Y1088913D01*
G01X1840796Y1095913D02*
X1856896D01*
G01X1840796Y1088913D02*
Y1095913D01*
G01X1833350Y1090173D02*
X1817250D01*
G01X1833350Y1097173D02*
Y1090173D01*
G01X1817250Y1097173D02*
X1833350D01*
G01X1817250Y1090173D02*
Y1097173D01*
G01X1839977Y1129664D02*
X1859177D01*
Y1140864D01*
X1839977D01*
Y1129664D01*
X1840377D01*
G01X1837500Y1166017D02*
X1835000D01*
Y1167058D01*
X1835125Y1167392D01*
X1835292Y1167600D01*
X1835625Y1167683D01*
X1835958Y1167600D01*
X1836167Y1167350D01*
X1836292Y1167058D01*
Y1166017D01*
G01Y1167058D02*
X1837500Y1167683D01*
G01X1837125Y1169033D02*
X1837333Y1169283D01*
X1837458Y1169575D01*
X1837500Y1169950D01*
X1837417Y1170325D01*
X1837250Y1170617D01*
X1836958Y1170825D01*
X1836625Y1170867D01*
X1836292Y1170783D01*
X1836083Y1170575D01*
X1835917Y1170283D01*
X1835875Y1169992D01*
X1835917Y1169700D01*
X1836083Y1169325D01*
X1835000Y1169450D01*
Y1170575D01*
G01X1837208Y1172342D02*
X1837417Y1172633D01*
X1837500Y1172967D01*
X1837417Y1173300D01*
X1837167Y1173592D01*
X1836792Y1173800D01*
X1836417Y1173883D01*
X1835958D01*
X1835583Y1173800D01*
X1835250Y1173592D01*
X1835083Y1173342D01*
X1835000Y1173050D01*
X1835083Y1172717D01*
X1835250Y1172467D01*
X1835500Y1172300D01*
X1835833Y1172217D01*
X1836125Y1172300D01*
X1836417Y1172508D01*
X1836583Y1172758D01*
X1836625Y1173050D01*
X1836542Y1173383D01*
X1836333Y1173633D01*
X1835958Y1173883D01*
G01X1837208Y1175442D02*
X1837417Y1175733D01*
X1837500Y1176067D01*
X1837417Y1176400D01*
X1837167Y1176692D01*
X1836792Y1176900D01*
X1836417Y1176983D01*
X1835958D01*
X1835583Y1176900D01*
X1835250Y1176692D01*
X1835083Y1176442D01*
X1835000Y1176150D01*
X1835083Y1175817D01*
X1835250Y1175567D01*
X1835500Y1175400D01*
X1835833Y1175317D01*
X1836125Y1175400D01*
X1836417Y1175608D01*
X1836583Y1175858D01*
X1836625Y1176150D01*
X1836542Y1176483D01*
X1836333Y1176733D01*
X1835958Y1176983D01*
G01X1837700Y1179017D02*
X1835200D01*
Y1180058D01*
X1835325Y1180392D01*
X1835492Y1180600D01*
X1835825Y1180683D01*
X1836158Y1180600D01*
X1836367Y1180350D01*
X1836492Y1180058D01*
Y1179017D01*
G01Y1180058D02*
X1837700Y1180683D01*
G01X1837325Y1182033D02*
X1837533Y1182283D01*
X1837658Y1182575D01*
X1837700Y1182950D01*
X1837617Y1183325D01*
X1837450Y1183617D01*
X1837158Y1183825D01*
X1836825Y1183867D01*
X1836492Y1183783D01*
X1836283Y1183575D01*
X1836117Y1183283D01*
X1836075Y1182992D01*
X1836117Y1182700D01*
X1836283Y1182325D01*
X1835200Y1182450D01*
Y1183575D01*
G01X1837408Y1185342D02*
X1837617Y1185633D01*
X1837700Y1185967D01*
X1837617Y1186300D01*
X1837367Y1186592D01*
X1836992Y1186800D01*
X1836617Y1186883D01*
X1836158D01*
X1835783Y1186800D01*
X1835450Y1186592D01*
X1835283Y1186342D01*
X1835200Y1186050D01*
X1835283Y1185717D01*
X1835450Y1185467D01*
X1835700Y1185300D01*
X1836033Y1185217D01*
X1836325Y1185300D01*
X1836617Y1185508D01*
X1836783Y1185758D01*
X1836825Y1186050D01*
X1836742Y1186383D01*
X1836533Y1186633D01*
X1836158Y1186883D01*
G01X1836658Y1188358D02*
X1836367Y1188650D01*
X1836200Y1188900D01*
X1836117Y1189233D01*
X1836200Y1189525D01*
X1836367Y1189733D01*
X1836617Y1189900D01*
X1836908Y1189942D01*
X1837158Y1189900D01*
X1837408Y1189733D01*
X1837617Y1189483D01*
X1837700Y1189192D01*
X1837617Y1188858D01*
X1837367Y1188567D01*
X1836992Y1188400D01*
X1836575Y1188358D01*
X1836033Y1188442D01*
X1835742Y1188567D01*
X1835450Y1188775D01*
X1835242Y1189067D01*
X1835200Y1189358D01*
X1835283Y1189650D01*
X1835492Y1189858D01*
G01X1838431Y1149859D02*
X1834431D01*
Y1142459D01*
G01X1859892Y1166058D02*
X1859559Y1166100D01*
X1859267Y1166266D01*
X1859017Y1166516D01*
X1858850Y1166808D01*
X1858767Y1167141D01*
Y1167475D01*
X1858850Y1167808D01*
X1859017Y1168100D01*
X1859267Y1168350D01*
X1859559Y1168516D01*
X1859892Y1168558D01*
X1860225Y1168516D01*
X1860517Y1168350D01*
X1860767Y1168100D01*
X1860934Y1167808D01*
X1861017Y1167475D01*
Y1167141D01*
X1860934Y1166808D01*
X1860767Y1166516D01*
X1860517Y1166266D01*
X1860225Y1166100D01*
X1859892Y1166058D01*
G01X1860225Y1166725D02*
X1860725Y1166058D01*
G01X1862200Y1168141D02*
X1862450Y1168391D01*
X1862742Y1168516D01*
X1863075Y1168558D01*
X1863492Y1168475D01*
X1863784Y1168266D01*
X1863867Y1168016D01*
X1863825Y1167766D01*
X1863659Y1167558D01*
X1862825Y1167141D01*
X1862450Y1166850D01*
X1862200Y1166433D01*
X1862117Y1166058D01*
X1863867D01*
G01X1865384Y1166350D02*
X1865675Y1166141D01*
X1866009Y1166058D01*
X1866342Y1166141D01*
X1866634Y1166391D01*
X1866842Y1166766D01*
X1866925Y1167141D01*
Y1167600D01*
X1866842Y1167975D01*
X1866634Y1168308D01*
X1866384Y1168475D01*
X1866092Y1168558D01*
X1865759Y1168475D01*
X1865509Y1168308D01*
X1865342Y1168058D01*
X1865259Y1167725D01*
X1865342Y1167433D01*
X1865550Y1167141D01*
X1865800Y1166975D01*
X1866092Y1166933D01*
X1866425Y1167016D01*
X1866675Y1167225D01*
X1866925Y1167600D01*
G01X1868484Y1166350D02*
X1868775Y1166141D01*
X1869109Y1166058D01*
X1869442Y1166141D01*
X1869734Y1166391D01*
X1869942Y1166766D01*
X1870025Y1167141D01*
Y1167600D01*
X1869942Y1167975D01*
X1869734Y1168308D01*
X1869484Y1168475D01*
X1869192Y1168558D01*
X1868859Y1168475D01*
X1868609Y1168308D01*
X1868442Y1168058D01*
X1868359Y1167725D01*
X1868442Y1167433D01*
X1868650Y1167141D01*
X1868900Y1166975D01*
X1869192Y1166933D01*
X1869525Y1167016D01*
X1869775Y1167225D01*
X1870025Y1167600D01*
G01X1858042Y1164058D02*
Y1150058D01*
G01X1871042Y1164058D02*
X1858042D01*
G01Y1150058D02*
X1871042D01*
G01X1845827Y1166036D02*
X1845494Y1166078D01*
X1845202Y1166244D01*
X1844952Y1166494D01*
X1844785Y1166786D01*
X1844702Y1167119D01*
Y1167453D01*
X1844785Y1167786D01*
X1844952Y1168078D01*
X1845202Y1168328D01*
X1845494Y1168494D01*
X1845827Y1168536D01*
X1846160Y1168494D01*
X1846452Y1168328D01*
X1846702Y1168078D01*
X1846869Y1167786D01*
X1846952Y1167453D01*
Y1167119D01*
X1846869Y1166786D01*
X1846702Y1166494D01*
X1846452Y1166244D01*
X1846160Y1166078D01*
X1845827Y1166036D01*
G01X1846160Y1166703D02*
X1846660Y1166036D01*
G01X1848010Y1166536D02*
X1848260Y1166244D01*
X1848594Y1166078D01*
X1848969Y1166036D01*
X1849302Y1166078D01*
X1849635Y1166286D01*
X1849844Y1166536D01*
X1849885Y1166786D01*
X1849802Y1167078D01*
X1849510Y1167286D01*
X1849219Y1167369D01*
X1848844D01*
G01X1849219D02*
X1849469Y1167494D01*
X1849677Y1167703D01*
X1849760Y1167953D01*
X1849677Y1168203D01*
X1849469Y1168411D01*
X1849094Y1168536D01*
X1848719Y1168494D01*
X1848344Y1168328D01*
G01X1852027Y1168536D02*
X1851694Y1168453D01*
X1851444Y1168244D01*
X1851277Y1167994D01*
X1851152Y1167661D01*
X1851110Y1167286D01*
X1851152Y1166911D01*
X1851277Y1166578D01*
X1851444Y1166328D01*
X1851694Y1166119D01*
X1852027Y1166036D01*
X1852360Y1166119D01*
X1852610Y1166328D01*
X1852777Y1166578D01*
X1852902Y1166911D01*
X1852944Y1167286D01*
X1852902Y1167661D01*
X1852777Y1167994D01*
X1852610Y1168244D01*
X1852360Y1168453D01*
X1852027Y1168536D01*
G01X1855127D02*
X1854794Y1168453D01*
X1854544Y1168244D01*
X1854377Y1167994D01*
X1854252Y1167661D01*
X1854210Y1167286D01*
X1854252Y1166911D01*
X1854377Y1166578D01*
X1854544Y1166328D01*
X1854794Y1166119D01*
X1855127Y1166036D01*
X1855460Y1166119D01*
X1855710Y1166328D01*
X1855877Y1166578D01*
X1856002Y1166911D01*
X1856044Y1167286D01*
X1856002Y1167661D01*
X1855877Y1167994D01*
X1855710Y1168244D01*
X1855460Y1168453D01*
X1855127Y1168536D01*
G01X1843977Y1164036D02*
Y1150036D01*
G01X1856977Y1164036D02*
X1843977D01*
G01X1856977Y1150036D02*
Y1164036D01*
G01X1843977Y1150036D02*
X1856977D01*
G01X1840077Y1137264D02*
X1842177Y1135464D01*
X1840077Y1133264D01*
G01X1818400Y1165500D02*
X1818067Y1165542D01*
X1817775Y1165708D01*
X1817525Y1165958D01*
X1817358Y1166250D01*
X1817275Y1166583D01*
Y1166917D01*
X1817358Y1167250D01*
X1817525Y1167542D01*
X1817775Y1167792D01*
X1818067Y1167958D01*
X1818400Y1168000D01*
X1818733Y1167958D01*
X1819025Y1167792D01*
X1819275Y1167542D01*
X1819442Y1167250D01*
X1819525Y1166917D01*
Y1166583D01*
X1819442Y1166250D01*
X1819275Y1165958D01*
X1819025Y1165708D01*
X1818733Y1165542D01*
X1818400Y1165500D01*
G01X1818733Y1166167D02*
X1819233Y1165500D01*
G01X1820708Y1166542D02*
X1821000Y1166833D01*
X1821250Y1167000D01*
X1821583Y1167083D01*
X1821875Y1167000D01*
X1822083Y1166833D01*
X1822250Y1166583D01*
X1822292Y1166292D01*
X1822250Y1166042D01*
X1822083Y1165792D01*
X1821833Y1165583D01*
X1821542Y1165500D01*
X1821208Y1165583D01*
X1820917Y1165833D01*
X1820750Y1166208D01*
X1820708Y1166625D01*
X1820792Y1167167D01*
X1820917Y1167458D01*
X1821125Y1167750D01*
X1821417Y1167958D01*
X1821708Y1168000D01*
X1822000Y1167917D01*
X1822208Y1167708D01*
G01X1823808Y1167583D02*
X1824058Y1167833D01*
X1824350Y1167958D01*
X1824683Y1168000D01*
X1825100Y1167917D01*
X1825392Y1167708D01*
X1825475Y1167458D01*
X1825433Y1167208D01*
X1825267Y1167000D01*
X1824433Y1166583D01*
X1824058Y1166292D01*
X1823808Y1165875D01*
X1823725Y1165500D01*
X1825475D01*
G01X1842000Y1166017D02*
X1839500D01*
Y1167058D01*
X1839625Y1167392D01*
X1839792Y1167600D01*
X1840125Y1167683D01*
X1840458Y1167600D01*
X1840667Y1167350D01*
X1840792Y1167058D01*
Y1166017D01*
G01Y1167058D02*
X1842000Y1167683D01*
G01X1841500Y1169033D02*
X1841792Y1169283D01*
X1841958Y1169617D01*
X1842000Y1169992D01*
X1841958Y1170325D01*
X1841750Y1170658D01*
X1841500Y1170867D01*
X1841250Y1170908D01*
X1840958Y1170825D01*
X1840750Y1170533D01*
X1840667Y1170242D01*
Y1169867D01*
G01Y1170242D02*
X1840542Y1170492D01*
X1840333Y1170700D01*
X1840083Y1170783D01*
X1839833Y1170700D01*
X1839625Y1170492D01*
X1839500Y1170117D01*
X1839542Y1169742D01*
X1839708Y1169367D01*
G01X1839917Y1172258D02*
X1839667Y1172508D01*
X1839542Y1172800D01*
X1839500Y1173133D01*
X1839583Y1173550D01*
X1839792Y1173842D01*
X1840042Y1173925D01*
X1840292Y1173883D01*
X1840500Y1173717D01*
X1840917Y1172883D01*
X1841208Y1172508D01*
X1841625Y1172258D01*
X1842000Y1172175D01*
Y1173925D01*
G01X1840958Y1175358D02*
X1840667Y1175650D01*
X1840500Y1175900D01*
X1840417Y1176233D01*
X1840500Y1176525D01*
X1840667Y1176733D01*
X1840917Y1176900D01*
X1841208Y1176942D01*
X1841458Y1176900D01*
X1841708Y1176733D01*
X1841917Y1176483D01*
X1842000Y1176192D01*
X1841917Y1175858D01*
X1841667Y1175567D01*
X1841292Y1175400D01*
X1840875Y1175358D01*
X1840333Y1175442D01*
X1840042Y1175567D01*
X1839750Y1175775D01*
X1839542Y1176067D01*
X1839500Y1176358D01*
X1839583Y1176650D01*
X1839792Y1176858D01*
G01X1823208Y1193767D02*
X1823083Y1193517D01*
X1823000Y1193225D01*
Y1192892D01*
X1823125Y1192517D01*
X1823333Y1192225D01*
X1823583Y1192017D01*
X1824000Y1191850D01*
X1824375Y1191808D01*
X1824750Y1191892D01*
X1825000Y1192017D01*
X1825250Y1192267D01*
X1825417Y1192558D01*
X1825500Y1192850D01*
Y1193142D01*
X1825417Y1193433D01*
X1825292Y1193683D01*
X1825125Y1193892D01*
G01X1825500Y1195950D02*
X1823000D01*
X1823500Y1195450D01*
G01X1825500D02*
Y1196450D01*
G01Y1198967D02*
X1824958Y1199050D01*
X1824500Y1199175D01*
X1824083Y1199342D01*
X1823625Y1199550D01*
X1823000Y1199883D01*
Y1198217D01*
G01X1825125Y1201233D02*
X1825333Y1201483D01*
X1825458Y1201775D01*
X1825500Y1202150D01*
X1825417Y1202525D01*
X1825250Y1202817D01*
X1824958Y1203025D01*
X1824625Y1203067D01*
X1824292Y1202983D01*
X1824083Y1202775D01*
X1823917Y1202483D01*
X1823875Y1202192D01*
X1823917Y1201900D01*
X1824083Y1201525D01*
X1823000Y1201650D01*
Y1202775D01*
G01X1819208Y1193767D02*
X1819083Y1193517D01*
X1819000Y1193225D01*
Y1192892D01*
X1819125Y1192517D01*
X1819333Y1192225D01*
X1819583Y1192017D01*
X1820000Y1191850D01*
X1820375Y1191808D01*
X1820750Y1191892D01*
X1821000Y1192017D01*
X1821250Y1192267D01*
X1821417Y1192558D01*
X1821500Y1192850D01*
Y1193142D01*
X1821417Y1193433D01*
X1821292Y1193683D01*
X1821125Y1193892D01*
G01X1821500Y1195950D02*
X1819000D01*
X1819500Y1195450D01*
G01X1821500D02*
Y1196450D01*
G01Y1198967D02*
X1820958Y1199050D01*
X1820500Y1199175D01*
X1820083Y1199342D01*
X1819625Y1199550D01*
X1819000Y1199883D01*
Y1198217D01*
G01X1821500Y1202650D02*
X1819000D01*
X1820792Y1201108D01*
Y1203192D01*
G01X1837500Y1193017D02*
X1835000D01*
Y1194058D01*
X1835125Y1194392D01*
X1835292Y1194600D01*
X1835625Y1194683D01*
X1835958Y1194600D01*
X1836167Y1194350D01*
X1836292Y1194058D01*
Y1193017D01*
G01Y1194058D02*
X1837500Y1194683D01*
G01X1837000Y1196033D02*
X1837292Y1196283D01*
X1837458Y1196617D01*
X1837500Y1196992D01*
X1837458Y1197325D01*
X1837250Y1197658D01*
X1837000Y1197867D01*
X1836750Y1197908D01*
X1836458Y1197825D01*
X1836250Y1197533D01*
X1836167Y1197242D01*
Y1196867D01*
G01Y1197242D02*
X1836042Y1197492D01*
X1835833Y1197700D01*
X1835583Y1197783D01*
X1835333Y1197700D01*
X1835125Y1197492D01*
X1835000Y1197117D01*
X1835042Y1196742D01*
X1835208Y1196367D01*
G01X1837000Y1199133D02*
X1837292Y1199383D01*
X1837458Y1199717D01*
X1837500Y1200092D01*
X1837458Y1200425D01*
X1837250Y1200758D01*
X1837000Y1200967D01*
X1836750Y1201008D01*
X1836458Y1200925D01*
X1836250Y1200633D01*
X1836167Y1200342D01*
Y1199967D01*
G01Y1200342D02*
X1836042Y1200592D01*
X1835833Y1200800D01*
X1835583Y1200883D01*
X1835333Y1200800D01*
X1835125Y1200592D01*
X1835000Y1200217D01*
X1835042Y1199842D01*
X1835208Y1199467D01*
G01X1837000Y1202233D02*
X1837292Y1202483D01*
X1837458Y1202817D01*
X1837500Y1203192D01*
X1837458Y1203525D01*
X1837250Y1203858D01*
X1837000Y1204067D01*
X1836750Y1204108D01*
X1836458Y1204025D01*
X1836250Y1203733D01*
X1836167Y1203442D01*
Y1203067D01*
G01Y1203442D02*
X1836042Y1203692D01*
X1835833Y1203900D01*
X1835583Y1203983D01*
X1835333Y1203900D01*
X1835125Y1203692D01*
X1835000Y1203317D01*
X1835042Y1202942D01*
X1835208Y1202567D01*
G01X1815208Y1193767D02*
X1815083Y1193517D01*
X1815000Y1193225D01*
Y1192892D01*
X1815125Y1192517D01*
X1815333Y1192225D01*
X1815583Y1192017D01*
X1816000Y1191850D01*
X1816375Y1191808D01*
X1816750Y1191892D01*
X1817000Y1192017D01*
X1817250Y1192267D01*
X1817417Y1192558D01*
X1817500Y1192850D01*
Y1193142D01*
X1817417Y1193433D01*
X1817292Y1193683D01*
X1817125Y1193892D01*
G01X1817500Y1195950D02*
X1815000D01*
X1815500Y1195450D01*
G01X1817500D02*
Y1196450D01*
G01Y1198967D02*
X1816958Y1199050D01*
X1816500Y1199175D01*
X1816083Y1199342D01*
X1815625Y1199550D01*
X1815000Y1199883D01*
Y1198217D01*
G01X1817500Y1202067D02*
X1816958Y1202150D01*
X1816500Y1202275D01*
X1816083Y1202442D01*
X1815625Y1202650D01*
X1815000Y1202983D01*
Y1201317D01*
G01X1857411Y1271565D02*
Y1282765D01*
X1866211D01*
Y1271565D01*
X1857411D01*
G01X1852728Y1285665D02*
Y1288165D01*
X1853769D01*
X1854103Y1288040D01*
X1854311Y1287873D01*
X1854394Y1287540D01*
X1854311Y1287207D01*
X1854061Y1286998D01*
X1853769Y1286873D01*
X1852728D01*
G01X1853769D02*
X1854394Y1285665D01*
G01X1855828Y1288165D02*
Y1285665D01*
X1857494D01*
G01X1860594D02*
X1858928D01*
Y1288165D01*
X1860594D01*
G01X1859928Y1286957D02*
X1858928D01*
G01X1861944Y1285665D02*
Y1288165D01*
X1862778D01*
X1863111Y1288040D01*
X1863361Y1287873D01*
X1863569Y1287623D01*
X1863736Y1287332D01*
X1863778Y1286915D01*
X1863736Y1286498D01*
X1863569Y1286207D01*
X1863361Y1285957D01*
X1863111Y1285790D01*
X1862778Y1285665D01*
X1861944D01*
G01X1865044Y1286165D02*
X1865294Y1285873D01*
X1865628Y1285707D01*
X1866003Y1285665D01*
X1866336Y1285707D01*
X1866669Y1285915D01*
X1866878Y1286165D01*
X1866919Y1286415D01*
X1866836Y1286707D01*
X1866544Y1286915D01*
X1866253Y1286998D01*
X1865878D01*
G01X1866253D02*
X1866503Y1287123D01*
X1866711Y1287332D01*
X1866794Y1287582D01*
X1866711Y1287832D01*
X1866503Y1288040D01*
X1866128Y1288165D01*
X1865753Y1288123D01*
X1865378Y1287957D01*
G01X1868269Y1286707D02*
X1868561Y1286998D01*
X1868811Y1287165D01*
X1869144Y1287248D01*
X1869436Y1287165D01*
X1869644Y1286998D01*
X1869811Y1286748D01*
X1869853Y1286457D01*
X1869811Y1286207D01*
X1869644Y1285957D01*
X1869394Y1285748D01*
X1869103Y1285665D01*
X1868769Y1285748D01*
X1868478Y1285998D01*
X1868311Y1286373D01*
X1868269Y1286790D01*
X1868353Y1287332D01*
X1868478Y1287623D01*
X1868686Y1287915D01*
X1868978Y1288123D01*
X1869269Y1288165D01*
X1869561Y1288082D01*
X1869769Y1287873D01*
G01X1885856Y221492D02*
X1890906D01*
Y320192D01*
X1915556D01*
Y135792D01*
X1890906D01*
Y194492D01*
X1885856D01*
Y221492D01*
G01X1879108Y160184D02*
X1878858Y160309D01*
X1878566Y160392D01*
X1878233D01*
X1877858Y160267D01*
X1877566Y160059D01*
X1877358Y159809D01*
X1877191Y159392D01*
X1877149Y159017D01*
X1877233Y158642D01*
X1877358Y158392D01*
X1877608Y158142D01*
X1877899Y157975D01*
X1878191Y157892D01*
X1878483D01*
X1878774Y157975D01*
X1879024Y158100D01*
X1879233Y158267D01*
G01X1881791Y157892D02*
Y160392D01*
X1880249Y158600D01*
X1882333D01*
G01X1883683Y158184D02*
X1883974Y157975D01*
X1884308Y157892D01*
X1884641Y157975D01*
X1884933Y158225D01*
X1885141Y158600D01*
X1885224Y158975D01*
Y159434D01*
X1885141Y159809D01*
X1884933Y160142D01*
X1884683Y160309D01*
X1884391Y160392D01*
X1884058Y160309D01*
X1883808Y160142D01*
X1883641Y159892D01*
X1883558Y159559D01*
X1883641Y159267D01*
X1883849Y158975D01*
X1884099Y158809D01*
X1884391Y158767D01*
X1884724Y158850D01*
X1884974Y159059D01*
X1885224Y159434D01*
G01X1887991Y157892D02*
Y160392D01*
X1886449Y158600D01*
X1888533D01*
G01X1879267Y163792D02*
X1879017Y163917D01*
X1878725Y164000D01*
X1878392D01*
X1878017Y163875D01*
X1877725Y163667D01*
X1877517Y163417D01*
X1877350Y163000D01*
X1877308Y162625D01*
X1877392Y162250D01*
X1877517Y162000D01*
X1877767Y161750D01*
X1878058Y161583D01*
X1878350Y161500D01*
X1878642D01*
X1878933Y161583D01*
X1879183Y161708D01*
X1879392Y161875D01*
G01X1881950Y161500D02*
Y164000D01*
X1880408Y162208D01*
X1882492D01*
G01X1883842Y161792D02*
X1884133Y161583D01*
X1884467Y161500D01*
X1884800Y161583D01*
X1885092Y161833D01*
X1885300Y162208D01*
X1885383Y162583D01*
Y163042D01*
X1885300Y163417D01*
X1885092Y163750D01*
X1884842Y163917D01*
X1884550Y164000D01*
X1884217Y163917D01*
X1883967Y163750D01*
X1883800Y163500D01*
X1883717Y163167D01*
X1883800Y162875D01*
X1884008Y162583D01*
X1884258Y162417D01*
X1884550Y162375D01*
X1884883Y162458D01*
X1885133Y162667D01*
X1885383Y163042D01*
G01X1886733Y162000D02*
X1886983Y161708D01*
X1887317Y161542D01*
X1887692Y161500D01*
X1888025Y161542D01*
X1888358Y161750D01*
X1888567Y162000D01*
X1888608Y162250D01*
X1888525Y162542D01*
X1888233Y162750D01*
X1887942Y162833D01*
X1887567D01*
G01X1887942D02*
X1888192Y162958D01*
X1888400Y163167D01*
X1888483Y163417D01*
X1888400Y163667D01*
X1888192Y163875D01*
X1887817Y164000D01*
X1887442Y163958D01*
X1887067Y163792D01*
G01X1874900Y166017D02*
X1872400D01*
Y167058D01*
X1872525Y167392D01*
X1872692Y167600D01*
X1873025Y167683D01*
X1873358Y167600D01*
X1873567Y167350D01*
X1873692Y167058D01*
Y166017D01*
G01Y167058D02*
X1874900Y167683D01*
G01X1874608Y169242D02*
X1874817Y169533D01*
X1874900Y169867D01*
X1874817Y170200D01*
X1874567Y170492D01*
X1874192Y170700D01*
X1873817Y170783D01*
X1873358D01*
X1872983Y170700D01*
X1872650Y170492D01*
X1872483Y170242D01*
X1872400Y169950D01*
X1872483Y169617D01*
X1872650Y169367D01*
X1872900Y169200D01*
X1873233Y169117D01*
X1873525Y169200D01*
X1873817Y169408D01*
X1873983Y169658D01*
X1874025Y169950D01*
X1873942Y170283D01*
X1873733Y170533D01*
X1873358Y170783D01*
G01X1874400Y172133D02*
X1874692Y172383D01*
X1874858Y172717D01*
X1874900Y173092D01*
X1874858Y173425D01*
X1874650Y173758D01*
X1874400Y173967D01*
X1874150Y174008D01*
X1873858Y173925D01*
X1873650Y173633D01*
X1873567Y173342D01*
Y172967D01*
G01Y173342D02*
X1873442Y173592D01*
X1873233Y173800D01*
X1872983Y173883D01*
X1872733Y173800D01*
X1872525Y173592D01*
X1872400Y173217D01*
X1872442Y172842D01*
X1872608Y172467D01*
G01X1874525Y175233D02*
X1874733Y175483D01*
X1874858Y175775D01*
X1874900Y176150D01*
X1874817Y176525D01*
X1874650Y176817D01*
X1874358Y177025D01*
X1874025Y177067D01*
X1873692Y176983D01*
X1873483Y176775D01*
X1873317Y176483D01*
X1873275Y176192D01*
X1873317Y175900D01*
X1873483Y175525D01*
X1872400Y175650D01*
Y176775D01*
G01X1876900Y185544D02*
X1880900D01*
Y192944D01*
G01X1862817Y193800D02*
Y196300D01*
X1863858D01*
X1864192Y196175D01*
X1864400Y196008D01*
X1864483Y195675D01*
X1864400Y195342D01*
X1864150Y195133D01*
X1863858Y195008D01*
X1862817D01*
G01X1863858D02*
X1864483Y193800D01*
G01X1866042Y194092D02*
X1866333Y193883D01*
X1866667Y193800D01*
X1867000Y193883D01*
X1867292Y194133D01*
X1867500Y194508D01*
X1867583Y194883D01*
Y195342D01*
X1867500Y195717D01*
X1867292Y196050D01*
X1867042Y196217D01*
X1866750Y196300D01*
X1866417Y196217D01*
X1866167Y196050D01*
X1866000Y195800D01*
X1865917Y195467D01*
X1866000Y195175D01*
X1866208Y194883D01*
X1866458Y194717D01*
X1866750Y194675D01*
X1867083Y194758D01*
X1867333Y194967D01*
X1867583Y195342D01*
G01X1870350Y193800D02*
Y196300D01*
X1868808Y194508D01*
X1870892D01*
G01X1872158Y195883D02*
X1872408Y196133D01*
X1872700Y196258D01*
X1873033Y196300D01*
X1873450Y196217D01*
X1873742Y196008D01*
X1873825Y195758D01*
X1873783Y195508D01*
X1873617Y195300D01*
X1872783Y194883D01*
X1872408Y194592D01*
X1872158Y194175D01*
X1872075Y193800D01*
X1873825D01*
G01X1865500Y167850D02*
X1865458Y167517D01*
X1865292Y167225D01*
X1865042Y166975D01*
X1864750Y166808D01*
X1864417Y166725D01*
X1864083D01*
X1863750Y166808D01*
X1863458Y166975D01*
X1863208Y167225D01*
X1863042Y167517D01*
X1863000Y167850D01*
X1863042Y168183D01*
X1863208Y168475D01*
X1863458Y168725D01*
X1863750Y168892D01*
X1864083Y168975D01*
X1864417D01*
X1864750Y168892D01*
X1865042Y168725D01*
X1865292Y168475D01*
X1865458Y168183D01*
X1865500Y167850D01*
G01X1864833Y168183D02*
X1865500Y168683D01*
G01X1863417Y170158D02*
X1863167Y170408D01*
X1863042Y170700D01*
X1863000Y171033D01*
X1863083Y171450D01*
X1863292Y171742D01*
X1863542Y171825D01*
X1863792Y171783D01*
X1864000Y171617D01*
X1864417Y170783D01*
X1864708Y170408D01*
X1865125Y170158D01*
X1865500Y170075D01*
Y171825D01*
G01Y174050D02*
X1863000D01*
X1863500Y173550D01*
G01X1865500D02*
Y174550D01*
G01Y177150D02*
X1863000D01*
X1863500Y176650D01*
G01X1865500D02*
Y177650D01*
G01X1862117Y167875D02*
Y179275D01*
G01X1883969Y223261D02*
X1864769D01*
Y212061D01*
X1883969D01*
Y223261D01*
X1883569D01*
G01X1871334Y166017D02*
X1868834D01*
Y167058D01*
X1868959Y167392D01*
X1869126Y167600D01*
X1869459Y167683D01*
X1869792Y167600D01*
X1870001Y167350D01*
X1870126Y167058D01*
Y166017D01*
G01Y167058D02*
X1871334Y167683D01*
G01X1871042Y169242D02*
X1871251Y169533D01*
X1871334Y169867D01*
X1871251Y170200D01*
X1871001Y170492D01*
X1870626Y170700D01*
X1870251Y170783D01*
X1869792D01*
X1869417Y170700D01*
X1869084Y170492D01*
X1868917Y170242D01*
X1868834Y169950D01*
X1868917Y169617D01*
X1869084Y169367D01*
X1869334Y169200D01*
X1869667Y169117D01*
X1869959Y169200D01*
X1870251Y169408D01*
X1870417Y169658D01*
X1870459Y169950D01*
X1870376Y170283D01*
X1870167Y170533D01*
X1869792Y170783D01*
G01X1870834Y172133D02*
X1871126Y172383D01*
X1871292Y172717D01*
X1871334Y173092D01*
X1871292Y173425D01*
X1871084Y173758D01*
X1870834Y173967D01*
X1870584Y174008D01*
X1870292Y173925D01*
X1870084Y173633D01*
X1870001Y173342D01*
Y172967D01*
G01Y173342D02*
X1869876Y173592D01*
X1869667Y173800D01*
X1869417Y173883D01*
X1869167Y173800D01*
X1868959Y173592D01*
X1868834Y173217D01*
X1868876Y172842D01*
X1869042Y172467D01*
G01X1871042Y175442D02*
X1871251Y175733D01*
X1871334Y176067D01*
X1871251Y176400D01*
X1871001Y176692D01*
X1870626Y176900D01*
X1870251Y176983D01*
X1869792D01*
X1869417Y176900D01*
X1869084Y176692D01*
X1868917Y176442D01*
X1868834Y176150D01*
X1868917Y175817D01*
X1869084Y175567D01*
X1869334Y175400D01*
X1869667Y175317D01*
X1869959Y175400D01*
X1870251Y175608D01*
X1870417Y175858D01*
X1870459Y176150D01*
X1870376Y176483D01*
X1870167Y176733D01*
X1869792Y176983D01*
G01X1864236Y199953D02*
X1863986Y200078D01*
X1863694Y200161D01*
X1863361D01*
X1862986Y200036D01*
X1862694Y199828D01*
X1862486Y199578D01*
X1862319Y199161D01*
X1862277Y198786D01*
X1862361Y198411D01*
X1862486Y198161D01*
X1862736Y197911D01*
X1863027Y197744D01*
X1863319Y197661D01*
X1863611D01*
X1863902Y197744D01*
X1864152Y197869D01*
X1864361Y198036D01*
G01X1865502D02*
X1865752Y197828D01*
X1866044Y197703D01*
X1866419Y197661D01*
X1866794Y197744D01*
X1867086Y197911D01*
X1867294Y198203D01*
X1867336Y198536D01*
X1867252Y198869D01*
X1867044Y199078D01*
X1866752Y199244D01*
X1866461Y199286D01*
X1866169Y199244D01*
X1865794Y199078D01*
X1865919Y200161D01*
X1867044D01*
G01X1869519D02*
X1869186Y200078D01*
X1868936Y199869D01*
X1868769Y199619D01*
X1868644Y199286D01*
X1868602Y198911D01*
X1868644Y198536D01*
X1868769Y198203D01*
X1868936Y197953D01*
X1869186Y197744D01*
X1869519Y197661D01*
X1869852Y197744D01*
X1870102Y197953D01*
X1870269Y198203D01*
X1870394Y198536D01*
X1870436Y198911D01*
X1870394Y199286D01*
X1870269Y199619D01*
X1870102Y199869D01*
X1869852Y200078D01*
X1869519Y200161D01*
G01X1871702Y198161D02*
X1871952Y197869D01*
X1872286Y197703D01*
X1872661Y197661D01*
X1872994Y197703D01*
X1873327Y197911D01*
X1873536Y198161D01*
X1873577Y198411D01*
X1873494Y198703D01*
X1873202Y198911D01*
X1872911Y198994D01*
X1872536D01*
G01X1872911D02*
X1873161Y199119D01*
X1873369Y199328D01*
X1873452Y199578D01*
X1873369Y199828D01*
X1873161Y200036D01*
X1872786Y200161D01*
X1872411Y200119D01*
X1872036Y199953D01*
G01X1876208Y167767D02*
X1876083Y167517D01*
X1876000Y167225D01*
Y166892D01*
X1876125Y166517D01*
X1876333Y166225D01*
X1876583Y166017D01*
X1877000Y165850D01*
X1877375Y165808D01*
X1877750Y165892D01*
X1878000Y166017D01*
X1878250Y166267D01*
X1878417Y166558D01*
X1878500Y166850D01*
Y167142D01*
X1878417Y167433D01*
X1878292Y167683D01*
X1878125Y167892D01*
G01X1878500Y170450D02*
X1876000D01*
X1877792Y168908D01*
Y170992D01*
G01X1878208Y172342D02*
X1878417Y172633D01*
X1878500Y172967D01*
X1878417Y173300D01*
X1878167Y173592D01*
X1877792Y173800D01*
X1877417Y173883D01*
X1876958D01*
X1876583Y173800D01*
X1876250Y173592D01*
X1876083Y173342D01*
X1876000Y173050D01*
X1876083Y172717D01*
X1876250Y172467D01*
X1876500Y172300D01*
X1876833Y172217D01*
X1877125Y172300D01*
X1877417Y172508D01*
X1877583Y172758D01*
X1877625Y173050D01*
X1877542Y173383D01*
X1877333Y173633D01*
X1876958Y173883D01*
G01X1878500Y176067D02*
X1877958Y176150D01*
X1877500Y176275D01*
X1877083Y176442D01*
X1876625Y176650D01*
X1876000Y176983D01*
Y175317D01*
G01X1887000Y255517D02*
X1884500D01*
Y256558D01*
X1884625Y256892D01*
X1884792Y257100D01*
X1885125Y257183D01*
X1885458Y257100D01*
X1885667Y256850D01*
X1885792Y256558D01*
Y255517D01*
G01Y256558D02*
X1887000Y257183D01*
G01X1886708Y258742D02*
X1886917Y259033D01*
X1887000Y259367D01*
X1886917Y259700D01*
X1886667Y259992D01*
X1886292Y260200D01*
X1885917Y260283D01*
X1885458D01*
X1885083Y260200D01*
X1884750Y259992D01*
X1884583Y259742D01*
X1884500Y259450D01*
X1884583Y259117D01*
X1884750Y258867D01*
X1885000Y258700D01*
X1885333Y258617D01*
X1885625Y258700D01*
X1885917Y258908D01*
X1886083Y259158D01*
X1886125Y259450D01*
X1886042Y259783D01*
X1885833Y260033D01*
X1885458Y260283D01*
G01X1886500Y261633D02*
X1886792Y261883D01*
X1886958Y262217D01*
X1887000Y262592D01*
X1886958Y262925D01*
X1886750Y263258D01*
X1886500Y263467D01*
X1886250Y263508D01*
X1885958Y263425D01*
X1885750Y263133D01*
X1885667Y262842D01*
Y262467D01*
G01Y262842D02*
X1885542Y263092D01*
X1885333Y263300D01*
X1885083Y263383D01*
X1884833Y263300D01*
X1884625Y263092D01*
X1884500Y262717D01*
X1884542Y262342D01*
X1884708Y261967D01*
G01X1887000Y266150D02*
X1884500D01*
X1886292Y264608D01*
Y266692D01*
G01X1881169Y253961D02*
X1889169D01*
Y236361D01*
X1881169D01*
Y253961D01*
G01X1879469Y236161D02*
X1873969D01*
G01X1879469Y244161D02*
Y236161D01*
G01X1873969Y244161D02*
X1879469D01*
G01X1861869D02*
X1867369D01*
G01X1861869Y236161D02*
Y244161D01*
G01X1867369Y236161D02*
X1861869D01*
G01X1887500Y224850D02*
X1887458Y224517D01*
X1887292Y224225D01*
X1887042Y223975D01*
X1886750Y223808D01*
X1886417Y223725D01*
X1886083D01*
X1885750Y223808D01*
X1885458Y223975D01*
X1885208Y224225D01*
X1885042Y224517D01*
X1885000Y224850D01*
X1885042Y225183D01*
X1885208Y225475D01*
X1885458Y225725D01*
X1885750Y225892D01*
X1886083Y225975D01*
X1886417D01*
X1886750Y225892D01*
X1887042Y225725D01*
X1887292Y225475D01*
X1887458Y225183D01*
X1887500Y224850D01*
G01X1886833Y225183D02*
X1887500Y225683D01*
G01X1885417Y227158D02*
X1885167Y227408D01*
X1885042Y227700D01*
X1885000Y228033D01*
X1885083Y228450D01*
X1885292Y228742D01*
X1885542Y228825D01*
X1885792Y228783D01*
X1886000Y228617D01*
X1886417Y227783D01*
X1886708Y227408D01*
X1887125Y227158D01*
X1887500Y227075D01*
Y228825D01*
G01X1885000Y231050D02*
X1885083Y230717D01*
X1885292Y230467D01*
X1885542Y230300D01*
X1885875Y230175D01*
X1886250Y230133D01*
X1886625Y230175D01*
X1886958Y230300D01*
X1887208Y230467D01*
X1887417Y230717D01*
X1887500Y231050D01*
X1887417Y231383D01*
X1887208Y231633D01*
X1886958Y231800D01*
X1886625Y231925D01*
X1886250Y231967D01*
X1885875Y231925D01*
X1885542Y231800D01*
X1885292Y231633D01*
X1885083Y231383D01*
X1885000Y231050D01*
G01X1887208Y233442D02*
X1887417Y233733D01*
X1887500Y234067D01*
X1887417Y234400D01*
X1887167Y234692D01*
X1886792Y234900D01*
X1886417Y234983D01*
X1885958D01*
X1885583Y234900D01*
X1885250Y234692D01*
X1885083Y234442D01*
X1885000Y234150D01*
X1885083Y233817D01*
X1885250Y233567D01*
X1885500Y233400D01*
X1885833Y233317D01*
X1886125Y233400D01*
X1886417Y233608D01*
X1886583Y233858D01*
X1886625Y234150D01*
X1886542Y234483D01*
X1886333Y234733D01*
X1885958Y234983D01*
G01X1883869Y215661D02*
X1881769Y217461D01*
X1883869Y219661D01*
G01X1878208Y281767D02*
X1878083Y281517D01*
X1878000Y281225D01*
Y280892D01*
X1878125Y280517D01*
X1878333Y280225D01*
X1878583Y280017D01*
X1879000Y279850D01*
X1879375Y279808D01*
X1879750Y279892D01*
X1880000Y280017D01*
X1880250Y280267D01*
X1880417Y280558D01*
X1880500Y280850D01*
Y281142D01*
X1880417Y281433D01*
X1880292Y281683D01*
X1880125Y281892D01*
G01Y283033D02*
X1880333Y283283D01*
X1880458Y283575D01*
X1880500Y283950D01*
X1880417Y284325D01*
X1880250Y284617D01*
X1879958Y284825D01*
X1879625Y284867D01*
X1879292Y284783D01*
X1879083Y284575D01*
X1878917Y284283D01*
X1878875Y283992D01*
X1878917Y283700D01*
X1879083Y283325D01*
X1878000Y283450D01*
Y284575D01*
G01Y287050D02*
X1878083Y286717D01*
X1878292Y286467D01*
X1878542Y286300D01*
X1878875Y286175D01*
X1879250Y286133D01*
X1879625Y286175D01*
X1879958Y286300D01*
X1880208Y286467D01*
X1880417Y286717D01*
X1880500Y287050D01*
X1880417Y287383D01*
X1880208Y287633D01*
X1879958Y287800D01*
X1879625Y287925D01*
X1879250Y287967D01*
X1878875Y287925D01*
X1878542Y287800D01*
X1878292Y287633D01*
X1878083Y287383D01*
X1878000Y287050D01*
G01Y290150D02*
X1878083Y289817D01*
X1878292Y289567D01*
X1878542Y289400D01*
X1878875Y289275D01*
X1879250Y289233D01*
X1879625Y289275D01*
X1879958Y289400D01*
X1880208Y289567D01*
X1880417Y289817D01*
X1880500Y290150D01*
X1880417Y290483D01*
X1880208Y290733D01*
X1879958Y290900D01*
X1879625Y291025D01*
X1879250Y291067D01*
X1878875Y291025D01*
X1878542Y290900D01*
X1878292Y290733D01*
X1878083Y290483D01*
X1878000Y290150D01*
G01X1873300Y271500D02*
Y269000D01*
G01X1872342Y271500D02*
X1874258D01*
G01X1875567Y269000D02*
Y271500D01*
X1876567D01*
X1876900Y271375D01*
X1877150Y271083D01*
X1877233Y270750D01*
X1877150Y270417D01*
X1876942Y270167D01*
X1876567Y270042D01*
X1875567D01*
G01X1879500Y269000D02*
Y271500D01*
X1879000Y271000D01*
G01Y269000D02*
X1880000D01*
G01X1882517D02*
X1882600Y269542D01*
X1882725Y270000D01*
X1882892Y270417D01*
X1883100Y270875D01*
X1883433Y271500D01*
X1881767D01*
G01X1885617Y269000D02*
X1885700Y269542D01*
X1885825Y270000D01*
X1885992Y270417D01*
X1886200Y270875D01*
X1886533Y271500D01*
X1884867D01*
G01X1885542Y302267D02*
X1885417Y302017D01*
X1885334Y301725D01*
Y301392D01*
X1885459Y301017D01*
X1885667Y300725D01*
X1885917Y300517D01*
X1886334Y300350D01*
X1886709Y300308D01*
X1887084Y300392D01*
X1887334Y300517D01*
X1887584Y300767D01*
X1887751Y301058D01*
X1887834Y301350D01*
Y301642D01*
X1887751Y301933D01*
X1887626Y302183D01*
X1887459Y302392D01*
G01Y303533D02*
X1887667Y303783D01*
X1887792Y304075D01*
X1887834Y304450D01*
X1887751Y304825D01*
X1887584Y305117D01*
X1887292Y305325D01*
X1886959Y305367D01*
X1886626Y305283D01*
X1886417Y305075D01*
X1886251Y304783D01*
X1886209Y304492D01*
X1886251Y304200D01*
X1886417Y303825D01*
X1885334Y303950D01*
Y305075D01*
G01Y307550D02*
X1885417Y307217D01*
X1885626Y306967D01*
X1885876Y306800D01*
X1886209Y306675D01*
X1886584Y306633D01*
X1886959Y306675D01*
X1887292Y306800D01*
X1887542Y306967D01*
X1887751Y307217D01*
X1887834Y307550D01*
X1887751Y307883D01*
X1887542Y308133D01*
X1887292Y308300D01*
X1886959Y308425D01*
X1886584Y308467D01*
X1886209Y308425D01*
X1885876Y308300D01*
X1885626Y308133D01*
X1885417Y307883D01*
X1885334Y307550D01*
G01X1885751Y309858D02*
X1885501Y310108D01*
X1885376Y310400D01*
X1885334Y310733D01*
X1885417Y311150D01*
X1885626Y311442D01*
X1885876Y311525D01*
X1886126Y311483D01*
X1886334Y311317D01*
X1886751Y310483D01*
X1887042Y310108D01*
X1887459Y309858D01*
X1887834Y309775D01*
Y311525D01*
G01X1891031Y329492D02*
Y331992D01*
G01X1892781D02*
Y329492D01*
G01Y330742D02*
X1891031D01*
G01X1894089Y329492D02*
Y331992D01*
X1894923D01*
X1895256Y331867D01*
X1895506Y331700D01*
X1895714Y331450D01*
X1895881Y331159D01*
X1895923Y330742D01*
X1895881Y330325D01*
X1895714Y330034D01*
X1895506Y329784D01*
X1895256Y329617D01*
X1894923Y329492D01*
X1894089D01*
G01X1897189D02*
Y331992D01*
X1898023D01*
X1898356Y331867D01*
X1898606Y331700D01*
X1898814Y331450D01*
X1898981Y331159D01*
X1899023Y330742D01*
X1898981Y330325D01*
X1898814Y330034D01*
X1898606Y329784D01*
X1898356Y329617D01*
X1898023Y329492D01*
X1897189D01*
G01X1900331Y329825D02*
X1900664Y329617D01*
X1901039Y329492D01*
X1901373D01*
X1901706Y329617D01*
X1901956Y329825D01*
X1902081Y330117D01*
X1901998Y330409D01*
X1901789Y330659D01*
X1901414Y330825D01*
X1900914Y330909D01*
X1900623Y331075D01*
X1900498Y331367D01*
X1900581Y331659D01*
X1900789Y331867D01*
X1901081Y331992D01*
X1901373D01*
X1901664Y331909D01*
X1901914Y331700D01*
G01X1903264Y329492D02*
X1904306Y331992D01*
X1905348Y329492D01*
G01X1904973Y330367D02*
X1903639D01*
G01X1906531Y329825D02*
X1906864Y329617D01*
X1907239Y329492D01*
X1907573D01*
X1907906Y329617D01*
X1908156Y329825D01*
X1908281Y330117D01*
X1908198Y330409D01*
X1907989Y330659D01*
X1907614Y330825D01*
X1907114Y330909D01*
X1906823Y331075D01*
X1906698Y331367D01*
X1906781Y331659D01*
X1906989Y331867D01*
X1907281Y331992D01*
X1907573D01*
X1907864Y331909D01*
X1908114Y331700D01*
G01X1909589Y329992D02*
X1909839Y329700D01*
X1910173Y329534D01*
X1910548Y329492D01*
X1910881Y329534D01*
X1911214Y329742D01*
X1911423Y329992D01*
X1911464Y330242D01*
X1911381Y330534D01*
X1911089Y330742D01*
X1910798Y330825D01*
X1910423D01*
G01X1910798D02*
X1911048Y330950D01*
X1911256Y331159D01*
X1911339Y331409D01*
X1911256Y331659D01*
X1911048Y331867D01*
X1910673Y331992D01*
X1910298Y331950D01*
X1909923Y331784D01*
G01X1912689Y329867D02*
X1912939Y329659D01*
X1913231Y329534D01*
X1913606Y329492D01*
X1913981Y329575D01*
X1914273Y329742D01*
X1914481Y330034D01*
X1914523Y330367D01*
X1914439Y330700D01*
X1914231Y330909D01*
X1913939Y331075D01*
X1913648Y331117D01*
X1913356Y331075D01*
X1912981Y330909D01*
X1913106Y331992D01*
X1914231D01*
G01X1875232Y496017D02*
X1872732D01*
Y497058D01*
X1872857Y497392D01*
X1873024Y497600D01*
X1873357Y497683D01*
X1873690Y497600D01*
X1873899Y497350D01*
X1874024Y497058D01*
Y496017D01*
G01Y497058D02*
X1875232Y497683D01*
G01X1874732Y499033D02*
X1875024Y499283D01*
X1875190Y499617D01*
X1875232Y499992D01*
X1875190Y500325D01*
X1874982Y500658D01*
X1874732Y500867D01*
X1874482Y500908D01*
X1874190Y500825D01*
X1873982Y500533D01*
X1873899Y500242D01*
Y499867D01*
G01Y500242D02*
X1873774Y500492D01*
X1873565Y500700D01*
X1873315Y500783D01*
X1873065Y500700D01*
X1872857Y500492D01*
X1872732Y500117D01*
X1872774Y499742D01*
X1872940Y499367D01*
G01X1875232Y503550D02*
X1872732D01*
X1874524Y502008D01*
Y504092D01*
G01X1874190Y505358D02*
X1873899Y505650D01*
X1873732Y505900D01*
X1873649Y506233D01*
X1873732Y506525D01*
X1873899Y506733D01*
X1874149Y506900D01*
X1874440Y506942D01*
X1874690Y506900D01*
X1874940Y506733D01*
X1875149Y506483D01*
X1875232Y506192D01*
X1875149Y505858D01*
X1874899Y505567D01*
X1874524Y505400D01*
X1874107Y505358D01*
X1873565Y505442D01*
X1873274Y505567D01*
X1872982Y505775D01*
X1872774Y506067D01*
X1872732Y506358D01*
X1872815Y506650D01*
X1873024Y506858D01*
G01X1870232Y496017D02*
X1867732D01*
Y497058D01*
X1867857Y497392D01*
X1868024Y497600D01*
X1868357Y497683D01*
X1868690Y497600D01*
X1868899Y497350D01*
X1869024Y497058D01*
Y496017D01*
G01Y497058D02*
X1870232Y497683D01*
G01X1869732Y499033D02*
X1870024Y499283D01*
X1870190Y499617D01*
X1870232Y499992D01*
X1870190Y500325D01*
X1869982Y500658D01*
X1869732Y500867D01*
X1869482Y500908D01*
X1869190Y500825D01*
X1868982Y500533D01*
X1868899Y500242D01*
Y499867D01*
G01Y500242D02*
X1868774Y500492D01*
X1868565Y500700D01*
X1868315Y500783D01*
X1868065Y500700D01*
X1867857Y500492D01*
X1867732Y500117D01*
X1867774Y499742D01*
X1867940Y499367D01*
G01X1870232Y503550D02*
X1867732D01*
X1869524Y502008D01*
Y504092D01*
G01X1869732Y505233D02*
X1870024Y505483D01*
X1870190Y505817D01*
X1870232Y506192D01*
X1870190Y506525D01*
X1869982Y506858D01*
X1869732Y507067D01*
X1869482Y507108D01*
X1869190Y507025D01*
X1868982Y506733D01*
X1868899Y506442D01*
Y506067D01*
G01Y506442D02*
X1868774Y506692D01*
X1868565Y506900D01*
X1868315Y506983D01*
X1868065Y506900D01*
X1867857Y506692D01*
X1867732Y506317D01*
X1867774Y505942D01*
X1867940Y505567D01*
G01X1885856Y674248D02*
X1890906D01*
Y772948D01*
X1915556D01*
Y588548D01*
X1890906D01*
Y647248D01*
X1885856D01*
Y674248D01*
G01X1874400Y620517D02*
X1871900D01*
Y621558D01*
X1872025Y621892D01*
X1872192Y622100D01*
X1872525Y622183D01*
X1872858Y622100D01*
X1873067Y621850D01*
X1873192Y621558D01*
Y620517D01*
G01Y621558D02*
X1874400Y622183D01*
G01X1873358Y623658D02*
X1873067Y623950D01*
X1872900Y624200D01*
X1872817Y624533D01*
X1872900Y624825D01*
X1873067Y625033D01*
X1873317Y625200D01*
X1873608Y625242D01*
X1873858Y625200D01*
X1874108Y625033D01*
X1874317Y624783D01*
X1874400Y624492D01*
X1874317Y624158D01*
X1874067Y623867D01*
X1873692Y623700D01*
X1873275Y623658D01*
X1872733Y623742D01*
X1872442Y623867D01*
X1872150Y624075D01*
X1871942Y624367D01*
X1871900Y624658D01*
X1871983Y624950D01*
X1872192Y625158D01*
G01X1874025Y626633D02*
X1874233Y626883D01*
X1874358Y627175D01*
X1874400Y627550D01*
X1874317Y627925D01*
X1874150Y628217D01*
X1873858Y628425D01*
X1873525Y628467D01*
X1873192Y628383D01*
X1872983Y628175D01*
X1872817Y627883D01*
X1872775Y627592D01*
X1872817Y627300D01*
X1872983Y626925D01*
X1871900Y627050D01*
Y628175D01*
G01X1874108Y629942D02*
X1874317Y630233D01*
X1874400Y630567D01*
X1874317Y630900D01*
X1874067Y631192D01*
X1873692Y631400D01*
X1873317Y631483D01*
X1872858D01*
X1872483Y631400D01*
X1872150Y631192D01*
X1871983Y630942D01*
X1871900Y630650D01*
X1871983Y630317D01*
X1872150Y630067D01*
X1872400Y629900D01*
X1872733Y629817D01*
X1873025Y629900D01*
X1873317Y630108D01*
X1873483Y630358D01*
X1873525Y630650D01*
X1873442Y630983D01*
X1873233Y631233D01*
X1872858Y631483D01*
G01X1876900Y638300D02*
X1880900D01*
Y645700D01*
G01X1862117Y620631D02*
Y632031D01*
G01X1879267Y611792D02*
X1879017Y611917D01*
X1878725Y612000D01*
X1878392D01*
X1878017Y611875D01*
X1877725Y611667D01*
X1877517Y611417D01*
X1877350Y611000D01*
X1877308Y610625D01*
X1877392Y610250D01*
X1877517Y610000D01*
X1877767Y609750D01*
X1878058Y609583D01*
X1878350Y609500D01*
X1878642D01*
X1878933Y609583D01*
X1879183Y609708D01*
X1879392Y609875D01*
G01X1880533Y610000D02*
X1880783Y609708D01*
X1881117Y609542D01*
X1881492Y609500D01*
X1881825Y609542D01*
X1882158Y609750D01*
X1882367Y610000D01*
X1882408Y610250D01*
X1882325Y610542D01*
X1882033Y610750D01*
X1881742Y610833D01*
X1881367D01*
G01X1881742D02*
X1881992Y610958D01*
X1882200Y611167D01*
X1882283Y611417D01*
X1882200Y611667D01*
X1881992Y611875D01*
X1881617Y612000D01*
X1881242Y611958D01*
X1880867Y611792D01*
G01X1883633Y610000D02*
X1883883Y609708D01*
X1884217Y609542D01*
X1884592Y609500D01*
X1884925Y609542D01*
X1885258Y609750D01*
X1885467Y610000D01*
X1885508Y610250D01*
X1885425Y610542D01*
X1885133Y610750D01*
X1884842Y610833D01*
X1884467D01*
G01X1884842D02*
X1885092Y610958D01*
X1885300Y611167D01*
X1885383Y611417D01*
X1885300Y611667D01*
X1885092Y611875D01*
X1884717Y612000D01*
X1884342Y611958D01*
X1883967Y611792D01*
G01X1887650Y609500D02*
X1887942Y609542D01*
X1888275Y609667D01*
X1888483Y609875D01*
X1888567Y610167D01*
X1888483Y610458D01*
X1888233Y610708D01*
X1887858Y610833D01*
X1887442D01*
X1887192Y610917D01*
X1886983Y611125D01*
X1886900Y611417D01*
X1887025Y611708D01*
X1887317Y611917D01*
X1887650Y612000D01*
X1887983Y611917D01*
X1888275Y611708D01*
X1888400Y611417D01*
X1888317Y611125D01*
X1888108Y610917D01*
X1887858Y610833D01*
X1887442D01*
X1887067Y610708D01*
X1886817Y610458D01*
X1886733Y610167D01*
X1886817Y609875D01*
X1887025Y609667D01*
X1887358Y609542D01*
X1887650Y609500D01*
G01X1879267Y615792D02*
X1879017Y615917D01*
X1878725Y616000D01*
X1878392D01*
X1878017Y615875D01*
X1877725Y615667D01*
X1877517Y615417D01*
X1877350Y615000D01*
X1877308Y614625D01*
X1877392Y614250D01*
X1877517Y614000D01*
X1877767Y613750D01*
X1878058Y613583D01*
X1878350Y613500D01*
X1878642D01*
X1878933Y613583D01*
X1879183Y613708D01*
X1879392Y613875D01*
G01X1880533Y614000D02*
X1880783Y613708D01*
X1881117Y613542D01*
X1881492Y613500D01*
X1881825Y613542D01*
X1882158Y613750D01*
X1882367Y614000D01*
X1882408Y614250D01*
X1882325Y614542D01*
X1882033Y614750D01*
X1881742Y614833D01*
X1881367D01*
G01X1881742D02*
X1881992Y614958D01*
X1882200Y615167D01*
X1882283Y615417D01*
X1882200Y615667D01*
X1881992Y615875D01*
X1881617Y616000D01*
X1881242Y615958D01*
X1880867Y615792D01*
G01X1883633Y614000D02*
X1883883Y613708D01*
X1884217Y613542D01*
X1884592Y613500D01*
X1884925Y613542D01*
X1885258Y613750D01*
X1885467Y614000D01*
X1885508Y614250D01*
X1885425Y614542D01*
X1885133Y614750D01*
X1884842Y614833D01*
X1884467D01*
G01X1884842D02*
X1885092Y614958D01*
X1885300Y615167D01*
X1885383Y615417D01*
X1885300Y615667D01*
X1885092Y615875D01*
X1884717Y616000D01*
X1884342Y615958D01*
X1883967Y615792D01*
G01X1887567Y613500D02*
X1887650Y614042D01*
X1887775Y614500D01*
X1887942Y614917D01*
X1888150Y615375D01*
X1888483Y616000D01*
X1886817D01*
G01X1870500Y620517D02*
X1868000D01*
Y621558D01*
X1868125Y621892D01*
X1868292Y622100D01*
X1868625Y622183D01*
X1868958Y622100D01*
X1869167Y621850D01*
X1869292Y621558D01*
Y620517D01*
G01Y621558D02*
X1870500Y622183D01*
G01X1869458Y623658D02*
X1869167Y623950D01*
X1869000Y624200D01*
X1868917Y624533D01*
X1869000Y624825D01*
X1869167Y625033D01*
X1869417Y625200D01*
X1869708Y625242D01*
X1869958Y625200D01*
X1870208Y625033D01*
X1870417Y624783D01*
X1870500Y624492D01*
X1870417Y624158D01*
X1870167Y623867D01*
X1869792Y623700D01*
X1869375Y623658D01*
X1868833Y623742D01*
X1868542Y623867D01*
X1868250Y624075D01*
X1868042Y624367D01*
X1868000Y624658D01*
X1868083Y624950D01*
X1868292Y625158D01*
G01X1869458Y626758D02*
X1869167Y627050D01*
X1869000Y627300D01*
X1868917Y627633D01*
X1869000Y627925D01*
X1869167Y628133D01*
X1869417Y628300D01*
X1869708Y628342D01*
X1869958Y628300D01*
X1870208Y628133D01*
X1870417Y627883D01*
X1870500Y627592D01*
X1870417Y627258D01*
X1870167Y626967D01*
X1869792Y626800D01*
X1869375Y626758D01*
X1868833Y626842D01*
X1868542Y626967D01*
X1868250Y627175D01*
X1868042Y627467D01*
X1868000Y627758D01*
X1868083Y628050D01*
X1868292Y628258D01*
G01X1870000Y629733D02*
X1870292Y629983D01*
X1870458Y630317D01*
X1870500Y630692D01*
X1870458Y631025D01*
X1870250Y631358D01*
X1870000Y631567D01*
X1869750Y631608D01*
X1869458Y631525D01*
X1869250Y631233D01*
X1869167Y630942D01*
Y630567D01*
G01Y630942D02*
X1869042Y631192D01*
X1868833Y631400D01*
X1868583Y631483D01*
X1868333Y631400D01*
X1868125Y631192D01*
X1868000Y630817D01*
X1868042Y630442D01*
X1868208Y630067D01*
G01X1876208Y622267D02*
X1876083Y622017D01*
X1876000Y621725D01*
Y621392D01*
X1876125Y621017D01*
X1876333Y620725D01*
X1876583Y620517D01*
X1877000Y620350D01*
X1877375Y620308D01*
X1877750Y620392D01*
X1878000Y620517D01*
X1878250Y620767D01*
X1878417Y621058D01*
X1878500Y621350D01*
Y621642D01*
X1878417Y621933D01*
X1878292Y622183D01*
X1878125Y622392D01*
G01X1878000Y623533D02*
X1878292Y623783D01*
X1878458Y624117D01*
X1878500Y624492D01*
X1878458Y624825D01*
X1878250Y625158D01*
X1878000Y625367D01*
X1877750Y625408D01*
X1877458Y625325D01*
X1877250Y625033D01*
X1877167Y624742D01*
Y624367D01*
G01Y624742D02*
X1877042Y624992D01*
X1876833Y625200D01*
X1876583Y625283D01*
X1876333Y625200D01*
X1876125Y624992D01*
X1876000Y624617D01*
X1876042Y624242D01*
X1876208Y623867D01*
G01X1878500Y628050D02*
X1876000D01*
X1877792Y626508D01*
Y628592D01*
G01X1878125Y629733D02*
X1878333Y629983D01*
X1878458Y630275D01*
X1878500Y630650D01*
X1878417Y631025D01*
X1878250Y631317D01*
X1877958Y631525D01*
X1877625Y631567D01*
X1877292Y631483D01*
X1877083Y631275D01*
X1876917Y630983D01*
X1876875Y630692D01*
X1876917Y630400D01*
X1877083Y630025D01*
X1876000Y630150D01*
Y631275D01*
G01X1881169Y706717D02*
X1889169D01*
Y689117D01*
X1881169D01*
Y706717D01*
G01X1879469Y688917D02*
X1873969D01*
G01X1879469Y696917D02*
Y688917D01*
G01X1861869D02*
Y696917D01*
G01X1867369Y688917D02*
X1861869D01*
G01X1888500Y677350D02*
X1888458Y677017D01*
X1888292Y676725D01*
X1888042Y676475D01*
X1887750Y676308D01*
X1887417Y676225D01*
X1887083D01*
X1886750Y676308D01*
X1886458Y676475D01*
X1886208Y676725D01*
X1886042Y677017D01*
X1886000Y677350D01*
X1886042Y677683D01*
X1886208Y677975D01*
X1886458Y678225D01*
X1886750Y678392D01*
X1887083Y678475D01*
X1887417D01*
X1887750Y678392D01*
X1888042Y678225D01*
X1888292Y677975D01*
X1888458Y677683D01*
X1888500Y677350D01*
G01X1887833Y677683D02*
X1888500Y678183D01*
G01Y680450D02*
X1886000D01*
X1886500Y679950D01*
G01X1888500D02*
Y680950D01*
G01X1888000Y682633D02*
X1888292Y682883D01*
X1888458Y683217D01*
X1888500Y683592D01*
X1888458Y683925D01*
X1888250Y684258D01*
X1888000Y684467D01*
X1887750Y684508D01*
X1887458Y684425D01*
X1887250Y684133D01*
X1887167Y683842D01*
Y683467D01*
G01Y683842D02*
X1887042Y684092D01*
X1886833Y684300D01*
X1886583Y684383D01*
X1886333Y684300D01*
X1886125Y684092D01*
X1886000Y683717D01*
X1886042Y683342D01*
X1886208Y682967D01*
G01X1888500Y686567D02*
X1887958Y686650D01*
X1887500Y686775D01*
X1887083Y686942D01*
X1886625Y687150D01*
X1886000Y687483D01*
Y685817D01*
G01X1883869Y668417D02*
X1881769Y670217D01*
X1883869Y672417D01*
G01X1883969Y676017D02*
X1864769D01*
Y664817D01*
X1883969D01*
Y676017D01*
X1883569D01*
G01X1886000Y709017D02*
X1883500D01*
Y710058D01*
X1883625Y710392D01*
X1883792Y710600D01*
X1884125Y710683D01*
X1884458Y710600D01*
X1884667Y710350D01*
X1884792Y710058D01*
Y709017D01*
G01Y710058D02*
X1886000Y710683D01*
G01X1884958Y712158D02*
X1884667Y712450D01*
X1884500Y712700D01*
X1884417Y713033D01*
X1884500Y713325D01*
X1884667Y713533D01*
X1884917Y713700D01*
X1885208Y713742D01*
X1885458Y713700D01*
X1885708Y713533D01*
X1885917Y713283D01*
X1886000Y712992D01*
X1885917Y712658D01*
X1885667Y712367D01*
X1885292Y712200D01*
X1884875Y712158D01*
X1884333Y712242D01*
X1884042Y712367D01*
X1883750Y712575D01*
X1883542Y712867D01*
X1883500Y713158D01*
X1883583Y713450D01*
X1883792Y713658D01*
G01X1885625Y715133D02*
X1885833Y715383D01*
X1885958Y715675D01*
X1886000Y716050D01*
X1885917Y716425D01*
X1885750Y716717D01*
X1885458Y716925D01*
X1885125Y716967D01*
X1884792Y716883D01*
X1884583Y716675D01*
X1884417Y716383D01*
X1884375Y716092D01*
X1884417Y715800D01*
X1884583Y715425D01*
X1883500Y715550D01*
Y716675D01*
G01X1886000Y719150D02*
X1885958Y719442D01*
X1885833Y719775D01*
X1885625Y719983D01*
X1885333Y720067D01*
X1885042Y719983D01*
X1884792Y719733D01*
X1884667Y719358D01*
Y718942D01*
X1884583Y718692D01*
X1884375Y718483D01*
X1884083Y718400D01*
X1883792Y718525D01*
X1883583Y718817D01*
X1883500Y719150D01*
X1883583Y719483D01*
X1883792Y719775D01*
X1884083Y719900D01*
X1884375Y719817D01*
X1884583Y719608D01*
X1884667Y719358D01*
Y718942D01*
X1884792Y718567D01*
X1885042Y718317D01*
X1885333Y718233D01*
X1885625Y718317D01*
X1885833Y718525D01*
X1885958Y718858D01*
X1886000Y719150D01*
G01X1878708Y733767D02*
X1878583Y733517D01*
X1878500Y733225D01*
Y732892D01*
X1878625Y732517D01*
X1878833Y732225D01*
X1879083Y732017D01*
X1879500Y731850D01*
X1879875Y731808D01*
X1880250Y731892D01*
X1880500Y732017D01*
X1880750Y732267D01*
X1880917Y732558D01*
X1881000Y732850D01*
Y733142D01*
X1880917Y733433D01*
X1880792Y733683D01*
X1880625Y733892D01*
G01X1880500Y735033D02*
X1880792Y735283D01*
X1880958Y735617D01*
X1881000Y735992D01*
X1880958Y736325D01*
X1880750Y736658D01*
X1880500Y736867D01*
X1880250Y736908D01*
X1879958Y736825D01*
X1879750Y736533D01*
X1879667Y736242D01*
Y735867D01*
G01Y736242D02*
X1879542Y736492D01*
X1879333Y736700D01*
X1879083Y736783D01*
X1878833Y736700D01*
X1878625Y736492D01*
X1878500Y736117D01*
X1878542Y735742D01*
X1878708Y735367D01*
G01X1881000Y739550D02*
X1878500D01*
X1880292Y738008D01*
Y740092D01*
G01X1880500Y741233D02*
X1880792Y741483D01*
X1880958Y741817D01*
X1881000Y742192D01*
X1880958Y742525D01*
X1880750Y742858D01*
X1880500Y743067D01*
X1880250Y743108D01*
X1879958Y743025D01*
X1879750Y742733D01*
X1879667Y742442D01*
Y742067D01*
G01Y742442D02*
X1879542Y742692D01*
X1879333Y742900D01*
X1879083Y742983D01*
X1878833Y742900D01*
X1878625Y742692D01*
X1878500Y742317D01*
X1878542Y741942D01*
X1878708Y741567D01*
G01X1873969Y696917D02*
X1879469D01*
G01X1861869D02*
X1867369D01*
G01X1873000Y711800D02*
X1875500D01*
G01X1873000Y710842D02*
Y712758D01*
G01X1875500Y714067D02*
X1873000D01*
Y715067D01*
X1873125Y715400D01*
X1873417Y715650D01*
X1873750Y715733D01*
X1874083Y715650D01*
X1874333Y715442D01*
X1874458Y715067D01*
Y714067D01*
G01X1875500Y718000D02*
X1873000D01*
X1873500Y717500D01*
G01X1875500D02*
Y718500D01*
G01Y721100D02*
X1873000D01*
X1873500Y720600D01*
G01X1875500D02*
Y721600D01*
G01Y724117D02*
X1874958Y724200D01*
X1874500Y724325D01*
X1874083Y724492D01*
X1873625Y724700D01*
X1873000Y725033D01*
Y723367D01*
G01X1893531Y779748D02*
Y782248D01*
G01X1895281D02*
Y779748D01*
G01Y780998D02*
X1893531D01*
G01X1896589Y779748D02*
Y782248D01*
X1897423D01*
X1897756Y782123D01*
X1898006Y781956D01*
X1898214Y781706D01*
X1898381Y781415D01*
X1898423Y780998D01*
X1898381Y780581D01*
X1898214Y780290D01*
X1898006Y780040D01*
X1897756Y779873D01*
X1897423Y779748D01*
X1896589D01*
G01X1899689D02*
Y782248D01*
X1900523D01*
X1900856Y782123D01*
X1901106Y781956D01*
X1901314Y781706D01*
X1901481Y781415D01*
X1901523Y780998D01*
X1901481Y780581D01*
X1901314Y780290D01*
X1901106Y780040D01*
X1900856Y779873D01*
X1900523Y779748D01*
X1899689D01*
G01X1902831Y780081D02*
X1903164Y779873D01*
X1903539Y779748D01*
X1903873D01*
X1904206Y779873D01*
X1904456Y780081D01*
X1904581Y780373D01*
X1904498Y780665D01*
X1904289Y780915D01*
X1903914Y781081D01*
X1903414Y781165D01*
X1903123Y781331D01*
X1902998Y781623D01*
X1903081Y781915D01*
X1903289Y782123D01*
X1903581Y782248D01*
X1903873D01*
X1904164Y782165D01*
X1904414Y781956D01*
G01X1905764Y779748D02*
X1906806Y782248D01*
X1907848Y779748D01*
G01X1907473Y780623D02*
X1906139D01*
G01X1909031Y780081D02*
X1909364Y779873D01*
X1909739Y779748D01*
X1910073D01*
X1910406Y779873D01*
X1910656Y780081D01*
X1910781Y780373D01*
X1910698Y780665D01*
X1910489Y780915D01*
X1910114Y781081D01*
X1909614Y781165D01*
X1909323Y781331D01*
X1909198Y781623D01*
X1909281Y781915D01*
X1909489Y782123D01*
X1909781Y782248D01*
X1910073D01*
X1910364Y782165D01*
X1910614Y781956D01*
G01X1912214Y781831D02*
X1912464Y782081D01*
X1912756Y782206D01*
X1913089Y782248D01*
X1913506Y782165D01*
X1913798Y781956D01*
X1913881Y781706D01*
X1913839Y781456D01*
X1913673Y781248D01*
X1912839Y780831D01*
X1912464Y780540D01*
X1912214Y780123D01*
X1912131Y779748D01*
X1913881D01*
G01X1915189Y780248D02*
X1915439Y779956D01*
X1915773Y779790D01*
X1916148Y779748D01*
X1916481Y779790D01*
X1916814Y779998D01*
X1917023Y780248D01*
X1917064Y780498D01*
X1916981Y780790D01*
X1916689Y780998D01*
X1916398Y781081D01*
X1916023D01*
G01X1916398D02*
X1916648Y781206D01*
X1916856Y781415D01*
X1916939Y781665D01*
X1916856Y781915D01*
X1916648Y782123D01*
X1916273Y782248D01*
X1915898Y782206D01*
X1915523Y782040D01*
G01X1881708Y746767D02*
X1881583Y746517D01*
X1881500Y746225D01*
Y745892D01*
X1881625Y745517D01*
X1881833Y745225D01*
X1882083Y745017D01*
X1882500Y744850D01*
X1882875Y744808D01*
X1883250Y744892D01*
X1883500Y745017D01*
X1883750Y745267D01*
X1883917Y745558D01*
X1884000Y745850D01*
Y746142D01*
X1883917Y746433D01*
X1883792Y746683D01*
X1883625Y746892D01*
G01X1883500Y748033D02*
X1883792Y748283D01*
X1883958Y748617D01*
X1884000Y748992D01*
X1883958Y749325D01*
X1883750Y749658D01*
X1883500Y749867D01*
X1883250Y749908D01*
X1882958Y749825D01*
X1882750Y749533D01*
X1882667Y749242D01*
Y748867D01*
G01Y749242D02*
X1882542Y749492D01*
X1882333Y749700D01*
X1882083Y749783D01*
X1881833Y749700D01*
X1881625Y749492D01*
X1881500Y749117D01*
X1881542Y748742D01*
X1881708Y748367D01*
G01X1884000Y752550D02*
X1881500D01*
X1883292Y751008D01*
Y753092D01*
G01X1882958Y754358D02*
X1882667Y754650D01*
X1882500Y754900D01*
X1882417Y755233D01*
X1882500Y755525D01*
X1882667Y755733D01*
X1882917Y755900D01*
X1883208Y755942D01*
X1883458Y755900D01*
X1883708Y755733D01*
X1883917Y755483D01*
X1884000Y755192D01*
X1883917Y754858D01*
X1883667Y754567D01*
X1883292Y754400D01*
X1882875Y754358D01*
X1882333Y754442D01*
X1882042Y754567D01*
X1881750Y754775D01*
X1881542Y755067D01*
X1881500Y755358D01*
X1881583Y755650D01*
X1881792Y755858D01*
G01X1878602Y1033938D02*
Y1036438D01*
X1879643D01*
X1879977Y1036313D01*
X1880185Y1036146D01*
X1880268Y1035813D01*
X1880185Y1035480D01*
X1879935Y1035271D01*
X1879643Y1035146D01*
X1878602D01*
G01X1879643D02*
X1880268Y1033938D01*
G01X1881618Y1034438D02*
X1881868Y1034146D01*
X1882202Y1033980D01*
X1882577Y1033938D01*
X1882910Y1033980D01*
X1883243Y1034188D01*
X1883452Y1034438D01*
X1883493Y1034688D01*
X1883410Y1034980D01*
X1883118Y1035188D01*
X1882827Y1035271D01*
X1882452D01*
G01X1882827D02*
X1883077Y1035396D01*
X1883285Y1035605D01*
X1883368Y1035855D01*
X1883285Y1036105D01*
X1883077Y1036313D01*
X1882702Y1036438D01*
X1882327Y1036396D01*
X1881952Y1036230D01*
G01X1885635Y1033938D02*
X1885927Y1033980D01*
X1886260Y1034105D01*
X1886468Y1034313D01*
X1886552Y1034605D01*
X1886468Y1034896D01*
X1886218Y1035146D01*
X1885843Y1035271D01*
X1885427D01*
X1885177Y1035355D01*
X1884968Y1035563D01*
X1884885Y1035855D01*
X1885010Y1036146D01*
X1885302Y1036355D01*
X1885635Y1036438D01*
X1885968Y1036355D01*
X1886260Y1036146D01*
X1886385Y1035855D01*
X1886302Y1035563D01*
X1886093Y1035355D01*
X1885843Y1035271D01*
X1885427D01*
X1885052Y1035146D01*
X1884802Y1034896D01*
X1884718Y1034605D01*
X1884802Y1034313D01*
X1885010Y1034105D01*
X1885343Y1033980D01*
X1885635Y1033938D01*
G01X1887818Y1034438D02*
X1888068Y1034146D01*
X1888402Y1033980D01*
X1888777Y1033938D01*
X1889110Y1033980D01*
X1889443Y1034188D01*
X1889652Y1034438D01*
X1889693Y1034688D01*
X1889610Y1034980D01*
X1889318Y1035188D01*
X1889027Y1035271D01*
X1888652D01*
G01X1889027D02*
X1889277Y1035396D01*
X1889485Y1035605D01*
X1889568Y1035855D01*
X1889485Y1036105D01*
X1889277Y1036313D01*
X1888902Y1036438D01*
X1888527Y1036396D01*
X1888152Y1036230D01*
G01X1876162Y1023443D02*
X1873662D01*
Y1024484D01*
X1873787Y1024818D01*
X1873954Y1025026D01*
X1874287Y1025109D01*
X1874620Y1025026D01*
X1874829Y1024776D01*
X1874954Y1024484D01*
Y1023443D01*
G01Y1024484D02*
X1876162Y1025109D01*
G01X1875662Y1026459D02*
X1875954Y1026709D01*
X1876120Y1027043D01*
X1876162Y1027418D01*
X1876120Y1027751D01*
X1875912Y1028084D01*
X1875662Y1028293D01*
X1875412Y1028334D01*
X1875120Y1028251D01*
X1874912Y1027959D01*
X1874829Y1027668D01*
Y1027293D01*
G01Y1027668D02*
X1874704Y1027918D01*
X1874495Y1028126D01*
X1874245Y1028209D01*
X1873995Y1028126D01*
X1873787Y1027918D01*
X1873662Y1027543D01*
X1873704Y1027168D01*
X1873870Y1026793D01*
G01X1875870Y1029768D02*
X1876079Y1030059D01*
X1876162Y1030393D01*
X1876079Y1030726D01*
X1875829Y1031018D01*
X1875454Y1031226D01*
X1875079Y1031309D01*
X1874620D01*
X1874245Y1031226D01*
X1873912Y1031018D01*
X1873745Y1030768D01*
X1873662Y1030476D01*
X1873745Y1030143D01*
X1873912Y1029893D01*
X1874162Y1029726D01*
X1874495Y1029643D01*
X1874787Y1029726D01*
X1875079Y1029934D01*
X1875245Y1030184D01*
X1875287Y1030476D01*
X1875204Y1030809D01*
X1874995Y1031059D01*
X1874620Y1031309D01*
G01X1876162Y1033576D02*
X1873662D01*
X1874162Y1033076D01*
G01X1876162D02*
Y1034076D01*
G01X1871662Y1023443D02*
X1869162D01*
Y1024484D01*
X1869287Y1024818D01*
X1869454Y1025026D01*
X1869787Y1025109D01*
X1870120Y1025026D01*
X1870329Y1024776D01*
X1870454Y1024484D01*
Y1023443D01*
G01Y1024484D02*
X1871662Y1025109D01*
G01X1871162Y1026459D02*
X1871454Y1026709D01*
X1871620Y1027043D01*
X1871662Y1027418D01*
X1871620Y1027751D01*
X1871412Y1028084D01*
X1871162Y1028293D01*
X1870912Y1028334D01*
X1870620Y1028251D01*
X1870412Y1027959D01*
X1870329Y1027668D01*
Y1027293D01*
G01Y1027668D02*
X1870204Y1027918D01*
X1869995Y1028126D01*
X1869745Y1028209D01*
X1869495Y1028126D01*
X1869287Y1027918D01*
X1869162Y1027543D01*
X1869204Y1027168D01*
X1869370Y1026793D01*
G01X1871370Y1029768D02*
X1871579Y1030059D01*
X1871662Y1030393D01*
X1871579Y1030726D01*
X1871329Y1031018D01*
X1870954Y1031226D01*
X1870579Y1031309D01*
X1870120D01*
X1869745Y1031226D01*
X1869412Y1031018D01*
X1869245Y1030768D01*
X1869162Y1030476D01*
X1869245Y1030143D01*
X1869412Y1029893D01*
X1869662Y1029726D01*
X1869995Y1029643D01*
X1870287Y1029726D01*
X1870579Y1029934D01*
X1870745Y1030184D01*
X1870787Y1030476D01*
X1870704Y1030809D01*
X1870495Y1031059D01*
X1870120Y1031309D01*
G01X1871662Y1034076D02*
X1869162D01*
X1870954Y1032534D01*
Y1034618D01*
G01X1867600Y1023517D02*
X1865100D01*
Y1024558D01*
X1865225Y1024892D01*
X1865392Y1025100D01*
X1865725Y1025183D01*
X1866058Y1025100D01*
X1866267Y1024850D01*
X1866392Y1024558D01*
Y1023517D01*
G01Y1024558D02*
X1867600Y1025183D01*
G01X1867100Y1026533D02*
X1867392Y1026783D01*
X1867558Y1027117D01*
X1867600Y1027492D01*
X1867558Y1027825D01*
X1867350Y1028158D01*
X1867100Y1028367D01*
X1866850Y1028408D01*
X1866558Y1028325D01*
X1866350Y1028033D01*
X1866267Y1027742D01*
Y1027367D01*
G01Y1027742D02*
X1866142Y1027992D01*
X1865933Y1028200D01*
X1865683Y1028283D01*
X1865433Y1028200D01*
X1865225Y1027992D01*
X1865100Y1027617D01*
X1865142Y1027242D01*
X1865308Y1026867D01*
G01X1867308Y1029842D02*
X1867517Y1030133D01*
X1867600Y1030467D01*
X1867517Y1030800D01*
X1867267Y1031092D01*
X1866892Y1031300D01*
X1866517Y1031383D01*
X1866058D01*
X1865683Y1031300D01*
X1865350Y1031092D01*
X1865183Y1030842D01*
X1865100Y1030550D01*
X1865183Y1030217D01*
X1865350Y1029967D01*
X1865600Y1029800D01*
X1865933Y1029717D01*
X1866225Y1029800D01*
X1866517Y1030008D01*
X1866683Y1030258D01*
X1866725Y1030550D01*
X1866642Y1030883D01*
X1866433Y1031133D01*
X1866058Y1031383D01*
G01X1867225Y1032733D02*
X1867433Y1032983D01*
X1867558Y1033275D01*
X1867600Y1033650D01*
X1867517Y1034025D01*
X1867350Y1034317D01*
X1867058Y1034525D01*
X1866725Y1034567D01*
X1866392Y1034483D01*
X1866183Y1034275D01*
X1866017Y1033983D01*
X1865975Y1033692D01*
X1866017Y1033400D01*
X1866183Y1033025D01*
X1865100Y1033150D01*
Y1034275D01*
G01X1878517Y1029500D02*
Y1032000D01*
X1879558D01*
X1879892Y1031875D01*
X1880100Y1031708D01*
X1880183Y1031375D01*
X1880100Y1031042D01*
X1879850Y1030833D01*
X1879558Y1030708D01*
X1878517D01*
G01X1879558D02*
X1880183Y1029500D01*
G01X1881533Y1030000D02*
X1881783Y1029708D01*
X1882117Y1029542D01*
X1882492Y1029500D01*
X1882825Y1029542D01*
X1883158Y1029750D01*
X1883367Y1030000D01*
X1883408Y1030250D01*
X1883325Y1030542D01*
X1883033Y1030750D01*
X1882742Y1030833D01*
X1882367D01*
G01X1882742D02*
X1882992Y1030958D01*
X1883200Y1031167D01*
X1883283Y1031417D01*
X1883200Y1031667D01*
X1882992Y1031875D01*
X1882617Y1032000D01*
X1882242Y1031958D01*
X1881867Y1031792D01*
G01X1885550Y1029500D02*
X1885842Y1029542D01*
X1886175Y1029667D01*
X1886383Y1029875D01*
X1886467Y1030167D01*
X1886383Y1030458D01*
X1886133Y1030708D01*
X1885758Y1030833D01*
X1885342D01*
X1885092Y1030917D01*
X1884883Y1031125D01*
X1884800Y1031417D01*
X1884925Y1031708D01*
X1885217Y1031917D01*
X1885550Y1032000D01*
X1885883Y1031917D01*
X1886175Y1031708D01*
X1886300Y1031417D01*
X1886217Y1031125D01*
X1886008Y1030917D01*
X1885758Y1030833D01*
X1885342D01*
X1884967Y1030708D01*
X1884717Y1030458D01*
X1884633Y1030167D01*
X1884717Y1029875D01*
X1884925Y1029667D01*
X1885258Y1029542D01*
X1885550Y1029500D01*
G01X1888567D02*
X1888650Y1030042D01*
X1888775Y1030500D01*
X1888942Y1030917D01*
X1889150Y1031375D01*
X1889483Y1032000D01*
X1887817D01*
G01X1885856Y1127004D02*
X1890906D01*
Y1225704D01*
X1915556D01*
Y1041304D01*
X1890906D01*
Y1100004D01*
X1885856D01*
Y1127004D01*
G01X1886785Y1057938D02*
Y1061938D01*
X1879385D01*
G01X1874662Y1056726D02*
X1878662D01*
Y1064126D01*
G01X1870162Y1056726D02*
X1874162D01*
Y1064126D01*
G01X1870100Y1064200D02*
X1866100D01*
Y1056800D01*
G01X1868400Y1037500D02*
X1868067Y1037542D01*
X1867775Y1037708D01*
X1867525Y1037958D01*
X1867358Y1038250D01*
X1867275Y1038583D01*
Y1038917D01*
X1867358Y1039250D01*
X1867525Y1039542D01*
X1867775Y1039792D01*
X1868067Y1039958D01*
X1868400Y1040000D01*
X1868733Y1039958D01*
X1869025Y1039792D01*
X1869275Y1039542D01*
X1869442Y1039250D01*
X1869525Y1038917D01*
Y1038583D01*
X1869442Y1038250D01*
X1869275Y1037958D01*
X1869025Y1037708D01*
X1868733Y1037542D01*
X1868400Y1037500D01*
G01X1868733Y1038167D02*
X1869233Y1037500D01*
G01X1870708Y1038542D02*
X1871000Y1038833D01*
X1871250Y1039000D01*
X1871583Y1039083D01*
X1871875Y1039000D01*
X1872083Y1038833D01*
X1872250Y1038583D01*
X1872292Y1038292D01*
X1872250Y1038042D01*
X1872083Y1037792D01*
X1871833Y1037583D01*
X1871542Y1037500D01*
X1871208Y1037583D01*
X1870917Y1037833D01*
X1870750Y1038208D01*
X1870708Y1038625D01*
X1870792Y1039167D01*
X1870917Y1039458D01*
X1871125Y1039750D01*
X1871417Y1039958D01*
X1871708Y1040000D01*
X1872000Y1039917D01*
X1872208Y1039708D01*
G01X1874517Y1037500D02*
X1874600Y1038042D01*
X1874725Y1038500D01*
X1874892Y1038917D01*
X1875100Y1039375D01*
X1875433Y1040000D01*
X1873767D01*
G01X1874030Y1073800D02*
Y1085200D01*
G01X1866267Y1048292D02*
X1866017Y1048417D01*
X1865725Y1048500D01*
X1865392D01*
X1865017Y1048375D01*
X1864725Y1048167D01*
X1864517Y1047917D01*
X1864350Y1047500D01*
X1864308Y1047125D01*
X1864392Y1046750D01*
X1864517Y1046500D01*
X1864767Y1046250D01*
X1865058Y1046083D01*
X1865350Y1046000D01*
X1865642D01*
X1865933Y1046083D01*
X1866183Y1046208D01*
X1866392Y1046375D01*
G01X1868450Y1046000D02*
Y1048500D01*
X1867950Y1048000D01*
G01Y1046000D02*
X1868950D01*
G01X1871550D02*
X1871842Y1046042D01*
X1872175Y1046167D01*
X1872383Y1046375D01*
X1872467Y1046667D01*
X1872383Y1046958D01*
X1872133Y1047208D01*
X1871758Y1047333D01*
X1871342D01*
X1871092Y1047417D01*
X1870883Y1047625D01*
X1870800Y1047917D01*
X1870925Y1048208D01*
X1871217Y1048417D01*
X1871550Y1048500D01*
X1871883Y1048417D01*
X1872175Y1048208D01*
X1872300Y1047917D01*
X1872217Y1047625D01*
X1872008Y1047417D01*
X1871758Y1047333D01*
X1871342D01*
X1870967Y1047208D01*
X1870717Y1046958D01*
X1870633Y1046667D01*
X1870717Y1046375D01*
X1870925Y1046167D01*
X1871258Y1046042D01*
X1871550Y1046000D01*
G01X1875150D02*
Y1048500D01*
X1873608Y1046708D01*
X1875692D01*
G01X1880267Y1044792D02*
X1880017Y1044917D01*
X1879725Y1045000D01*
X1879392D01*
X1879017Y1044875D01*
X1878725Y1044667D01*
X1878517Y1044417D01*
X1878350Y1044000D01*
X1878308Y1043625D01*
X1878392Y1043250D01*
X1878517Y1043000D01*
X1878767Y1042750D01*
X1879058Y1042583D01*
X1879350Y1042500D01*
X1879642D01*
X1879933Y1042583D01*
X1880183Y1042708D01*
X1880392Y1042875D01*
G01X1882450Y1042500D02*
Y1045000D01*
X1881950Y1044500D01*
G01Y1042500D02*
X1882950D01*
G01X1885550D02*
X1885842Y1042542D01*
X1886175Y1042667D01*
X1886383Y1042875D01*
X1886467Y1043167D01*
X1886383Y1043458D01*
X1886133Y1043708D01*
X1885758Y1043833D01*
X1885342D01*
X1885092Y1043917D01*
X1884883Y1044125D01*
X1884800Y1044417D01*
X1884925Y1044708D01*
X1885217Y1044917D01*
X1885550Y1045000D01*
X1885883Y1044917D01*
X1886175Y1044708D01*
X1886300Y1044417D01*
X1886217Y1044125D01*
X1886008Y1043917D01*
X1885758Y1043833D01*
X1885342D01*
X1884967Y1043708D01*
X1884717Y1043458D01*
X1884633Y1043167D01*
X1884717Y1042875D01*
X1884925Y1042667D01*
X1885258Y1042542D01*
X1885550Y1042500D01*
G01X1887858Y1044583D02*
X1888108Y1044833D01*
X1888400Y1044958D01*
X1888733Y1045000D01*
X1889150Y1044917D01*
X1889442Y1044708D01*
X1889525Y1044458D01*
X1889483Y1044208D01*
X1889317Y1044000D01*
X1888483Y1043583D01*
X1888108Y1043292D01*
X1887858Y1042875D01*
X1887775Y1042500D01*
X1889525D01*
G01X1880267Y1048792D02*
X1880017Y1048917D01*
X1879725Y1049000D01*
X1879392D01*
X1879017Y1048875D01*
X1878725Y1048667D01*
X1878517Y1048417D01*
X1878350Y1048000D01*
X1878308Y1047625D01*
X1878392Y1047250D01*
X1878517Y1047000D01*
X1878767Y1046750D01*
X1879058Y1046583D01*
X1879350Y1046500D01*
X1879642D01*
X1879933Y1046583D01*
X1880183Y1046708D01*
X1880392Y1046875D01*
G01X1882450Y1046500D02*
Y1049000D01*
X1881950Y1048500D01*
G01Y1046500D02*
X1882950D01*
G01X1885550D02*
X1885842Y1046542D01*
X1886175Y1046667D01*
X1886383Y1046875D01*
X1886467Y1047167D01*
X1886383Y1047458D01*
X1886133Y1047708D01*
X1885758Y1047833D01*
X1885342D01*
X1885092Y1047917D01*
X1884883Y1048125D01*
X1884800Y1048417D01*
X1884925Y1048708D01*
X1885217Y1048917D01*
X1885550Y1049000D01*
X1885883Y1048917D01*
X1886175Y1048708D01*
X1886300Y1048417D01*
X1886217Y1048125D01*
X1886008Y1047917D01*
X1885758Y1047833D01*
X1885342D01*
X1884967Y1047708D01*
X1884717Y1047458D01*
X1884633Y1047167D01*
X1884717Y1046875D01*
X1884925Y1046667D01*
X1885258Y1046542D01*
X1885550Y1046500D01*
G01X1888650D02*
Y1049000D01*
X1888150Y1048500D01*
G01Y1046500D02*
X1889150D01*
G01X1866900Y1042000D02*
X1866567Y1042042D01*
X1866275Y1042208D01*
X1866025Y1042458D01*
X1865858Y1042750D01*
X1865775Y1043083D01*
Y1043417D01*
X1865858Y1043750D01*
X1866025Y1044042D01*
X1866275Y1044292D01*
X1866567Y1044458D01*
X1866900Y1044500D01*
X1867233Y1044458D01*
X1867525Y1044292D01*
X1867775Y1044042D01*
X1867942Y1043750D01*
X1868025Y1043417D01*
Y1043083D01*
X1867942Y1042750D01*
X1867775Y1042458D01*
X1867525Y1042208D01*
X1867233Y1042042D01*
X1866900Y1042000D01*
G01X1867233Y1042667D02*
X1867733Y1042000D01*
G01X1869208Y1043042D02*
X1869500Y1043333D01*
X1869750Y1043500D01*
X1870083Y1043583D01*
X1870375Y1043500D01*
X1870583Y1043333D01*
X1870750Y1043083D01*
X1870792Y1042792D01*
X1870750Y1042542D01*
X1870583Y1042292D01*
X1870333Y1042083D01*
X1870042Y1042000D01*
X1869708Y1042083D01*
X1869417Y1042333D01*
X1869250Y1042708D01*
X1869208Y1043125D01*
X1869292Y1043667D01*
X1869417Y1043958D01*
X1869625Y1044250D01*
X1869917Y1044458D01*
X1870208Y1044500D01*
X1870500Y1044417D01*
X1870708Y1044208D01*
G01X1872308Y1043042D02*
X1872600Y1043333D01*
X1872850Y1043500D01*
X1873183Y1043583D01*
X1873475Y1043500D01*
X1873683Y1043333D01*
X1873850Y1043083D01*
X1873892Y1042792D01*
X1873850Y1042542D01*
X1873683Y1042292D01*
X1873433Y1042083D01*
X1873142Y1042000D01*
X1872808Y1042083D01*
X1872517Y1042333D01*
X1872350Y1042708D01*
X1872308Y1043125D01*
X1872392Y1043667D01*
X1872517Y1043958D01*
X1872725Y1044250D01*
X1873017Y1044458D01*
X1873308Y1044500D01*
X1873600Y1044417D01*
X1873808Y1044208D01*
G01X1866267Y1052292D02*
X1866017Y1052417D01*
X1865725Y1052500D01*
X1865392D01*
X1865017Y1052375D01*
X1864725Y1052167D01*
X1864517Y1051917D01*
X1864350Y1051500D01*
X1864308Y1051125D01*
X1864392Y1050750D01*
X1864517Y1050500D01*
X1864767Y1050250D01*
X1865058Y1050083D01*
X1865350Y1050000D01*
X1865642D01*
X1865933Y1050083D01*
X1866183Y1050208D01*
X1866392Y1050375D01*
G01X1868450Y1050000D02*
Y1052500D01*
X1867950Y1052000D01*
G01Y1050000D02*
X1868950D01*
G01X1871550D02*
X1871842Y1050042D01*
X1872175Y1050167D01*
X1872383Y1050375D01*
X1872467Y1050667D01*
X1872383Y1050958D01*
X1872133Y1051208D01*
X1871758Y1051333D01*
X1871342D01*
X1871092Y1051417D01*
X1870883Y1051625D01*
X1870800Y1051917D01*
X1870925Y1052208D01*
X1871217Y1052417D01*
X1871550Y1052500D01*
X1871883Y1052417D01*
X1872175Y1052208D01*
X1872300Y1051917D01*
X1872217Y1051625D01*
X1872008Y1051417D01*
X1871758Y1051333D01*
X1871342D01*
X1870967Y1051208D01*
X1870717Y1050958D01*
X1870633Y1050667D01*
X1870717Y1050375D01*
X1870925Y1050167D01*
X1871258Y1050042D01*
X1871550Y1050000D01*
G01X1873733Y1050500D02*
X1873983Y1050208D01*
X1874317Y1050042D01*
X1874692Y1050000D01*
X1875025Y1050042D01*
X1875358Y1050250D01*
X1875567Y1050500D01*
X1875608Y1050750D01*
X1875525Y1051042D01*
X1875233Y1051250D01*
X1874942Y1051333D01*
X1874567D01*
G01X1874942D02*
X1875192Y1051458D01*
X1875400Y1051667D01*
X1875483Y1051917D01*
X1875400Y1052167D01*
X1875192Y1052375D01*
X1874817Y1052500D01*
X1874442Y1052458D01*
X1874067Y1052292D01*
G01X1880352Y1040330D02*
X1880102Y1040455D01*
X1879810Y1040538D01*
X1879477D01*
X1879102Y1040413D01*
X1878810Y1040205D01*
X1878602Y1039955D01*
X1878435Y1039538D01*
X1878393Y1039163D01*
X1878477Y1038788D01*
X1878602Y1038538D01*
X1878852Y1038288D01*
X1879143Y1038121D01*
X1879435Y1038038D01*
X1879727D01*
X1880018Y1038121D01*
X1880268Y1038246D01*
X1880477Y1038413D01*
G01X1882535Y1038038D02*
Y1040538D01*
X1882035Y1040038D01*
G01Y1038038D02*
X1883035D01*
G01X1885635D02*
X1885927Y1038080D01*
X1886260Y1038205D01*
X1886468Y1038413D01*
X1886552Y1038705D01*
X1886468Y1038996D01*
X1886218Y1039246D01*
X1885843Y1039371D01*
X1885427D01*
X1885177Y1039455D01*
X1884968Y1039663D01*
X1884885Y1039955D01*
X1885010Y1040246D01*
X1885302Y1040455D01*
X1885635Y1040538D01*
X1885968Y1040455D01*
X1886260Y1040246D01*
X1886385Y1039955D01*
X1886302Y1039663D01*
X1886093Y1039455D01*
X1885843Y1039371D01*
X1885427D01*
X1885052Y1039246D01*
X1884802Y1038996D01*
X1884718Y1038705D01*
X1884802Y1038413D01*
X1885010Y1038205D01*
X1885343Y1038080D01*
X1885635Y1038038D01*
G01X1888027Y1038330D02*
X1888318Y1038121D01*
X1888652Y1038038D01*
X1888985Y1038121D01*
X1889277Y1038371D01*
X1889485Y1038746D01*
X1889568Y1039121D01*
Y1039580D01*
X1889485Y1039955D01*
X1889277Y1040288D01*
X1889027Y1040455D01*
X1888735Y1040538D01*
X1888402Y1040455D01*
X1888152Y1040288D01*
X1887985Y1040038D01*
X1887902Y1039705D01*
X1887985Y1039413D01*
X1888193Y1039121D01*
X1888443Y1038955D01*
X1888735Y1038913D01*
X1889068Y1038996D01*
X1889318Y1039205D01*
X1889568Y1039580D01*
G01X1881553Y1145973D02*
X1889553D01*
Y1128373D01*
X1881553D01*
Y1145973D01*
G01X1879848Y1122458D02*
X1874348D01*
G01X1879848Y1130458D02*
Y1122458D01*
G01X1874348Y1130458D02*
X1879848D01*
G01X1862248D02*
X1867748D01*
G01X1862248Y1122458D02*
Y1130458D01*
G01X1867748Y1122458D02*
X1862248D01*
G01X1883979Y1105763D02*
X1881879Y1107563D01*
X1883979Y1109763D01*
G01X1884079Y1113363D02*
X1864879D01*
Y1102163D01*
X1884079D01*
Y1113363D01*
X1883679D01*
G01X1880500Y1141017D02*
X1878000D01*
Y1142058D01*
X1878125Y1142392D01*
X1878292Y1142600D01*
X1878625Y1142683D01*
X1878958Y1142600D01*
X1879167Y1142350D01*
X1879292Y1142058D01*
Y1141017D01*
G01Y1142058D02*
X1880500Y1142683D01*
G01X1880000Y1144033D02*
X1880292Y1144283D01*
X1880458Y1144617D01*
X1880500Y1144992D01*
X1880458Y1145325D01*
X1880250Y1145658D01*
X1880000Y1145867D01*
X1879750Y1145908D01*
X1879458Y1145825D01*
X1879250Y1145533D01*
X1879167Y1145242D01*
Y1144867D01*
G01Y1145242D02*
X1879042Y1145492D01*
X1878833Y1145700D01*
X1878583Y1145783D01*
X1878333Y1145700D01*
X1878125Y1145492D01*
X1878000Y1145117D01*
X1878042Y1144742D01*
X1878208Y1144367D01*
G01X1880500Y1148050D02*
X1880458Y1148342D01*
X1880333Y1148675D01*
X1880125Y1148883D01*
X1879833Y1148967D01*
X1879542Y1148883D01*
X1879292Y1148633D01*
X1879167Y1148258D01*
Y1147842D01*
X1879083Y1147592D01*
X1878875Y1147383D01*
X1878583Y1147300D01*
X1878292Y1147425D01*
X1878083Y1147717D01*
X1878000Y1148050D01*
X1878083Y1148383D01*
X1878292Y1148675D01*
X1878583Y1148800D01*
X1878875Y1148717D01*
X1879083Y1148508D01*
X1879167Y1148258D01*
Y1147842D01*
X1879292Y1147467D01*
X1879542Y1147217D01*
X1879833Y1147133D01*
X1880125Y1147217D01*
X1880333Y1147425D01*
X1880458Y1147758D01*
X1880500Y1148050D01*
G01X1878417Y1150358D02*
X1878167Y1150608D01*
X1878042Y1150900D01*
X1878000Y1151233D01*
X1878083Y1151650D01*
X1878292Y1151942D01*
X1878542Y1152025D01*
X1878792Y1151983D01*
X1879000Y1151817D01*
X1879417Y1150983D01*
X1879708Y1150608D01*
X1880125Y1150358D01*
X1880500Y1150275D01*
Y1152025D01*
G01X1872017Y1166000D02*
Y1168500D01*
X1873058D01*
X1873392Y1168375D01*
X1873600Y1168208D01*
X1873683Y1167875D01*
X1873600Y1167542D01*
X1873350Y1167333D01*
X1873058Y1167208D01*
X1872017D01*
G01X1873058D02*
X1873683Y1166000D01*
G01X1875033Y1166500D02*
X1875283Y1166208D01*
X1875617Y1166042D01*
X1875992Y1166000D01*
X1876325Y1166042D01*
X1876658Y1166250D01*
X1876867Y1166500D01*
X1876908Y1166750D01*
X1876825Y1167042D01*
X1876533Y1167250D01*
X1876242Y1167333D01*
X1875867D01*
G01X1876242D02*
X1876492Y1167458D01*
X1876700Y1167667D01*
X1876783Y1167917D01*
X1876700Y1168167D01*
X1876492Y1168375D01*
X1876117Y1168500D01*
X1875742Y1168458D01*
X1875367Y1168292D01*
G01X1879050Y1166000D02*
X1879342Y1166042D01*
X1879675Y1166167D01*
X1879883Y1166375D01*
X1879967Y1166667D01*
X1879883Y1166958D01*
X1879633Y1167208D01*
X1879258Y1167333D01*
X1878842D01*
X1878592Y1167417D01*
X1878383Y1167625D01*
X1878300Y1167917D01*
X1878425Y1168208D01*
X1878717Y1168417D01*
X1879050Y1168500D01*
X1879383Y1168417D01*
X1879675Y1168208D01*
X1879800Y1167917D01*
X1879717Y1167625D01*
X1879508Y1167417D01*
X1879258Y1167333D01*
X1878842D01*
X1878467Y1167208D01*
X1878217Y1166958D01*
X1878133Y1166667D01*
X1878217Y1166375D01*
X1878425Y1166167D01*
X1878758Y1166042D01*
X1879050Y1166000D01*
G01X1882650D02*
Y1168500D01*
X1881108Y1166708D01*
X1883192D01*
G01X1871984Y1156157D02*
Y1164157D01*
X1889584D01*
Y1156157D01*
X1871984D01*
G01X1871042Y1150058D02*
Y1164058D01*
G01X1874208Y1142767D02*
X1874083Y1142517D01*
X1874000Y1142225D01*
Y1141892D01*
X1874125Y1141517D01*
X1874333Y1141225D01*
X1874583Y1141017D01*
X1875000Y1140850D01*
X1875375Y1140808D01*
X1875750Y1140892D01*
X1876000Y1141017D01*
X1876250Y1141267D01*
X1876417Y1141558D01*
X1876500Y1141850D01*
Y1142142D01*
X1876417Y1142433D01*
X1876292Y1142683D01*
X1876125Y1142892D01*
G01X1876500Y1144950D02*
X1874000D01*
X1874500Y1144450D01*
G01X1876500D02*
Y1145450D01*
G01Y1148050D02*
X1876458Y1148342D01*
X1876333Y1148675D01*
X1876125Y1148883D01*
X1875833Y1148967D01*
X1875542Y1148883D01*
X1875292Y1148633D01*
X1875167Y1148258D01*
Y1147842D01*
X1875083Y1147592D01*
X1874875Y1147383D01*
X1874583Y1147300D01*
X1874292Y1147425D01*
X1874083Y1147717D01*
X1874000Y1148050D01*
X1874083Y1148383D01*
X1874292Y1148675D01*
X1874583Y1148800D01*
X1874875Y1148717D01*
X1875083Y1148508D01*
X1875167Y1148258D01*
Y1147842D01*
X1875292Y1147467D01*
X1875542Y1147217D01*
X1875833Y1147133D01*
X1876125Y1147217D01*
X1876333Y1147425D01*
X1876458Y1147758D01*
X1876500Y1148050D01*
G01Y1151150D02*
X1876458Y1151442D01*
X1876333Y1151775D01*
X1876125Y1151983D01*
X1875833Y1152067D01*
X1875542Y1151983D01*
X1875292Y1151733D01*
X1875167Y1151358D01*
Y1150942D01*
X1875083Y1150692D01*
X1874875Y1150483D01*
X1874583Y1150400D01*
X1874292Y1150525D01*
X1874083Y1150817D01*
X1874000Y1151150D01*
X1874083Y1151483D01*
X1874292Y1151775D01*
X1874583Y1151900D01*
X1874875Y1151817D01*
X1875083Y1151608D01*
X1875167Y1151358D01*
Y1150942D01*
X1875292Y1150567D01*
X1875542Y1150317D01*
X1875833Y1150233D01*
X1876125Y1150317D01*
X1876333Y1150525D01*
X1876458Y1150858D01*
X1876500Y1151150D01*
G01X1873000Y1141900D02*
X1872958Y1141567D01*
X1872792Y1141275D01*
X1872542Y1141025D01*
X1872250Y1140858D01*
X1871917Y1140775D01*
X1871583D01*
X1871250Y1140858D01*
X1870958Y1141025D01*
X1870708Y1141275D01*
X1870542Y1141567D01*
X1870500Y1141900D01*
X1870542Y1142233D01*
X1870708Y1142525D01*
X1870958Y1142775D01*
X1871250Y1142942D01*
X1871583Y1143025D01*
X1871917D01*
X1872250Y1142942D01*
X1872542Y1142775D01*
X1872792Y1142525D01*
X1872958Y1142233D01*
X1873000Y1141900D01*
G01X1872333Y1142233D02*
X1873000Y1142733D01*
G01X1871958Y1144208D02*
X1871667Y1144500D01*
X1871500Y1144750D01*
X1871417Y1145083D01*
X1871500Y1145375D01*
X1871667Y1145583D01*
X1871917Y1145750D01*
X1872208Y1145792D01*
X1872458Y1145750D01*
X1872708Y1145583D01*
X1872917Y1145333D01*
X1873000Y1145042D01*
X1872917Y1144708D01*
X1872667Y1144417D01*
X1872292Y1144250D01*
X1871875Y1144208D01*
X1871333Y1144292D01*
X1871042Y1144417D01*
X1870750Y1144625D01*
X1870542Y1144917D01*
X1870500Y1145208D01*
X1870583Y1145500D01*
X1870792Y1145708D01*
G01X1873000Y1148100D02*
X1872958Y1148392D01*
X1872833Y1148725D01*
X1872625Y1148933D01*
X1872333Y1149017D01*
X1872042Y1148933D01*
X1871792Y1148683D01*
X1871667Y1148308D01*
Y1147892D01*
X1871583Y1147642D01*
X1871375Y1147433D01*
X1871083Y1147350D01*
X1870792Y1147475D01*
X1870583Y1147767D01*
X1870500Y1148100D01*
X1870583Y1148433D01*
X1870792Y1148725D01*
X1871083Y1148850D01*
X1871375Y1148767D01*
X1871583Y1148558D01*
X1871667Y1148308D01*
Y1147892D01*
X1871792Y1147517D01*
X1872042Y1147267D01*
X1872333Y1147183D01*
X1872625Y1147267D01*
X1872833Y1147475D01*
X1872958Y1147808D01*
X1873000Y1148100D01*
G01X1879350Y1178000D02*
Y1175500D01*
G01X1878392Y1178000D02*
X1880308D01*
G01X1881617Y1175500D02*
Y1178000D01*
X1882617D01*
X1882950Y1177875D01*
X1883200Y1177583D01*
X1883283Y1177250D01*
X1883200Y1176917D01*
X1882992Y1176667D01*
X1882617Y1176542D01*
X1881617D01*
G01X1884633Y1175875D02*
X1884883Y1175667D01*
X1885175Y1175542D01*
X1885550Y1175500D01*
X1885925Y1175583D01*
X1886217Y1175750D01*
X1886425Y1176042D01*
X1886467Y1176375D01*
X1886383Y1176708D01*
X1886175Y1176917D01*
X1885883Y1177083D01*
X1885592Y1177125D01*
X1885300Y1177083D01*
X1884925Y1176917D01*
X1885050Y1178000D01*
X1886175D01*
G01X1888567Y1175500D02*
X1888650Y1176042D01*
X1888775Y1176500D01*
X1888942Y1176917D01*
X1889150Y1177375D01*
X1889483Y1178000D01*
X1887817D01*
G01X1876708Y1182267D02*
X1876583Y1182017D01*
X1876500Y1181725D01*
Y1181392D01*
X1876625Y1181017D01*
X1876833Y1180725D01*
X1877083Y1180517D01*
X1877500Y1180350D01*
X1877875Y1180308D01*
X1878250Y1180392D01*
X1878500Y1180517D01*
X1878750Y1180767D01*
X1878917Y1181058D01*
X1879000Y1181350D01*
Y1181642D01*
X1878917Y1181933D01*
X1878792Y1182183D01*
X1878625Y1182392D01*
G01X1879000Y1184450D02*
X1876500D01*
X1877000Y1183950D01*
G01X1879000D02*
Y1184950D01*
G01Y1187550D02*
X1878958Y1187842D01*
X1878833Y1188175D01*
X1878625Y1188383D01*
X1878333Y1188467D01*
X1878042Y1188383D01*
X1877792Y1188133D01*
X1877667Y1187758D01*
Y1187342D01*
X1877583Y1187092D01*
X1877375Y1186883D01*
X1877083Y1186800D01*
X1876792Y1186925D01*
X1876583Y1187217D01*
X1876500Y1187550D01*
X1876583Y1187883D01*
X1876792Y1188175D01*
X1877083Y1188300D01*
X1877375Y1188217D01*
X1877583Y1188008D01*
X1877667Y1187758D01*
Y1187342D01*
X1877792Y1186967D01*
X1878042Y1186717D01*
X1878333Y1186633D01*
X1878625Y1186717D01*
X1878833Y1186925D01*
X1878958Y1187258D01*
X1879000Y1187550D01*
G01Y1190567D02*
X1878458Y1190650D01*
X1878000Y1190775D01*
X1877583Y1190942D01*
X1877125Y1191150D01*
X1876500Y1191483D01*
Y1189817D01*
G01X1881208Y1196267D02*
X1881083Y1196017D01*
X1881000Y1195725D01*
Y1195392D01*
X1881125Y1195017D01*
X1881333Y1194725D01*
X1881583Y1194517D01*
X1882000Y1194350D01*
X1882375Y1194308D01*
X1882750Y1194392D01*
X1883000Y1194517D01*
X1883250Y1194767D01*
X1883417Y1195058D01*
X1883500Y1195350D01*
Y1195642D01*
X1883417Y1195933D01*
X1883292Y1196183D01*
X1883125Y1196392D01*
G01X1883500Y1198450D02*
X1881000D01*
X1881500Y1197950D01*
G01X1883500D02*
Y1198950D01*
G01X1883208Y1200842D02*
X1883417Y1201133D01*
X1883500Y1201467D01*
X1883417Y1201800D01*
X1883167Y1202092D01*
X1882792Y1202300D01*
X1882417Y1202383D01*
X1881958D01*
X1881583Y1202300D01*
X1881250Y1202092D01*
X1881083Y1201842D01*
X1881000Y1201550D01*
X1881083Y1201217D01*
X1881250Y1200967D01*
X1881500Y1200800D01*
X1881833Y1200717D01*
X1882125Y1200800D01*
X1882417Y1201008D01*
X1882583Y1201258D01*
X1882625Y1201550D01*
X1882542Y1201883D01*
X1882333Y1202133D01*
X1881958Y1202383D01*
G01X1881000Y1204650D02*
X1881083Y1204317D01*
X1881292Y1204067D01*
X1881542Y1203900D01*
X1881875Y1203775D01*
X1882250Y1203733D01*
X1882625Y1203775D01*
X1882958Y1203900D01*
X1883208Y1204067D01*
X1883417Y1204317D01*
X1883500Y1204650D01*
X1883417Y1204983D01*
X1883208Y1205233D01*
X1882958Y1205400D01*
X1882625Y1205525D01*
X1882250Y1205567D01*
X1881875Y1205525D01*
X1881542Y1205400D01*
X1881292Y1205233D01*
X1881083Y1204983D01*
X1881000Y1204650D01*
G01X1891031Y1234004D02*
Y1236504D01*
G01X1892781D02*
Y1234004D01*
G01Y1235254D02*
X1891031D01*
G01X1894089Y1234004D02*
Y1236504D01*
X1894923D01*
X1895256Y1236379D01*
X1895506Y1236212D01*
X1895714Y1235962D01*
X1895881Y1235671D01*
X1895923Y1235254D01*
X1895881Y1234837D01*
X1895714Y1234546D01*
X1895506Y1234296D01*
X1895256Y1234129D01*
X1894923Y1234004D01*
X1894089D01*
G01X1897189D02*
Y1236504D01*
X1898023D01*
X1898356Y1236379D01*
X1898606Y1236212D01*
X1898814Y1235962D01*
X1898981Y1235671D01*
X1899023Y1235254D01*
X1898981Y1234837D01*
X1898814Y1234546D01*
X1898606Y1234296D01*
X1898356Y1234129D01*
X1898023Y1234004D01*
X1897189D01*
G01X1900331Y1234337D02*
X1900664Y1234129D01*
X1901039Y1234004D01*
X1901373D01*
X1901706Y1234129D01*
X1901956Y1234337D01*
X1902081Y1234629D01*
X1901998Y1234921D01*
X1901789Y1235171D01*
X1901414Y1235337D01*
X1900914Y1235421D01*
X1900623Y1235587D01*
X1900498Y1235879D01*
X1900581Y1236171D01*
X1900789Y1236379D01*
X1901081Y1236504D01*
X1901373D01*
X1901664Y1236421D01*
X1901914Y1236212D01*
G01X1903264Y1234004D02*
X1904306Y1236504D01*
X1905348Y1234004D01*
G01X1904973Y1234879D02*
X1903639D01*
G01X1906531Y1234337D02*
X1906864Y1234129D01*
X1907239Y1234004D01*
X1907573D01*
X1907906Y1234129D01*
X1908156Y1234337D01*
X1908281Y1234629D01*
X1908198Y1234921D01*
X1907989Y1235171D01*
X1907614Y1235337D01*
X1907114Y1235421D01*
X1906823Y1235587D01*
X1906698Y1235879D01*
X1906781Y1236171D01*
X1906989Y1236379D01*
X1907281Y1236504D01*
X1907573D01*
X1907864Y1236421D01*
X1908114Y1236212D01*
G01X1910506Y1234004D02*
Y1236504D01*
X1910006Y1236004D01*
G01Y1234004D02*
X1911006D01*
G01X1913606D02*
Y1236504D01*
X1913106Y1236004D01*
G01Y1234004D02*
X1914106D01*
G54D13*
G01X1082000Y1152000D02*
X1076000D01*
Y1155500D01*
G01X1082000Y1414500D02*
X1076000D01*
Y1411000D01*
G01X1143500Y1152000D02*
X1149500D01*
Y1155500D01*
G01X1143500Y1414500D02*
X1149500D01*
Y1411000D01*
G54D23*
G01X24200Y1198000D02*
X23100D01*
G01X70600Y501000D02*
X71700D01*
G01X68300D02*
X69400D01*
G01X65600D02*
X66700D01*
G01X70600Y953755D02*
X71700D01*
G01X68300D02*
X69400D01*
G01X65600D02*
X66700D01*
G01X29200Y1198000D02*
X28100D01*
G01X31900D02*
X30800D01*
G01X26900D02*
X25800D01*
G01X80437Y245161D02*
Y249161D01*
G01X93437Y293161D02*
X97437D01*
G01X73300Y501000D02*
X74400D01*
G01X80437Y697917D02*
Y701917D01*
G01X93437Y745917D02*
X97437D01*
G01X73300Y953755D02*
X74400D01*
G01X80437Y1150673D02*
Y1154673D01*
G01X93437Y1198673D02*
X97437D01*
G01X142437Y254261D02*
Y255361D01*
G01Y256961D02*
Y258061D01*
G01Y709717D02*
Y710817D01*
G01Y707017D02*
Y708117D01*
G01X126863Y976825D02*
X127963D01*
G01X124163D02*
X125263D01*
G01X128063Y995225D02*
Y999225D01*
G01X142437Y1162473D02*
Y1163573D01*
G01Y1159773D02*
Y1160873D01*
G01X134622Y1198537D02*
X133522D01*
G01X137322D02*
X136222D01*
G01X139622D02*
X138522D01*
G01X142322D02*
X141222D01*
G01X204649Y245161D02*
Y249161D01*
G01X197512Y501000D02*
X198612D01*
G01X194812D02*
X195912D01*
G01X192512D02*
X193612D01*
G01X189812D02*
X190912D01*
G01X193563Y564825D02*
X194663D01*
G01X190863D02*
X191963D01*
G01X194763Y583225D02*
Y587225D01*
G01X204649Y697917D02*
Y701917D01*
G01X217512Y953555D02*
X218612D01*
G01X214812D02*
X215912D01*
G01X204649Y1150673D02*
Y1154673D01*
G01X217649Y293161D02*
X221649D01*
G01X217649Y745917D02*
X221649D01*
G01X222512Y953555D02*
X223612D01*
G01X219812D02*
X220912D01*
G01X258794Y1198368D02*
X257694D01*
G01X261494D02*
X260394D01*
G01X263794D02*
X262694D01*
G01X266494D02*
X265394D01*
G01X217649Y1198673D02*
X221649D01*
G01X315312Y106031D02*
X311312D01*
G01X266649Y254261D02*
Y255361D01*
G01Y256961D02*
Y258061D01*
G01X314025Y501000D02*
X315125D01*
G01X266649Y709717D02*
Y710817D01*
G01Y707017D02*
Y708117D01*
G01X314025Y953755D02*
X315125D01*
G01X266649Y1162473D02*
Y1163573D01*
G01Y1159773D02*
Y1160873D01*
G01X328862Y245161D02*
Y249161D01*
G01X341862Y293161D02*
X345862D01*
G01X321725Y501000D02*
X322825D01*
G01X319025D02*
X320125D01*
G01X316725D02*
X317825D01*
G01X328862Y697917D02*
Y701917D01*
G01X341862Y745917D02*
X345862D01*
G01X321725Y953755D02*
X322825D01*
G01X319025D02*
X320125D01*
G01X316725D02*
X317825D01*
G01X328862Y1150673D02*
Y1154673D01*
G01X341862Y1198673D02*
X345862D01*
G01X390862Y254261D02*
Y255361D01*
G01Y256961D02*
Y258061D01*
G01Y709717D02*
Y710817D01*
G01Y707017D02*
Y708117D01*
G01X390662Y1162473D02*
Y1163573D01*
G01Y1159773D02*
Y1160873D01*
G01X383049Y1198242D02*
X381949D01*
G01X385749D02*
X384649D01*
G01X388049D02*
X386949D01*
G01X390749D02*
X389649D01*
G01X453074Y245161D02*
Y249161D01*
G01X445938Y501000D02*
X447038D01*
G01X443238D02*
X444338D01*
G01X440938D02*
X442038D01*
G01X438238D02*
X439338D01*
G01X453074Y697917D02*
Y701917D01*
G01X445938Y953755D02*
X447038D01*
G01X443238D02*
X444338D01*
G01X440938D02*
X442038D01*
G01X438238D02*
X439338D01*
G01X466074Y293161D02*
X470074D01*
G01X466074Y745917D02*
X470074D01*
G01X502874Y1128973D02*
Y1130073D01*
G01Y1131673D02*
Y1132773D01*
G01X507303Y1198157D02*
X506203D01*
G01X466074Y1198673D02*
X470074D01*
G01X515074Y256961D02*
Y258061D01*
G01Y254261D02*
Y255361D01*
G01X540150Y501000D02*
X541250D01*
G01X537450D02*
X538550D01*
G01X535150D02*
X536250D01*
G01X532450D02*
X533550D01*
G01X521279Y561713D02*
X522379D01*
G01X518579D02*
X519679D01*
G01X527297Y551231D02*
Y555231D01*
G01X515074Y709717D02*
Y710817D01*
G01Y707017D02*
Y708117D01*
G01X528674Y1154773D02*
Y1150773D01*
G01X510003Y1198157D02*
X508903D01*
G01X512303D02*
X511203D01*
G01X515003D02*
X513903D01*
G01X577287Y245161D02*
Y249161D01*
G01X590287Y293161D02*
X594287D01*
G01X572529Y504627D02*
Y508627D01*
G01X595779Y545831D02*
Y549831D01*
G01X582279Y569831D02*
X586279D01*
G01X577287Y697917D02*
Y701917D01*
G01X590287Y745917D02*
X594287D01*
G01X570150Y953755D02*
X571250D01*
G01X567450D02*
X568550D01*
G01X565150D02*
X566250D01*
G01X562450D02*
X563550D01*
G01X577287Y1150673D02*
Y1154673D01*
G01X590287Y1198673D02*
X594287D01*
G01X639287Y256961D02*
Y258061D01*
G01Y254261D02*
Y255361D01*
G01X650763Y509000D02*
X651863D01*
G01X648463D02*
X649563D01*
G01X645763D02*
X646863D01*
G01X609460Y553274D02*
X605460D01*
G01Y563774D02*
X609460D01*
G01X639287Y709717D02*
Y710817D01*
G01Y707017D02*
Y708117D01*
G01Y1162473D02*
Y1163573D01*
G01Y1159773D02*
Y1160873D01*
G01X631516Y1198074D02*
X630416D01*
G01X634216D02*
X633116D01*
G01X636516D02*
X635416D01*
G01X639216D02*
X638116D01*
G01X653463Y509000D02*
X654563D01*
G01X694363Y953755D02*
X695463D01*
G01X691663D02*
X692763D01*
G01X689363D02*
X690463D01*
G01X686663D02*
X687763D01*
G01X750409Y162628D02*
X749309D01*
G01X701500Y245161D02*
Y249161D01*
G01X714500Y293161D02*
X718500D01*
G01X747100Y669000D02*
X748200D01*
G01X701500Y697917D02*
Y701917D01*
G01X714500Y745917D02*
X718500D01*
G01X701500Y1150673D02*
Y1154673D01*
G01X714500Y1198673D02*
X718500D01*
G01X753109Y162628D02*
X752009D01*
G01X749800Y669000D02*
X750900D01*
G01X751700Y1160500D02*
X750600D01*
G01X754400D02*
X753300D01*
G01X830308Y39372D02*
Y35372D01*
G01X865577Y39234D02*
Y35234D01*
G01X867663Y841553D02*
X863663D01*
G01X879256Y1367950D02*
X883256D01*
G01X871600Y1480760D02*
Y1484760D01*
G01X893500Y1536918D02*
X894600D01*
G01X890800D02*
X891900D01*
G01X931524Y924900D02*
X935524D01*
G01X946776Y938000D02*
X942776D01*
G01X941000Y1010200D02*
X937000D01*
G01X935009Y993763D02*
Y989763D01*
G01X912082Y1536500D02*
Y1532500D01*
G01X989970Y1011007D02*
X985970D01*
G01X954813Y1493424D02*
Y1497424D01*
G01X969813Y1546166D02*
X965813D01*
G01Y1556766D02*
X969813D01*
G01X951500Y1556200D02*
X955500D01*
G01X965001Y1531926D02*
Y1535926D01*
G01X1029063Y857853D02*
X1025063D01*
G01X1011700Y933000D02*
Y937000D01*
G01X1019000Y1102000D02*
X1015000D01*
G01X1066500Y1103000D02*
X1062500D01*
G01X1095000Y-45600D02*
X1096100D01*
G01X1092300D02*
X1093400D01*
G01X1110300Y-46400D02*
Y-50400D01*
G01X1109100Y1102900D02*
X1105100D01*
G01X1210405Y1159194D02*
X1209305D01*
G01X1213105D02*
X1212005D01*
G01X1215405D02*
X1214305D01*
G01X1218105D02*
X1217005D01*
G01X1253500Y255361D02*
Y254261D01*
G01Y258061D02*
Y256961D01*
G01X1270678Y501421D02*
X1271778D01*
G01X1267978D02*
X1269078D01*
G01X1265678D02*
X1266778D01*
G01X1262978D02*
X1264078D01*
G01X1251500Y708117D02*
Y707017D01*
G01Y710817D02*
Y709717D01*
G01X1269542Y953586D02*
X1270642D01*
G01X1266842D02*
X1267942D01*
G01X1264542D02*
X1265642D01*
G01X1261842D02*
X1262942D01*
G01X1252800Y1161000D02*
Y1159900D01*
G01Y1163700D02*
Y1162600D01*
G01X1314999Y114125D02*
X1310999D01*
G01X1296500Y292661D02*
X1300500D01*
G01X1296500Y263161D02*
X1300500D01*
G01X1296500Y715917D02*
X1300500D01*
G01X1296500Y745417D02*
X1300500D01*
G01X1296500Y1168673D02*
X1300500D01*
G01X1296500Y1198173D02*
X1300500D01*
G01X1377713Y255361D02*
Y254261D01*
G01Y258061D02*
Y256961D01*
G01X1365682Y501000D02*
X1366782D01*
G01X1362982D02*
X1364082D01*
G01X1360682D02*
X1361782D01*
G01X1357982D02*
X1359082D01*
G01X1375713Y708117D02*
Y707017D01*
G01Y710817D02*
Y709717D01*
G01X1368182Y953755D02*
X1369282D01*
G01X1365482D02*
X1366582D01*
G01X1363182D02*
X1364282D01*
G01X1360482D02*
X1361582D01*
G01X1350521Y1159153D02*
X1349421D01*
G01X1353221D02*
X1352121D01*
G01X1345521D02*
X1344421D01*
G01X1348221D02*
X1347121D01*
G01X1377000Y1160900D02*
Y1159800D01*
G01Y1163600D02*
Y1162500D01*
G01X1420713Y292661D02*
X1424713D01*
G01X1420713Y263161D02*
X1424713D01*
G01X1424419Y529757D02*
X1428419D01*
G01Y519257D02*
X1424419D01*
G01X1420713Y715917D02*
X1424713D01*
G01X1420713Y745417D02*
X1424713D01*
G01X1420713Y1168673D02*
X1424713D01*
G01X1420713Y1198173D02*
X1424713D01*
G01X1445700Y522600D02*
X1441700D01*
G01X1432200Y546600D02*
Y542600D01*
G01X1457261Y590256D02*
Y586256D01*
G01X1470153Y1159027D02*
X1469053D01*
G01X1472853D02*
X1471753D01*
G01X1475153D02*
X1474053D01*
G01X1500025Y255261D02*
Y254161D01*
G01Y257961D02*
Y256861D01*
G01X1492394Y501000D02*
X1493494D01*
G01X1489694D02*
X1490794D01*
G01X1487394D02*
X1488494D01*
G01X1484694D02*
X1485794D01*
G01X1506237Y530903D02*
X1505137D01*
G01X1508937D02*
X1507837D01*
G01X1500882Y541100D02*
Y537100D01*
G01X1499925Y708117D02*
Y707017D01*
G01Y710817D02*
Y709717D01*
G01X1492394Y953755D02*
X1493494D01*
G01X1489694D02*
X1490794D01*
G01X1487394D02*
X1488494D01*
G01X1484694D02*
X1485794D01*
G01X1477853Y1159027D02*
X1476753D01*
G01X1501700Y1160900D02*
Y1159800D01*
G01Y1163600D02*
Y1162500D01*
G01X1544925Y292661D02*
X1548925D01*
G01X1544925Y263161D02*
X1548925D01*
G01X1544925Y715917D02*
X1548925D01*
G01X1544925Y745417D02*
X1548925D01*
G01X1544925Y1168673D02*
X1548925D01*
G01X1544925Y1198173D02*
X1548925D01*
G01X1616607Y501000D02*
X1617707D01*
G01X1613907D02*
X1615007D01*
G01X1611607D02*
X1612707D01*
G01X1608907D02*
X1610007D01*
G01X1616607Y953755D02*
X1617707D01*
G01X1613907D02*
X1615007D01*
G01X1611607D02*
X1612707D01*
G01X1608907D02*
X1610007D01*
G01X1614752Y1159206D02*
X1613652D01*
G01X1617452D02*
X1616352D01*
G01X1619436D02*
X1618336D01*
G01X1625738Y255261D02*
Y254161D01*
G01Y257961D02*
Y256861D01*
G01X1624138Y708117D02*
Y707017D01*
G01Y710817D02*
Y709717D01*
G01X1622136Y1159206D02*
X1621036D01*
G01X1636138Y1160873D02*
Y1159773D01*
G01Y1163573D02*
Y1162473D01*
G01X1669138Y292661D02*
X1673138D01*
G01X1669138Y263161D02*
X1673138D01*
G01X1669138Y715917D02*
X1673138D01*
G01X1669138Y745417D02*
X1673138D01*
G01X1717317Y1159153D02*
X1716217D01*
G01X1669138Y1168673D02*
X1673138D01*
G01X1669138Y1198173D02*
X1673138D01*
G01X1750550Y255261D02*
Y254161D01*
G01Y257961D02*
Y256861D01*
G01X1740819Y501000D02*
X1741919D01*
G01X1738119D02*
X1739219D01*
G01X1735819D02*
X1736919D01*
G01X1733119D02*
X1734219D01*
G01X1759700Y728000D02*
X1758600D01*
G01X1762400D02*
X1761300D01*
G01X1740819Y953755D02*
X1741919D01*
G01X1738119D02*
X1739219D01*
G01X1735819D02*
X1736919D01*
G01X1733119D02*
X1734219D01*
G01X1722317Y1159153D02*
X1721217D01*
G01X1725017D02*
X1723917D01*
G01X1720017D02*
X1718917D01*
G01X1749700Y1161000D02*
Y1159900D01*
G01Y1163700D02*
Y1162600D01*
G01X1793350Y292661D02*
X1797350D01*
G01X1793350Y263161D02*
X1797350D01*
G01X1793350Y715917D02*
X1797350D01*
G01X1793468Y745594D02*
X1797468D01*
G01X1783466Y953744D02*
X1784566D01*
G01X1780766D02*
X1781866D01*
G01X1778466D02*
X1779566D01*
G01X1775766D02*
X1776866D01*
G01X1768663Y988825D02*
X1769763D01*
G01X1765963D02*
X1767063D01*
G01X1769863Y1007225D02*
Y1011225D01*
G01X1793350Y1168673D02*
X1797350D01*
G01X1793350Y1198173D02*
X1797350D01*
G01X1860032Y501000D02*
X1861132D01*
G01X1857332D02*
X1858432D01*
G01X1835600Y1158700D02*
X1834500D01*
G01X1838300D02*
X1837200D01*
G01X1840284Y1158721D02*
X1839184D01*
G01X1842984D02*
X1841884D01*
G01X1870300Y187744D02*
X1871400D01*
G01X1867600D02*
X1868700D01*
G01X1872169Y245161D02*
Y249161D01*
G01X1885169Y293161D02*
X1889169D01*
G01X1865032Y501000D02*
X1866132D01*
G01X1862332D02*
X1863432D01*
G01X1870300Y640500D02*
X1871400D01*
G01X1867600D02*
X1868700D01*
G01X1872169Y697917D02*
Y701917D01*
G01X1885169Y745917D02*
X1889169D01*
G01X1884332Y1055027D02*
Y1056127D01*
G01Y1052327D02*
Y1053427D01*
G01X1873648Y1131143D02*
Y1135143D01*
G01X1885169Y1198673D02*
X1889169D01*
G54D14*
G01X124174Y166942D02*
Y163942D01*
G01Y619698D02*
Y616698D01*
G01Y1072454D02*
Y1069454D01*
G01X248386Y166942D02*
Y163942D01*
G01Y619698D02*
Y616698D01*
G01Y1072454D02*
Y1069454D01*
G01X349321Y64095D02*
Y61245D01*
X346621D01*
G01X372599Y166942D02*
Y163942D01*
G01Y619698D02*
Y616698D01*
G01Y1072454D02*
Y1069454D01*
G01X496811Y166942D02*
Y163942D01*
G01Y619698D02*
Y616698D01*
G01Y1072454D02*
Y1069454D01*
G01X533021Y547256D02*
Y550106D01*
X535721D01*
G01X621024Y166942D02*
Y163942D01*
G01Y619698D02*
Y616698D01*
G01X643992Y603336D02*
Y607636D01*
X647792D01*
G01X621024Y1072454D02*
Y1069454D01*
G01X672102Y112810D02*
Y115660D01*
X674802D01*
G01X693544Y593726D02*
Y599776D01*
X688294D01*
G01X745237Y166942D02*
Y163942D01*
G01Y619698D02*
Y616698D01*
G01Y1072454D02*
Y1069454D01*
G01X803914Y34017D02*
X799814D01*
Y29767D01*
G01X837658Y1533291D02*
Y1536141D01*
X840358D01*
G01X904100Y1525100D02*
Y1527950D01*
X906800D01*
G01X963163Y-128307D02*
X960163D01*
G01X972955Y1161803D02*
X970105D01*
Y1164503D01*
G01X1033020Y-65655D02*
X1029020D01*
Y-59855D01*
G01X1029905Y1478111D02*
X1025605D01*
Y1481911D01*
G01X1002105Y1478111D02*
X997805D01*
Y1481911D01*
G01X1029536Y1515197D02*
X1035636D01*
Y1521247D01*
G01X1055533Y-70897D02*
X1051533D01*
Y-65097D01*
G01X1057705Y1478111D02*
X1053405D01*
Y1481911D01*
G01X1244250Y230700D02*
Y227850D01*
X1241550D01*
G01X1325695Y61279D02*
X1322845D01*
Y63979D01*
G01X1294843Y166942D02*
Y163942D01*
G01Y619698D02*
Y616698D01*
G01Y1072454D02*
Y1069454D01*
G01X1376050Y536500D02*
X1371750D01*
Y540300D01*
G01X1419056Y166942D02*
Y163942D01*
G01X1385050Y583600D02*
X1379000D01*
Y578350D01*
G01X1419056Y619698D02*
Y616698D01*
G01Y1072454D02*
Y1069454D01*
G01X1494958Y545175D02*
Y542325D01*
X1492258D01*
G01X1543268Y166942D02*
Y163942D01*
G01Y619698D02*
Y616698D01*
G01Y1072454D02*
Y1069454D01*
G01X1667481Y166942D02*
Y163942D01*
G01Y619698D02*
Y616698D01*
G01Y1072454D02*
Y1069454D01*
G01X1791693Y166942D02*
Y163942D01*
G01Y619698D02*
Y616698D01*
G01Y1072454D02*
Y1069454D01*
G01X1915906Y166942D02*
Y163942D01*
G01Y619698D02*
Y616698D01*
G01Y1072454D02*
Y1069454D01*
G54D15*
G01X23622Y0D02*
X54331D01*
G01Y1374803D02*
X23622D01*
G01X48087Y222111D02*
Y229861D01*
G01Y674867D02*
Y682617D01*
G01Y1127623D02*
Y1135373D01*
G01X91787Y231211D02*
Y223461D01*
G01Y683967D02*
Y676217D01*
G01Y1136723D02*
Y1128973D01*
G01X172299Y222111D02*
Y229861D01*
G01X215999Y231211D02*
Y223461D01*
G01X172299Y674867D02*
Y682617D01*
G01X215999Y683967D02*
Y676217D01*
G01X172299Y1127623D02*
Y1135373D01*
G01X215999Y1136723D02*
Y1128973D01*
G01X296512Y222111D02*
Y229861D01*
G01Y674867D02*
Y682617D01*
G01Y1127623D02*
Y1135373D01*
G01X323229Y0D02*
X362599D01*
G01X340212Y231211D02*
Y223461D01*
G01Y683967D02*
Y676217D01*
G01Y1136723D02*
Y1128973D01*
G01X353740Y1374803D02*
X393110D01*
G01X420724Y222111D02*
Y229861D01*
G01Y674867D02*
Y682617D01*
G01X444250Y1126650D02*
Y1134400D01*
G01X464424Y231211D02*
Y223461D01*
G01Y683967D02*
Y676217D01*
G01X544937Y222111D02*
Y229861D01*
G01Y674867D02*
Y682617D01*
G01Y1127623D02*
Y1135373D01*
G01X532324Y1136623D02*
Y1128873D01*
G01X588637Y231211D02*
Y223461D01*
G01Y683967D02*
Y676217D01*
G01Y1136723D02*
Y1128973D01*
G01X659474Y0D02*
X628765D01*
G01X669150Y222111D02*
Y229861D01*
G01Y674867D02*
Y682617D01*
G01Y1127623D02*
Y1135373D01*
G01X723229Y1374803D02*
X692520D01*
G01X712850Y231211D02*
Y223461D01*
G01Y683967D02*
Y676217D01*
G01Y1136723D02*
Y1128973D01*
G01X787402Y1626772D02*
Y1596063D01*
G01X866142Y-129134D02*
Y-98425D01*
G01X996650Y1150950D02*
Y1158700D01*
G01X1181102Y-94488D02*
Y-125197D01*
G01X1195670Y1374803D02*
X1226378D01*
G01X1220472Y1592126D02*
Y1622835D01*
G01X1315748Y0D02*
X1346457D01*
G01X1315650Y230611D02*
Y238361D01*
G01X1304950Y218511D02*
X1312700D01*
G01X1315650Y683367D02*
Y691117D01*
G01X1304950Y671267D02*
X1312700D01*
G01X1304950Y1124023D02*
X1312700D01*
G01X1315650Y1136123D02*
Y1143873D01*
G01X1439863Y230611D02*
Y238361D01*
G01X1429163Y218511D02*
X1436913D01*
G01X1439863Y683367D02*
Y691117D01*
G01X1429163Y671267D02*
X1436913D01*
G01X1429163Y1124023D02*
X1436913D01*
G01X1439863Y1136123D02*
Y1143873D01*
G01X1564075Y230611D02*
Y238361D01*
G01X1553375Y218511D02*
X1561125D01*
G01X1564075Y683367D02*
Y691117D01*
G01X1548375Y673267D02*
X1556125D01*
G01X1566923Y1128725D02*
Y1120975D01*
G01X1563977Y1374803D02*
X1524607D01*
G01X1593701Y0D02*
X1633071D01*
G01X1595650Y1096850D02*
X1587900D01*
G01X1688288Y230611D02*
Y238361D01*
G01X1677588Y218511D02*
X1685338D01*
G01X1688288Y683367D02*
Y691117D01*
G01X1677588Y671267D02*
X1685338D01*
G01X1677588Y1124023D02*
X1685338D01*
G01X1688288Y1136123D02*
Y1143873D01*
G01X1812500Y230611D02*
Y238361D01*
G01X1801800Y218511D02*
X1809550D01*
G01X1812500Y683367D02*
Y691117D01*
G01X1801800Y671267D02*
X1809550D01*
G01X1799800Y1124023D02*
X1807550D01*
G01X1812500Y1136123D02*
Y1143873D01*
G01X1839819Y222111D02*
Y229861D01*
G01Y674867D02*
Y682617D01*
G01X1840427Y1121714D02*
Y1129464D01*
G01X1880512Y0D02*
X1911221D01*
G01X1883519Y231211D02*
Y223461D01*
G01Y683967D02*
Y676217D01*
G01X1883629Y1121313D02*
Y1113563D01*
G01X1895276Y1374803D02*
X1864567D01*
G54D16*
G01X1179000Y267700D02*
Y261000D01*
G54D17*
G01X873223Y833303D02*
Y825703D01*
G01X1034623Y849703D02*
Y842103D01*
G54D18*
G01X333186Y559773D02*
G03I-10900J0D01*
G54D19*
G01X268670Y396140D02*
G03I-16350J0D01*
M02*
